G04 ================== begin FILE IDENTIFICATION RECORD ==================*
G04 Layout Name:  13948-1b.brd*
G04 Film Name:    BSILK*
G04 File Format:  Gerber RS274X*
G04 File Origin:  Cadence Allegro 16.5-S045*
G04 Origin Date:  Thu Nov 13 15:45:47 2014*
G04 *
G04 Layer:  VIA CLASS/FILMMASKBOTTOM*
G04 Layer:  REF DES/ASSEMBLY_BOTTOM*
G04 Layer:  PACKAGE GEOMETRY/SILKSCREEN_BOTTOM*
G04 Layer:  DRAWING FORMAT/LAYER_PCB_STORY*
G04 Layer:  DRAWING FORMAT/LAYER_SILK_B*
G04 Layer:  BOARD GEOMETRY/SILKSCREEN_BOTTOM*
G04 *
G04 Offset:    (0.00 0.00)*
G04 Mirror:    No*
G04 Mode:      Positive*
G04 Rotation:  0*
G04 FullContactRelief:  No*
G04 UndefLineWidth:     6.00*
G04 ================== end FILE IDENTIFICATION RECORD ====================*
%FSLAX35Y35*MOIN*%
%IR0*IPPOS*OFA0.00000B0.00000*MIA0B0*SFA1.00000B1.00000*%
%ADD10C,.026*%
%ADD11C,.02*%
%ADD12C,.012*%
%ADD13C,.013*%
%ADD14C,.006*%
%ADD15C,.008*%
G75*
%LPD*%
G75*
G36*
G01X471978Y835100D02*
X476978D01*
Y840100D01*
X471978Y835100D01*
G37*
G36*
G01X1015800Y45400D02*
X1017200Y44000D01*
X1014400D01*
X1015800Y45400D01*
G37*
G54D10*
X227000Y858000D03*
X217000Y858500D03*
X222000Y853500D03*
Y858500D03*
Y863500D03*
X663500Y452000D03*
X672500D03*
X663500Y456000D03*
Y460500D03*
X667500Y454000D03*
Y458500D03*
X672500Y456000D03*
Y460500D03*
X681000Y452000D03*
Y456000D03*
Y460500D03*
X676500Y454000D03*
Y458500D03*
X713716Y121284D03*
X721716Y112784D03*
Y116784D03*
X717716Y121284D03*
X721716D03*
Y129284D03*
Y125284D03*
X729716Y121284D03*
X725716D03*
X788600Y449300D03*
X784800D03*
X784900Y453000D03*
X788800D03*
X852000Y401500D03*
X842000D03*
X847000Y396500D03*
Y401500D03*
Y406500D03*
X1031500Y884500D03*
X1035216Y884468D03*
X1035000Y888500D03*
Y880500D03*
X1039468Y155284D03*
X1048968D03*
X1053500Y153000D03*
X1044000D03*
X1048968Y150784D03*
X1039500Y151000D03*
X1048968Y159284D03*
X1039500Y159500D03*
X1053500Y157500D03*
X1044000D03*
X1039000Y884500D03*
X1057968Y155284D03*
X1058000Y150500D03*
Y159500D03*
X1116468Y870284D03*
Y874284D03*
Y865784D03*
X1112468Y870284D03*
X1120468D03*
X1259968Y444284D03*
X1260000Y448500D03*
X1264500Y446500D03*
X1260000Y440000D03*
X1264500Y442000D03*
X1278500Y448500D03*
Y444000D03*
X1274000Y447000D03*
X1269468Y444284D03*
Y448284D03*
X1278500Y439500D03*
X1269468Y439784D03*
X1274000Y442000D03*
X1344000Y434500D03*
X1340200D03*
Y438300D03*
X1343900Y438500D03*
X1344617Y588712D03*
Y593412D03*
X1349317D03*
G54D11*
G01X-245081Y-422119D02*
G02I-12000J0D01*
G01X-250231D02*
G02I-6850J0D01*
G01X-241081D02*
X-273081D01*
G01X-257081Y-438119D02*
Y-406119D01*
G01X-241081Y-438119D02*
Y-518119D01*
G01D02*
X1034819D01*
G01X-241081Y-473619D02*
X1034819D01*
G01X-241081Y-438119D02*
X1034819D01*
G01X247319D02*
Y-518119D01*
G01X310953Y238352D02*
Y233352D01*
G01Y230352D02*
Y225352D01*
G01X328500Y71500D02*
X323500D01*
G01X366000Y13500D02*
X371000D01*
G01X384819Y-438119D02*
Y-518119D01*
G01X389429Y160000D02*
X394429D01*
G01X385829Y184200D02*
Y179200D01*
G01X385800Y209429D02*
Y204429D01*
G01X394000Y325500D02*
X399000D01*
G01X390555Y443500D02*
Y438500D01*
G01X403929Y201000D02*
X398929D01*
G01X421429D02*
X416429D01*
G01X468087Y305217D02*
Y300217D01*
G01X476255Y312100D02*
Y317100D01*
G01X482523Y424783D02*
X477523D01*
G01X487929Y131500D02*
X492929D01*
G01X490278Y865000D02*
Y870000D01*
G01X499819Y-438119D02*
Y-518119D01*
G01X495929Y131500D02*
X500929D01*
G01X502855Y335200D02*
Y340200D01*
G01X503555Y383000D02*
Y388000D01*
G01Y398000D02*
Y403000D01*
G01X644500Y351500D02*
X649500D01*
G01X667319Y-438119D02*
Y-518119D01*
G01X659962Y468464D02*
Y463464D01*
G01X722748Y110000D02*
Y105000D01*
G01X737248Y133500D02*
X742248D01*
G01X837319Y-438119D02*
Y-518119D01*
G01X1034819Y-438119D02*
Y-518119D01*
G01X1066819Y-422119D02*
X1034819D01*
G01X1050819Y-438119D02*
Y-406119D01*
G01X1062819Y-422119D02*
G02I-12000J0D01*
G01X1057669D02*
G02I-6850J0D01*
G01X1229677Y202000D02*
X1224677D01*
G54D12*
G01X69146Y988189D02*
X43949D01*
G01X108268Y266096D02*
Y240899D01*
G01X237876Y988189D02*
X212680D01*
G01X243898Y189684D02*
Y164487D01*
G01X318509Y0D02*
X301186D01*
G01X540498D02*
X515301D01*
G01X666394Y988189D02*
X641197D01*
G01X752245Y0D02*
X727048D01*
G01X884305Y988189D02*
X859108D01*
G01X921851Y912078D02*
Y886881D01*
G01X1009397Y0D02*
X984200D01*
G01X988781Y886881D02*
Y912078D01*
G01X1070591Y988189D02*
X1095788D01*
G01X1112146Y125146D02*
Y99949D01*
G01X1226319Y0D02*
X1210571D01*
G01X1206635Y97099D02*
Y122296D01*
G01X1354800Y988189D02*
X1379997D01*
G01X1396063Y0D02*
X1380315D01*
G54D13*
G01X317900Y295600D02*
X315050D01*
Y292900D01*
G01X1014800Y46200D02*
X1018800D01*
Y52000D01*
G54D14*
G01X-185516Y-508119D02*
Y-490619D01*
G01X-176346D02*
Y-508119D01*
G01Y-499369D02*
X-185516D01*
G01X-163431Y-508119D02*
X-165178Y-507827D01*
X-166706Y-506661D01*
X-168016Y-504911D01*
X-168890Y-502869D01*
X-169326Y-500536D01*
Y-498202D01*
X-168890Y-495869D01*
X-168016Y-493827D01*
X-166706Y-492078D01*
X-165178Y-490911D01*
X-163431Y-490619D01*
X-161685Y-490911D01*
X-160156Y-492078D01*
X-158846Y-493827D01*
X-157972Y-495869D01*
X-157536Y-498202D01*
Y-500536D01*
X-157972Y-502869D01*
X-158846Y-504911D01*
X-160156Y-506661D01*
X-161685Y-507827D01*
X-163431Y-508119D01*
G01X-150953D02*
Y-490619D01*
X-140909Y-508119D01*
Y-490619D01*
G01X-124064Y-508119D02*
X-132798D01*
Y-490619D01*
X-124064D01*
G01X-127558Y-499077D02*
X-132798D01*
G01X-110931Y-508119D02*
Y-500244D01*
X-115298Y-490619D01*
G01X-106564D02*
X-110931Y-500244D01*
G01X-74185Y-498786D02*
X-73311Y-497911D01*
X-72656Y-496453D01*
X-72219Y-494410D01*
X-72656Y-492661D01*
X-73529Y-491494D01*
X-75058Y-490619D01*
X-80953D01*
Y-508119D01*
X-73748D01*
X-72219Y-506953D01*
X-71346Y-505202D01*
X-70909Y-503161D01*
X-71346Y-501119D01*
X-72656Y-499369D01*
X-74185Y-498786D01*
X-80953D01*
G01X-63890Y-508119D02*
X-58431Y-490619D01*
X-52972Y-508119D01*
G01X-54938Y-501994D02*
X-61925D01*
G01X-45734Y-508119D02*
Y-490619D01*
X-41368D01*
X-39621Y-491494D01*
X-38311Y-492661D01*
X-37219Y-494410D01*
X-36346Y-496453D01*
X-36128Y-499369D01*
X-36346Y-502286D01*
X-37219Y-504328D01*
X-38311Y-506078D01*
X-39621Y-507244D01*
X-41368Y-508119D01*
X-45734D01*
G01X-22121Y-499369D02*
X-17754D01*
Y-504619D01*
X-19064Y-506369D01*
X-20593Y-507536D01*
X-22776Y-508119D01*
X-24959Y-507536D01*
X-26488Y-506369D01*
X-27798Y-504619D01*
X-28671Y-502577D01*
X-29108Y-500244D01*
Y-498202D01*
X-28671Y-496453D01*
X-27798Y-494410D01*
X-26488Y-492661D01*
X-25178Y-491494D01*
X-23431Y-490619D01*
X-21903D01*
X-20156Y-491202D01*
X-18846Y-492369D01*
G01X-1564Y-508119D02*
X-10298D01*
Y-490619D01*
X-1564D01*
G01X-5058Y-499077D02*
X-10298D01*
G01X7202Y-508119D02*
Y-490619D01*
X12661D01*
X14407Y-491494D01*
X15499Y-492661D01*
X15936Y-494994D01*
X15499Y-497328D01*
X14189Y-498786D01*
X12661Y-499661D01*
X7202D01*
G01X12661D02*
X15936Y-508119D01*
G01X48315Y-498786D02*
X49189Y-497911D01*
X49844Y-496453D01*
X50281Y-494410D01*
X49844Y-492661D01*
X48971Y-491494D01*
X47442Y-490619D01*
X41547D01*
Y-508119D01*
X48752D01*
X50281Y-506953D01*
X51154Y-505202D01*
X51591Y-503161D01*
X51154Y-501119D01*
X49844Y-499369D01*
X48315Y-498786D01*
X41547D01*
G01X58610Y-508119D02*
X64069Y-490619D01*
X69528Y-508119D01*
G01X67562Y-501994D02*
X60575D01*
G01X76984Y-505786D02*
X78731Y-507244D01*
X80696Y-508119D01*
X82442D01*
X84189Y-507244D01*
X85499Y-505786D01*
X86154Y-503744D01*
X85717Y-501703D01*
X84626Y-499952D01*
X82661Y-498786D01*
X80041Y-498202D01*
X78512Y-497036D01*
X77857Y-494994D01*
X78294Y-492952D01*
X79386Y-491494D01*
X80914Y-490619D01*
X82442D01*
X83971Y-491202D01*
X85281Y-492661D01*
G01X103436Y-508119D02*
X94702D01*
Y-490619D01*
X103436D01*
G01X99942Y-499077D02*
X94702D01*
G01X118315Y-498786D02*
X119189Y-497911D01*
X119844Y-496453D01*
X120281Y-494410D01*
X119844Y-492661D01*
X118971Y-491494D01*
X117442Y-490619D01*
X111547D01*
Y-508119D01*
X118752D01*
X120281Y-506953D01*
X121154Y-505202D01*
X121591Y-503161D01*
X121154Y-501119D01*
X119844Y-499369D01*
X118315Y-498786D01*
X111547D01*
G01X134069Y-508119D02*
X132322Y-507827D01*
X130794Y-506661D01*
X129484Y-504911D01*
X128610Y-502869D01*
X128174Y-500536D01*
Y-498202D01*
X128610Y-495869D01*
X129484Y-493827D01*
X130794Y-492078D01*
X132322Y-490911D01*
X134069Y-490619D01*
X135815Y-490911D01*
X137344Y-492078D01*
X138654Y-493827D01*
X139528Y-495869D01*
X139964Y-498202D01*
Y-500536D01*
X139528Y-502869D01*
X138654Y-504911D01*
X137344Y-506661D01*
X135815Y-507827D01*
X134069Y-508119D01*
G01X146110D02*
X151569Y-490619D01*
X157028Y-508119D01*
G01X155062Y-501994D02*
X148075D01*
G01X164702Y-508119D02*
Y-490619D01*
X170161D01*
X171907Y-491494D01*
X172999Y-492661D01*
X173436Y-494994D01*
X172999Y-497328D01*
X171689Y-498786D01*
X170161Y-499661D01*
X164702D01*
G01X170161D02*
X173436Y-508119D01*
G01X181766D02*
Y-490619D01*
X186132D01*
X187879Y-491494D01*
X189189Y-492661D01*
X190281Y-494410D01*
X191154Y-496453D01*
X191372Y-499369D01*
X191154Y-502286D01*
X190281Y-504328D01*
X189189Y-506078D01*
X187879Y-507244D01*
X186132Y-508119D01*
X181766D01*
G01X-37858Y-463119D02*
Y-445619D01*
X-32181Y-460202D01*
X-26504Y-445619D01*
Y-463119D01*
G01X-14681D02*
X-15991Y-462827D01*
X-17301Y-461661D01*
X-18175Y-459619D01*
X-18611Y-457286D01*
X-18175Y-454952D01*
X-17301Y-452911D01*
X-15991Y-451744D01*
X-14681Y-451453D01*
X-13371Y-451744D01*
X-12061Y-452911D01*
X-11188Y-454952D01*
X-10969Y-457286D01*
X-11188Y-459619D01*
X-12061Y-461661D01*
X-13371Y-462827D01*
X-14681Y-463119D01*
G01X6749Y-445619D02*
Y-463119D01*
G01Y-460495D02*
X5876Y-461953D01*
X4565Y-462827D01*
X3037Y-463119D01*
X1291Y-462536D01*
X-19Y-461078D01*
X-893Y-459328D01*
X-1111Y-457286D01*
X-893Y-455244D01*
X-19Y-453494D01*
X1291Y-452036D01*
X3037Y-451453D01*
X4565Y-451744D01*
X5657Y-452328D01*
X6749Y-453494D01*
G01X17044Y-455244D02*
X24031D01*
X23376Y-453202D01*
X22284Y-452036D01*
X20756Y-451453D01*
X19227Y-451744D01*
X17917Y-452619D01*
X17044Y-454661D01*
X16607Y-456411D01*
Y-458161D01*
X17044Y-459911D01*
X18136Y-461661D01*
X19446Y-462827D01*
X20974Y-463119D01*
X22502Y-462536D01*
X24031Y-460786D01*
G01X37819Y-463119D02*
Y-445619D01*
G01X281019Y-508119D02*
Y-490619D01*
X278399Y-494119D01*
G01Y-508119D02*
X283639D01*
G01X293716Y-504619D02*
X295025Y-506661D01*
X296772Y-507827D01*
X298737Y-508119D01*
X300484Y-507827D01*
X302231Y-506369D01*
X303322Y-504619D01*
X303541Y-502869D01*
X303104Y-500828D01*
X301576Y-499369D01*
X300047Y-498786D01*
X298082D01*
G01X300047D02*
X301357Y-497911D01*
X302449Y-496453D01*
X302886Y-494703D01*
X302449Y-492952D01*
X301357Y-491494D01*
X299392Y-490619D01*
X297427Y-490911D01*
X295462Y-492078D01*
G01X312307Y-506078D02*
X313836Y-507536D01*
X315582Y-508119D01*
X317329Y-507536D01*
X318857Y-505786D01*
X319949Y-503161D01*
X320386Y-500536D01*
Y-497328D01*
X319949Y-494703D01*
X318857Y-492369D01*
X317547Y-491202D01*
X316019Y-490619D01*
X314272Y-491202D01*
X312962Y-492369D01*
X312089Y-494119D01*
X311652Y-496453D01*
X312089Y-498494D01*
X313181Y-500536D01*
X314491Y-501703D01*
X316019Y-501994D01*
X317765Y-501411D01*
X319076Y-499952D01*
X320386Y-497328D01*
G01X336139Y-508119D02*
Y-490619D01*
X328060Y-503161D01*
X338978D01*
G01X351019Y-508119D02*
X352547Y-507827D01*
X354294Y-506953D01*
X355386Y-505495D01*
X355822Y-503452D01*
X355386Y-501411D01*
X354076Y-499661D01*
X352111Y-498786D01*
X349927D01*
X348617Y-498202D01*
X347525Y-496744D01*
X347089Y-494703D01*
X347744Y-492661D01*
X349272Y-491202D01*
X351019Y-490619D01*
X352765Y-491202D01*
X354294Y-492661D01*
X354949Y-494703D01*
X354512Y-496744D01*
X353421Y-498202D01*
X352111Y-498786D01*
X349927D01*
X347962Y-499661D01*
X346652Y-501411D01*
X346216Y-503452D01*
X346652Y-505495D01*
X347744Y-506953D01*
X349491Y-507827D01*
X351019Y-508119D01*
G01X267902Y-463119D02*
Y-445619D01*
X273142D01*
X274889Y-446494D01*
X276199Y-448536D01*
X276636Y-450869D01*
X276199Y-453202D01*
X275107Y-454952D01*
X273142Y-455828D01*
X267902D01*
G01X294572Y-447078D02*
X293262Y-446202D01*
X291734Y-445619D01*
X289987D01*
X288022Y-446494D01*
X286494Y-447952D01*
X285402Y-449703D01*
X284529Y-452619D01*
X284310Y-455244D01*
X284747Y-457869D01*
X285402Y-459619D01*
X286712Y-461369D01*
X288241Y-462536D01*
X289769Y-463119D01*
X291297D01*
X292826Y-462536D01*
X294136Y-461661D01*
X295228Y-460495D01*
G01X309015Y-453786D02*
X309889Y-452911D01*
X310544Y-451453D01*
X310981Y-449410D01*
X310544Y-447661D01*
X309671Y-446494D01*
X308142Y-445619D01*
X302247D01*
Y-463119D01*
X309452D01*
X310981Y-461953D01*
X311854Y-460202D01*
X312291Y-458161D01*
X311854Y-456119D01*
X310544Y-454369D01*
X309015Y-453786D01*
X302247D01*
G01X318219Y-468952D02*
X331319D01*
G01X337247Y-463119D02*
Y-445619D01*
X347291Y-463119D01*
Y-445619D01*
G01X359769Y-463119D02*
X358022Y-462827D01*
X356494Y-461661D01*
X355184Y-459911D01*
X354310Y-457869D01*
X353874Y-455536D01*
Y-453202D01*
X354310Y-450869D01*
X355184Y-448827D01*
X356494Y-447078D01*
X358022Y-445911D01*
X359769Y-445619D01*
X361515Y-445911D01*
X363044Y-447078D01*
X364354Y-448827D01*
X365228Y-450869D01*
X365664Y-453202D01*
Y-455536D01*
X365228Y-457869D01*
X364354Y-459911D01*
X363044Y-461661D01*
X361515Y-462827D01*
X359769Y-463119D01*
G01X410610Y-445619D02*
X416069Y-463119D01*
X421528Y-445619D01*
G01X437936Y-463119D02*
X429202D01*
Y-445619D01*
X437936D01*
G01X434442Y-454077D02*
X429202D01*
G01X446702Y-463119D02*
Y-445619D01*
X452161D01*
X453907Y-446494D01*
X454999Y-447661D01*
X455436Y-449994D01*
X454999Y-452328D01*
X453689Y-453786D01*
X452161Y-454661D01*
X446702D01*
G01X452161D02*
X455436Y-463119D01*
G01X468569Y-463702D02*
X468132Y-463411D01*
Y-462827D01*
X468569Y-462536D01*
X469006Y-462827D01*
Y-463411D01*
X468569Y-463702D01*
G01X433569Y-508119D02*
Y-490619D01*
X430949Y-494119D01*
G01Y-508119D02*
X436189D01*
G01X452815Y-498786D02*
X453689Y-497911D01*
X454344Y-496453D01*
X454781Y-494410D01*
X454344Y-492661D01*
X453471Y-491494D01*
X451942Y-490619D01*
X446047D01*
Y-508119D01*
X453252D01*
X454781Y-506953D01*
X455654Y-505202D01*
X456091Y-503161D01*
X455654Y-501119D01*
X454344Y-499369D01*
X452815Y-498786D01*
X446047D01*
G01X616773D02*
X615899Y-497911D01*
X615244Y-496453D01*
X614807Y-494410D01*
X615244Y-492661D01*
X616117Y-491494D01*
X617646Y-490619D01*
X623541D01*
Y-508119D01*
X616336D01*
X614807Y-506953D01*
X613934Y-505202D01*
X613497Y-503161D01*
X613934Y-501119D01*
X615244Y-499369D01*
X616773Y-498786D01*
X623541D01*
G01X605604Y-505786D02*
X603857Y-507244D01*
X601892Y-508119D01*
X600146D01*
X598399Y-507244D01*
X597089Y-505786D01*
X596434Y-503744D01*
X596871Y-501703D01*
X597962Y-499952D01*
X599927Y-498786D01*
X602547Y-498202D01*
X604076Y-497036D01*
X604731Y-494994D01*
X604294Y-492952D01*
X603202Y-491494D01*
X601674Y-490619D01*
X600146D01*
X598617Y-491202D01*
X597307Y-492661D01*
G01X586139Y-490619D02*
X580899D01*
G01X583519D02*
Y-508119D01*
G01X586139D02*
X580899D01*
G01X570386Y-490619D02*
Y-508119D01*
X561652D01*
G01X553322D02*
Y-490619D01*
G01X545026D02*
X553322Y-501411D01*
G01X543716Y-508119D02*
X549611Y-496453D01*
G01X544152Y-445619D02*
Y-463119D01*
X552886D01*
G01X569949D02*
Y-451453D01*
G01Y-453494D02*
X569076Y-452328D01*
X567765Y-451744D01*
X566237Y-451453D01*
X564709Y-452036D01*
X563399Y-453202D01*
X562525Y-454952D01*
X562089Y-457286D01*
X562525Y-459619D01*
X563399Y-461369D01*
X564709Y-462536D01*
X566237Y-463119D01*
X567765Y-462827D01*
X569076Y-461953D01*
X569949Y-460786D01*
G01X578934Y-468369D02*
X580244Y-468952D01*
X581991Y-468369D01*
X583082Y-467203D01*
X583956Y-465744D01*
X585265Y-461078D01*
X588104Y-451453D01*
G01X581117D02*
X585265Y-461078D01*
G01X597744Y-455244D02*
X604731D01*
X604076Y-453202D01*
X602984Y-452036D01*
X601456Y-451453D01*
X599927Y-451744D01*
X598617Y-452619D01*
X597744Y-454661D01*
X597307Y-456411D01*
Y-458161D01*
X597744Y-459911D01*
X598836Y-461661D01*
X600146Y-462827D01*
X601674Y-463119D01*
X603202Y-462536D01*
X604731Y-460786D01*
G01X615462Y-463119D02*
Y-451453D01*
G01Y-453786D02*
X616554Y-452619D01*
X617646Y-451744D01*
X619174Y-451453D01*
X620265Y-451744D01*
X621576Y-452619D01*
G01X686702Y-490619D02*
Y-508119D01*
X695436D01*
G01X703984Y-513369D02*
X705294Y-513952D01*
X707041Y-513369D01*
X708132Y-512203D01*
X709006Y-510744D01*
X710315Y-506078D01*
X713154Y-496453D01*
G01X706167D02*
X710315Y-506078D01*
G01X722357Y-508119D02*
Y-496453D01*
G01Y-499369D02*
X723231Y-497911D01*
X724541Y-496744D01*
X726287Y-496453D01*
X727815Y-496744D01*
X729126Y-497911D01*
X729781Y-499952D01*
Y-508119D01*
G01X739857D02*
Y-496453D01*
G01Y-499369D02*
X740731Y-497911D01*
X742041Y-496744D01*
X743787Y-496453D01*
X745315Y-496744D01*
X746626Y-497911D01*
X747281Y-499952D01*
Y-508119D01*
G01X774202Y-490619D02*
Y-508119D01*
X782936D01*
G01X796069Y-496453D02*
Y-508119D01*
G01Y-491786D02*
X795632Y-491494D01*
Y-490911D01*
X796069Y-490619D01*
X796506Y-490911D01*
Y-491494D01*
X796069Y-491786D01*
G01X809857Y-496453D02*
Y-504619D01*
X810731Y-506661D01*
X812041Y-507827D01*
X813569Y-508119D01*
X815097Y-507827D01*
X816407Y-506661D01*
X817281Y-504619D01*
G01Y-508119D02*
Y-496453D01*
G01X686266Y-463119D02*
Y-445619D01*
X690632D01*
X692379Y-446494D01*
X693689Y-447661D01*
X694781Y-449410D01*
X695654Y-451453D01*
X695872Y-454369D01*
X695654Y-457286D01*
X694781Y-459328D01*
X693689Y-461078D01*
X692379Y-462244D01*
X690632Y-463119D01*
X686266D01*
G01X705294Y-455244D02*
X712281D01*
X711626Y-453202D01*
X710534Y-452036D01*
X709006Y-451453D01*
X707477Y-451744D01*
X706167Y-452619D01*
X705294Y-454661D01*
X704857Y-456411D01*
Y-458161D01*
X705294Y-459911D01*
X706386Y-461661D01*
X707696Y-462827D01*
X709224Y-463119D01*
X710752Y-462536D01*
X712281Y-460786D01*
G01X722794Y-461078D02*
X723886Y-462244D01*
X725414Y-463119D01*
X726724D01*
X728034Y-462536D01*
X728907Y-461661D01*
X729344Y-460495D01*
X729126Y-458744D01*
X728252Y-457869D01*
X724322Y-456119D01*
X723449Y-454077D01*
X723886Y-452619D01*
X724759Y-451744D01*
X726069Y-451453D01*
X727379Y-451744D01*
X728689Y-452619D01*
G01X743569Y-451453D02*
Y-463119D01*
G01Y-446786D02*
X743132Y-446494D01*
Y-445911D01*
X743569Y-445619D01*
X744006Y-445911D01*
Y-446494D01*
X743569Y-446786D01*
G01X758012Y-467494D02*
X759541Y-468661D01*
X761287Y-468952D01*
X762815Y-468661D01*
X764126Y-467203D01*
X764999Y-465161D01*
Y-451453D01*
G01Y-453786D02*
X764126Y-452619D01*
X762815Y-451744D01*
X761287Y-451453D01*
X759541Y-452036D01*
X758449Y-453202D01*
X757575Y-455244D01*
X757139Y-457286D01*
X757357Y-459036D01*
X758231Y-461078D01*
X759541Y-462536D01*
X761287Y-463119D01*
X762597Y-462827D01*
X764126Y-461661D01*
X764999Y-460495D01*
G01X774857Y-463119D02*
Y-451453D01*
G01Y-454369D02*
X775731Y-452911D01*
X777041Y-451744D01*
X778787Y-451453D01*
X780315Y-451744D01*
X781626Y-452911D01*
X782281Y-454952D01*
Y-463119D01*
G01X792794Y-455244D02*
X799781D01*
X799126Y-453202D01*
X798034Y-452036D01*
X796506Y-451453D01*
X794977Y-451744D01*
X793667Y-452619D01*
X792794Y-454661D01*
X792357Y-456411D01*
Y-458161D01*
X792794Y-459911D01*
X793886Y-461661D01*
X795196Y-462827D01*
X796724Y-463119D01*
X798252Y-462536D01*
X799781Y-460786D01*
G01X810512Y-463119D02*
Y-451453D01*
G01Y-453786D02*
X811604Y-452619D01*
X812696Y-451744D01*
X814224Y-451453D01*
X815315Y-451744D01*
X816626Y-452619D01*
G01X857269Y-508119D02*
Y-490619D01*
X854649Y-494119D01*
G01Y-508119D02*
X859889D01*
G01X874769D02*
Y-490619D01*
X872149Y-494119D01*
G01Y-508119D02*
X877389D01*
G01X888339Y-508702D02*
X896199Y-490619D01*
G01X909769Y-508119D02*
Y-490619D01*
X907149Y-494119D01*
G01Y-508119D02*
X912389D01*
G01X922466Y-504619D02*
X923775Y-506661D01*
X925522Y-507827D01*
X927487Y-508119D01*
X929234Y-507827D01*
X930981Y-506369D01*
X932072Y-504619D01*
X932291Y-502869D01*
X931854Y-500828D01*
X930326Y-499369D01*
X928797Y-498786D01*
X926832D01*
G01X928797D02*
X930107Y-497911D01*
X931199Y-496453D01*
X931636Y-494703D01*
X931199Y-492952D01*
X930107Y-491494D01*
X928142Y-490619D01*
X926177Y-490911D01*
X924212Y-492078D01*
G01X940839Y-508702D02*
X948699Y-490619D01*
G01X958121Y-493536D02*
X959431Y-491786D01*
X960959Y-490911D01*
X962706Y-490619D01*
X964889Y-491202D01*
X966417Y-492661D01*
X966854Y-494410D01*
X966636Y-496161D01*
X965762Y-497619D01*
X961396Y-500536D01*
X959431Y-502577D01*
X958121Y-505495D01*
X957684Y-508119D01*
X966854D01*
G01X979769Y-490619D02*
X978022Y-491202D01*
X976712Y-492661D01*
X975839Y-494410D01*
X975184Y-496744D01*
X974966Y-499369D01*
X975184Y-501994D01*
X975839Y-504328D01*
X976712Y-506078D01*
X978022Y-507536D01*
X979769Y-508119D01*
X981515Y-507536D01*
X982826Y-506078D01*
X983699Y-504328D01*
X984354Y-501994D01*
X984572Y-499369D01*
X984354Y-496744D01*
X983699Y-494410D01*
X982826Y-492661D01*
X981515Y-491202D01*
X979769Y-490619D01*
G01X997269Y-508119D02*
Y-490619D01*
X994649Y-494119D01*
G01Y-508119D02*
X999889D01*
G01X1017389D02*
Y-490619D01*
X1009310Y-503161D01*
X1020228D01*
G01X904966Y-463119D02*
Y-445619D01*
X909332D01*
X911079Y-446494D01*
X912389Y-447661D01*
X913481Y-449410D01*
X914354Y-451453D01*
X914572Y-454369D01*
X914354Y-457286D01*
X913481Y-459328D01*
X912389Y-461078D01*
X911079Y-462244D01*
X909332Y-463119D01*
X904966D01*
G01X931199D02*
Y-451453D01*
G01Y-453494D02*
X930326Y-452328D01*
X929015Y-451744D01*
X927487Y-451453D01*
X925959Y-452036D01*
X924649Y-453202D01*
X923775Y-454952D01*
X923339Y-457286D01*
X923775Y-459619D01*
X924649Y-461369D01*
X925959Y-462536D01*
X927487Y-463119D01*
X929015Y-462827D01*
X930326Y-461953D01*
X931199Y-460786D01*
G01X944769Y-445619D02*
Y-463119D01*
G01X941712Y-451453D02*
X947826D01*
G01X958994Y-455244D02*
X965981D01*
X965326Y-453202D01*
X964234Y-452036D01*
X962706Y-451453D01*
X961177Y-451744D01*
X959867Y-452619D01*
X958994Y-454661D01*
X958557Y-456411D01*
Y-458161D01*
X958994Y-459911D01*
X960086Y-461661D01*
X961396Y-462827D01*
X962924Y-463119D01*
X964452Y-462536D01*
X965981Y-460786D01*
G01X41075Y871833D02*
X40742Y871625D01*
X40367Y871500D01*
X40033D01*
X39700Y871625D01*
X39450Y871833D01*
X39325Y872125D01*
X39408Y872417D01*
X39617Y872667D01*
X39992Y872833D01*
X40492Y872917D01*
X40783Y873083D01*
X40908Y873375D01*
X40825Y873667D01*
X40617Y873875D01*
X40325Y874000D01*
X40033D01*
X39742Y873917D01*
X39492Y873708D01*
G01X37933Y871500D02*
Y874000D01*
X36892D01*
X36558Y873875D01*
X36350Y873708D01*
X36267Y873375D01*
X36350Y873042D01*
X36600Y872833D01*
X36892Y872708D01*
X37933D01*
G01X36892D02*
X36267Y871500D01*
G01X34917Y872000D02*
X34667Y871708D01*
X34333Y871542D01*
X33958Y871500D01*
X33625Y871542D01*
X33292Y871750D01*
X33083Y872000D01*
X33042Y872250D01*
X33125Y872542D01*
X33417Y872750D01*
X33708Y872833D01*
X34083D01*
G01X33708D02*
X33458Y872958D01*
X33250Y873167D01*
X33167Y873417D01*
X33250Y873667D01*
X33458Y873875D01*
X33833Y874000D01*
X34208Y873958D01*
X34583Y873792D01*
G01X30900Y871500D02*
Y874000D01*
X31400Y873500D01*
G01Y871500D02*
X30400D01*
G01X28717Y871875D02*
X28467Y871667D01*
X28175Y871542D01*
X27800Y871500D01*
X27425Y871583D01*
X27133Y871750D01*
X26925Y872042D01*
X26883Y872375D01*
X26967Y872708D01*
X27175Y872917D01*
X27467Y873083D01*
X27758Y873125D01*
X28050Y873083D01*
X28425Y872917D01*
X28300Y874000D01*
X27175D01*
G01X41075Y867833D02*
X40742Y867625D01*
X40367Y867500D01*
X40033D01*
X39700Y867625D01*
X39450Y867833D01*
X39325Y868125D01*
X39408Y868417D01*
X39617Y868667D01*
X39992Y868833D01*
X40492Y868917D01*
X40783Y869083D01*
X40908Y869375D01*
X40825Y869667D01*
X40617Y869875D01*
X40325Y870000D01*
X40033D01*
X39742Y869917D01*
X39492Y869708D01*
G01X37933Y867500D02*
Y870000D01*
X36892D01*
X36558Y869875D01*
X36350Y869708D01*
X36267Y869375D01*
X36350Y869042D01*
X36600Y868833D01*
X36892Y868708D01*
X37933D01*
G01X36892D02*
X36267Y867500D01*
G01X34917Y868000D02*
X34667Y867708D01*
X34333Y867542D01*
X33958Y867500D01*
X33625Y867542D01*
X33292Y867750D01*
X33083Y868000D01*
X33042Y868250D01*
X33125Y868542D01*
X33417Y868750D01*
X33708Y868833D01*
X34083D01*
G01X33708D02*
X33458Y868958D01*
X33250Y869167D01*
X33167Y869417D01*
X33250Y869667D01*
X33458Y869875D01*
X33833Y870000D01*
X34208Y869958D01*
X34583Y869792D01*
G01X30900Y867500D02*
Y870000D01*
X31400Y869500D01*
G01Y867500D02*
X30400D01*
G01X28592Y868542D02*
X28300Y868833D01*
X28050Y869000D01*
X27717Y869083D01*
X27425Y869000D01*
X27217Y868833D01*
X27050Y868583D01*
X27008Y868292D01*
X27050Y868042D01*
X27217Y867792D01*
X27467Y867583D01*
X27758Y867500D01*
X28092Y867583D01*
X28383Y867833D01*
X28550Y868208D01*
X28592Y868625D01*
X28508Y869167D01*
X28383Y869458D01*
X28175Y869750D01*
X27883Y869958D01*
X27592Y870000D01*
X27300Y869917D01*
X27092Y869708D01*
G01X49575Y403243D02*
X49700Y402993D01*
X49783Y402701D01*
Y402368D01*
X49658Y401993D01*
X49450Y401701D01*
X49200Y401493D01*
X48783Y401326D01*
X48408Y401284D01*
X48033Y401368D01*
X47783Y401493D01*
X47533Y401743D01*
X47366Y402034D01*
X47283Y402326D01*
Y402618D01*
X47366Y402909D01*
X47491Y403159D01*
X47658Y403368D01*
G01X47283Y405426D02*
X49783D01*
X49283Y404926D01*
G01X47283D02*
Y405926D01*
G01X47783Y407609D02*
X47491Y407859D01*
X47325Y408193D01*
X47283Y408568D01*
X47325Y408901D01*
X47533Y409234D01*
X47783Y409443D01*
X48033Y409484D01*
X48325Y409401D01*
X48533Y409109D01*
X48616Y408818D01*
Y408443D01*
G01Y408818D02*
X48741Y409068D01*
X48950Y409276D01*
X49200Y409359D01*
X49450Y409276D01*
X49658Y409068D01*
X49783Y408693D01*
X49741Y408318D01*
X49575Y407943D01*
G01X49783Y411626D02*
X49700Y411293D01*
X49491Y411043D01*
X49241Y410876D01*
X48908Y410751D01*
X48533Y410709D01*
X48158Y410751D01*
X47825Y410876D01*
X47575Y411043D01*
X47366Y411293D01*
X47283Y411626D01*
X47366Y411959D01*
X47575Y412209D01*
X47825Y412376D01*
X48158Y412501D01*
X48533Y412543D01*
X48908Y412501D01*
X49241Y412376D01*
X49491Y412209D01*
X49700Y411959D01*
X49783Y411626D01*
G01X45575Y403243D02*
X45700Y402993D01*
X45783Y402701D01*
Y402368D01*
X45658Y401993D01*
X45450Y401701D01*
X45200Y401493D01*
X44783Y401326D01*
X44408Y401284D01*
X44033Y401368D01*
X43783Y401493D01*
X43533Y401743D01*
X43366Y402034D01*
X43283Y402326D01*
Y402618D01*
X43366Y402909D01*
X43491Y403159D01*
X43658Y403368D01*
G01X43283Y405426D02*
X45783D01*
X45283Y404926D01*
G01X43283D02*
Y405926D01*
G01X45366Y407734D02*
X45616Y407984D01*
X45741Y408276D01*
X45783Y408609D01*
X45700Y409026D01*
X45491Y409318D01*
X45241Y409401D01*
X44991Y409359D01*
X44783Y409193D01*
X44366Y408359D01*
X44075Y407984D01*
X43658Y407734D01*
X43283Y407651D01*
Y409401D01*
G01X43575Y410918D02*
X43366Y411209D01*
X43283Y411543D01*
X43366Y411876D01*
X43616Y412168D01*
X43991Y412376D01*
X44366Y412459D01*
X44825D01*
X45200Y412376D01*
X45533Y412168D01*
X45700Y411918D01*
X45783Y411626D01*
X45700Y411293D01*
X45533Y411043D01*
X45283Y410876D01*
X44950Y410793D01*
X44658Y410876D01*
X44366Y411084D01*
X44200Y411334D01*
X44158Y411626D01*
X44241Y411959D01*
X44450Y412209D01*
X44825Y412459D01*
G01X67429Y673553D02*
X67096Y673345D01*
X66721Y673220D01*
X66387D01*
X66054Y673345D01*
X65804Y673553D01*
X65679Y673845D01*
X65762Y674137D01*
X65971Y674387D01*
X66346Y674553D01*
X66846Y674637D01*
X67137Y674803D01*
X67262Y675095D01*
X67179Y675387D01*
X66971Y675595D01*
X66679Y675720D01*
X66387D01*
X66096Y675637D01*
X65846Y675428D01*
G01X62537Y675512D02*
X62787Y675637D01*
X63079Y675720D01*
X63412D01*
X63787Y675595D01*
X64079Y675387D01*
X64287Y675137D01*
X64454Y674720D01*
X64496Y674345D01*
X64412Y673970D01*
X64287Y673720D01*
X64037Y673470D01*
X63746Y673303D01*
X63454Y673220D01*
X63162D01*
X62871Y673303D01*
X62621Y673428D01*
X62412Y673595D01*
G01X60354Y673220D02*
Y675720D01*
X60854Y675220D01*
G01Y673220D02*
X59854D01*
G01X57254D02*
Y675720D01*
X57754Y675220D01*
G01Y673220D02*
X56754D01*
G01X54154D02*
Y675720D01*
X54654Y675220D01*
G01Y673220D02*
X53654D01*
G01X51054D02*
Y675720D01*
X51554Y675220D01*
G01Y673220D02*
X50554D01*
G01X43300Y870500D02*
Y874500D01*
X50700D01*
G01X43300Y866500D02*
Y870500D01*
X50700D01*
G01X42520Y894705D02*
X45020D01*
Y895746D01*
X44895Y896080D01*
X44728Y896288D01*
X44395Y896371D01*
X44062Y896288D01*
X43853Y896038D01*
X43728Y895746D01*
Y894705D01*
G01Y895746D02*
X42520Y896371D01*
G01X42895Y897721D02*
X42687Y897971D01*
X42562Y898263D01*
X42520Y898638D01*
X42603Y899013D01*
X42770Y899305D01*
X43062Y899513D01*
X43395Y899555D01*
X43728Y899471D01*
X43937Y899263D01*
X44103Y898971D01*
X44145Y898680D01*
X44103Y898388D01*
X43937Y898013D01*
X45020Y898138D01*
Y899263D01*
G01X42520Y901738D02*
X45020D01*
X44520Y901238D01*
G01X42520D02*
Y902238D01*
G01X44603Y904046D02*
X44853Y904296D01*
X44978Y904588D01*
X45020Y904921D01*
X44937Y905338D01*
X44728Y905630D01*
X44478Y905713D01*
X44228Y905671D01*
X44020Y905505D01*
X43603Y904671D01*
X43312Y904296D01*
X42895Y904046D01*
X42520Y903963D01*
Y905713D01*
G01X41520Y916388D02*
X45520D01*
Y908988D01*
G01X47020Y894705D02*
X49520D01*
Y895746D01*
X49395Y896080D01*
X49228Y896288D01*
X48895Y896371D01*
X48562Y896288D01*
X48353Y896038D01*
X48228Y895746D01*
Y894705D01*
G01Y895746D02*
X47020Y896371D01*
G01X47395Y897721D02*
X47187Y897971D01*
X47062Y898263D01*
X47020Y898638D01*
X47103Y899013D01*
X47270Y899305D01*
X47562Y899513D01*
X47895Y899555D01*
X48228Y899471D01*
X48437Y899263D01*
X48603Y898971D01*
X48645Y898680D01*
X48603Y898388D01*
X48437Y898013D01*
X49520Y898138D01*
Y899263D01*
G01X47020Y901738D02*
X49520D01*
X49020Y901238D01*
G01X47020D02*
Y902238D01*
G01X47520Y903921D02*
X47228Y904171D01*
X47062Y904505D01*
X47020Y904880D01*
X47062Y905213D01*
X47270Y905546D01*
X47520Y905755D01*
X47770Y905796D01*
X48062Y905713D01*
X48270Y905421D01*
X48353Y905130D01*
Y904755D01*
G01Y905130D02*
X48478Y905380D01*
X48687Y905588D01*
X48937Y905671D01*
X49187Y905588D01*
X49395Y905380D01*
X49520Y905005D01*
X49478Y904630D01*
X49312Y904255D01*
G01X46020Y916388D02*
X50020D01*
Y908988D01*
G01X51520Y894705D02*
X54020D01*
Y895746D01*
X53895Y896080D01*
X53728Y896288D01*
X53395Y896371D01*
X53062Y896288D01*
X52853Y896038D01*
X52728Y895746D01*
Y894705D01*
G01Y895746D02*
X51520Y896371D01*
G01X51895Y897721D02*
X51687Y897971D01*
X51562Y898263D01*
X51520Y898638D01*
X51603Y899013D01*
X51770Y899305D01*
X52062Y899513D01*
X52395Y899555D01*
X52728Y899471D01*
X52937Y899263D01*
X53103Y898971D01*
X53145Y898680D01*
X53103Y898388D01*
X52937Y898013D01*
X54020Y898138D01*
Y899263D01*
G01X51520Y901738D02*
X54020D01*
X53520Y901238D01*
G01X51520D02*
Y902238D01*
G01Y905338D02*
X54020D01*
X52228Y903796D01*
Y905880D01*
G01X50520Y916388D02*
X54520D01*
Y908988D01*
G01X64575Y403243D02*
X64700Y402993D01*
X64783Y402701D01*
Y402368D01*
X64658Y401993D01*
X64450Y401701D01*
X64200Y401493D01*
X63783Y401326D01*
X63408Y401284D01*
X63033Y401368D01*
X62783Y401493D01*
X62533Y401743D01*
X62366Y402034D01*
X62283Y402326D01*
Y402618D01*
X62366Y402909D01*
X62491Y403159D01*
X62658Y403368D01*
G01X62283Y405426D02*
X64783D01*
X64283Y404926D01*
G01X62283D02*
Y405926D01*
G01X62783Y407609D02*
X62491Y407859D01*
X62325Y408193D01*
X62283Y408568D01*
X62325Y408901D01*
X62533Y409234D01*
X62783Y409443D01*
X63033Y409484D01*
X63325Y409401D01*
X63533Y409109D01*
X63616Y408818D01*
Y408443D01*
G01Y408818D02*
X63741Y409068D01*
X63950Y409276D01*
X64200Y409359D01*
X64450Y409276D01*
X64658Y409068D01*
X64783Y408693D01*
X64741Y408318D01*
X64575Y407943D01*
G01X62283Y412126D02*
X64783D01*
X62991Y410584D01*
Y412668D01*
G01X59075Y403243D02*
X59200Y402993D01*
X59283Y402701D01*
Y402368D01*
X59158Y401993D01*
X58950Y401701D01*
X58700Y401493D01*
X58283Y401326D01*
X57908Y401284D01*
X57533Y401368D01*
X57283Y401493D01*
X57033Y401743D01*
X56866Y402034D01*
X56783Y402326D01*
Y402618D01*
X56866Y402909D01*
X56991Y403159D01*
X57158Y403368D01*
G01X56783Y405426D02*
X59283D01*
X58783Y404926D01*
G01X56783D02*
Y405926D01*
G01X57283Y407609D02*
X56991Y407859D01*
X56825Y408193D01*
X56783Y408568D01*
X56825Y408901D01*
X57033Y409234D01*
X57283Y409443D01*
X57533Y409484D01*
X57825Y409401D01*
X58033Y409109D01*
X58116Y408818D01*
Y408443D01*
G01Y408818D02*
X58241Y409068D01*
X58450Y409276D01*
X58700Y409359D01*
X58950Y409276D01*
X59158Y409068D01*
X59283Y408693D01*
X59241Y408318D01*
X59075Y407943D01*
G01X57283Y410709D02*
X56991Y410959D01*
X56825Y411293D01*
X56783Y411668D01*
X56825Y412001D01*
X57033Y412334D01*
X57283Y412543D01*
X57533Y412584D01*
X57825Y412501D01*
X58033Y412209D01*
X58116Y411918D01*
Y411543D01*
G01Y411918D02*
X58241Y412168D01*
X58450Y412376D01*
X58700Y412459D01*
X58950Y412376D01*
X59158Y412168D01*
X59283Y411793D01*
X59241Y411418D01*
X59075Y411043D01*
G01X68575Y403243D02*
X68700Y402993D01*
X68783Y402701D01*
Y402368D01*
X68658Y401993D01*
X68450Y401701D01*
X68200Y401493D01*
X67783Y401326D01*
X67408Y401284D01*
X67033Y401368D01*
X66783Y401493D01*
X66533Y401743D01*
X66366Y402034D01*
X66283Y402326D01*
Y402618D01*
X66366Y402909D01*
X66491Y403159D01*
X66658Y403368D01*
G01X66283Y405426D02*
X68783D01*
X68283Y404926D01*
G01X66283D02*
Y405926D01*
G01X66783Y407609D02*
X66491Y407859D01*
X66325Y408193D01*
X66283Y408568D01*
X66325Y408901D01*
X66533Y409234D01*
X66783Y409443D01*
X67033Y409484D01*
X67325Y409401D01*
X67533Y409109D01*
X67616Y408818D01*
Y408443D01*
G01Y408818D02*
X67741Y409068D01*
X67950Y409276D01*
X68200Y409359D01*
X68450Y409276D01*
X68658Y409068D01*
X68783Y408693D01*
X68741Y408318D01*
X68575Y407943D01*
G01X68366Y410834D02*
X68616Y411084D01*
X68741Y411376D01*
X68783Y411709D01*
X68700Y412126D01*
X68491Y412418D01*
X68241Y412501D01*
X67991Y412459D01*
X67783Y412293D01*
X67366Y411459D01*
X67075Y411084D01*
X66658Y410834D01*
X66283Y410751D01*
Y412501D01*
G01X55075Y403243D02*
X55200Y402993D01*
X55283Y402701D01*
Y402368D01*
X55158Y401993D01*
X54950Y401701D01*
X54700Y401493D01*
X54283Y401326D01*
X53908Y401284D01*
X53533Y401368D01*
X53283Y401493D01*
X53033Y401743D01*
X52866Y402034D01*
X52783Y402326D01*
Y402618D01*
X52866Y402909D01*
X52991Y403159D01*
X53158Y403368D01*
G01X52783Y405426D02*
X55283D01*
X54783Y404926D01*
G01X52783D02*
Y405926D01*
G01X53283Y407609D02*
X52991Y407859D01*
X52825Y408193D01*
X52783Y408568D01*
X52825Y408901D01*
X53033Y409234D01*
X53283Y409443D01*
X53533Y409484D01*
X53825Y409401D01*
X54033Y409109D01*
X54116Y408818D01*
Y408443D01*
G01Y408818D02*
X54241Y409068D01*
X54450Y409276D01*
X54700Y409359D01*
X54950Y409276D01*
X55158Y409068D01*
X55283Y408693D01*
X55241Y408318D01*
X55075Y407943D01*
G01X52783Y411626D02*
X55283D01*
X54783Y411126D01*
G01X52783D02*
Y412126D01*
G01X70461Y697836D02*
X70128Y697628D01*
X69753Y697503D01*
X69419D01*
X69086Y697628D01*
X68836Y697836D01*
X68711Y698128D01*
X68794Y698420D01*
X69003Y698670D01*
X69378Y698836D01*
X69878Y698920D01*
X70169Y699086D01*
X70294Y699378D01*
X70211Y699670D01*
X70003Y699878D01*
X69711Y700003D01*
X69419D01*
X69128Y699920D01*
X68878Y699711D01*
G01X65569Y699795D02*
X65819Y699920D01*
X66111Y700003D01*
X66444D01*
X66819Y699878D01*
X67111Y699670D01*
X67319Y699420D01*
X67486Y699003D01*
X67528Y698628D01*
X67444Y698253D01*
X67319Y698003D01*
X67069Y697753D01*
X66778Y697586D01*
X66486Y697503D01*
X66194D01*
X65903Y697586D01*
X65653Y697711D01*
X65444Y697878D01*
G01X63386Y697503D02*
Y700003D01*
X63886Y699503D01*
G01Y697503D02*
X62886D01*
G01X60286D02*
Y700003D01*
X60786Y699503D01*
G01Y697503D02*
X59786D01*
G01X57186D02*
Y700003D01*
X57686Y699503D01*
G01Y697503D02*
X56686D01*
G01X54878Y698545D02*
X54586Y698836D01*
X54336Y699003D01*
X54003Y699086D01*
X53711Y699003D01*
X53503Y698836D01*
X53336Y698586D01*
X53294Y698295D01*
X53336Y698045D01*
X53503Y697795D01*
X53753Y697586D01*
X54044Y697503D01*
X54378Y697586D01*
X54669Y697836D01*
X54836Y698211D01*
X54878Y698628D01*
X54794Y699170D01*
X54669Y699461D01*
X54461Y699753D01*
X54169Y699961D01*
X53878Y700003D01*
X53586Y699920D01*
X53378Y699711D01*
G01X70461Y702336D02*
X70128Y702128D01*
X69753Y702003D01*
X69419D01*
X69086Y702128D01*
X68836Y702336D01*
X68711Y702628D01*
X68794Y702920D01*
X69003Y703170D01*
X69378Y703336D01*
X69878Y703420D01*
X70169Y703586D01*
X70294Y703878D01*
X70211Y704170D01*
X70003Y704378D01*
X69711Y704503D01*
X69419D01*
X69128Y704420D01*
X68878Y704211D01*
G01X65569Y704295D02*
X65819Y704420D01*
X66111Y704503D01*
X66444D01*
X66819Y704378D01*
X67111Y704170D01*
X67319Y703920D01*
X67486Y703503D01*
X67528Y703128D01*
X67444Y702753D01*
X67319Y702503D01*
X67069Y702253D01*
X66778Y702086D01*
X66486Y702003D01*
X66194D01*
X65903Y702086D01*
X65653Y702211D01*
X65444Y702378D01*
G01X63386Y702003D02*
Y704503D01*
X63886Y704003D01*
G01Y702003D02*
X62886D01*
G01X60286D02*
Y704503D01*
X60786Y704003D01*
G01Y702003D02*
X59786D01*
G01X57186D02*
Y704503D01*
X57686Y704003D01*
G01Y702003D02*
X56686D01*
G01X55003Y702378D02*
X54753Y702170D01*
X54461Y702045D01*
X54086Y702003D01*
X53711Y702086D01*
X53419Y702253D01*
X53211Y702545D01*
X53169Y702878D01*
X53253Y703211D01*
X53461Y703420D01*
X53753Y703586D01*
X54044Y703628D01*
X54336Y703586D01*
X54711Y703420D01*
X54586Y704503D01*
X53461D01*
G01X73879Y826053D02*
X73546Y825845D01*
X73171Y825720D01*
X72837D01*
X72504Y825845D01*
X72254Y826053D01*
X72129Y826345D01*
X72212Y826637D01*
X72421Y826887D01*
X72796Y827053D01*
X73296Y827137D01*
X73587Y827303D01*
X73712Y827595D01*
X73629Y827887D01*
X73421Y828095D01*
X73129Y828220D01*
X72837D01*
X72546Y828137D01*
X72296Y827928D01*
G01X68987Y828012D02*
X69237Y828137D01*
X69529Y828220D01*
X69862D01*
X70237Y828095D01*
X70529Y827887D01*
X70737Y827637D01*
X70904Y827220D01*
X70946Y826845D01*
X70862Y826470D01*
X70737Y826220D01*
X70487Y825970D01*
X70196Y825803D01*
X69904Y825720D01*
X69612D01*
X69321Y825803D01*
X69071Y825928D01*
X68862Y826095D01*
G01X66804Y825720D02*
X66512Y825762D01*
X66179Y825887D01*
X65971Y826095D01*
X65887Y826387D01*
X65971Y826678D01*
X66221Y826928D01*
X66596Y827053D01*
X67012D01*
X67262Y827137D01*
X67471Y827345D01*
X67554Y827637D01*
X67429Y827928D01*
X67137Y828137D01*
X66804Y828220D01*
X66471Y828137D01*
X66179Y827928D01*
X66054Y827637D01*
X66137Y827345D01*
X66346Y827137D01*
X66596Y827053D01*
X67012D01*
X67387Y826928D01*
X67637Y826678D01*
X67721Y826387D01*
X67637Y826095D01*
X67429Y825887D01*
X67096Y825762D01*
X66804Y825720D01*
G01X64496Y826762D02*
X64204Y827053D01*
X63954Y827220D01*
X63621Y827303D01*
X63329Y827220D01*
X63121Y827053D01*
X62954Y826803D01*
X62912Y826512D01*
X62954Y826262D01*
X63121Y826012D01*
X63371Y825803D01*
X63662Y825720D01*
X63996Y825803D01*
X64287Y826053D01*
X64454Y826428D01*
X64496Y826845D01*
X64412Y827387D01*
X64287Y827678D01*
X64079Y827970D01*
X63787Y828178D01*
X63496Y828220D01*
X63204Y828137D01*
X62996Y827928D01*
G01X60604Y828220D02*
X60937Y828137D01*
X61187Y827928D01*
X61354Y827678D01*
X61479Y827345D01*
X61521Y826970D01*
X61479Y826595D01*
X61354Y826262D01*
X61187Y826012D01*
X60937Y825803D01*
X60604Y825720D01*
X60271Y825803D01*
X60021Y826012D01*
X59854Y826262D01*
X59729Y826595D01*
X59687Y826970D01*
X59729Y827345D01*
X59854Y827678D01*
X60021Y827928D01*
X60271Y828137D01*
X60604Y828220D01*
G01X75879Y858553D02*
X75546Y858345D01*
X75171Y858220D01*
X74837D01*
X74504Y858345D01*
X74254Y858553D01*
X74129Y858845D01*
X74212Y859137D01*
X74421Y859387D01*
X74796Y859553D01*
X75296Y859637D01*
X75587Y859803D01*
X75712Y860095D01*
X75629Y860387D01*
X75421Y860595D01*
X75129Y860720D01*
X74837D01*
X74546Y860637D01*
X74296Y860428D01*
G01X70987Y860512D02*
X71237Y860637D01*
X71529Y860720D01*
X71862D01*
X72237Y860595D01*
X72529Y860387D01*
X72737Y860137D01*
X72904Y859720D01*
X72946Y859345D01*
X72862Y858970D01*
X72737Y858720D01*
X72487Y858470D01*
X72196Y858303D01*
X71904Y858220D01*
X71612D01*
X71321Y858303D01*
X71071Y858428D01*
X70862Y858595D01*
G01X68304Y858220D02*
Y860720D01*
X69846Y858928D01*
X67762D01*
G01X66496Y860303D02*
X66246Y860553D01*
X65954Y860678D01*
X65621Y860720D01*
X65204Y860637D01*
X64912Y860428D01*
X64829Y860178D01*
X64871Y859928D01*
X65037Y859720D01*
X65871Y859303D01*
X66246Y859012D01*
X66496Y858595D01*
X66579Y858220D01*
X64829D01*
G01X62604D02*
X62312Y858262D01*
X61979Y858387D01*
X61771Y858595D01*
X61687Y858887D01*
X61771Y859178D01*
X62021Y859428D01*
X62396Y859553D01*
X62812D01*
X63062Y859637D01*
X63271Y859845D01*
X63354Y860137D01*
X63229Y860428D01*
X62937Y860637D01*
X62604Y860720D01*
X62271Y860637D01*
X61979Y860428D01*
X61854Y860137D01*
X61937Y859845D01*
X62146Y859637D01*
X62396Y859553D01*
X62812D01*
X63187Y859428D01*
X63437Y859178D01*
X63521Y858887D01*
X63437Y858595D01*
X63229Y858387D01*
X62896Y858262D01*
X62604Y858220D01*
G01X56020Y894705D02*
X58520D01*
Y895746D01*
X58395Y896080D01*
X58228Y896288D01*
X57895Y896371D01*
X57562Y896288D01*
X57353Y896038D01*
X57228Y895746D01*
Y894705D01*
G01Y895746D02*
X56020Y896371D01*
G01X56395Y897721D02*
X56187Y897971D01*
X56062Y898263D01*
X56020Y898638D01*
X56103Y899013D01*
X56270Y899305D01*
X56562Y899513D01*
X56895Y899555D01*
X57228Y899471D01*
X57437Y899263D01*
X57603Y898971D01*
X57645Y898680D01*
X57603Y898388D01*
X57437Y898013D01*
X58520Y898138D01*
Y899263D01*
G01X56020Y901738D02*
X58520D01*
X58020Y901238D01*
G01X56020D02*
Y902238D01*
G01X56395Y903921D02*
X56187Y904171D01*
X56062Y904463D01*
X56020Y904838D01*
X56103Y905213D01*
X56270Y905505D01*
X56562Y905713D01*
X56895Y905755D01*
X57228Y905671D01*
X57437Y905463D01*
X57603Y905171D01*
X57645Y904880D01*
X57603Y904588D01*
X57437Y904213D01*
X58520Y904338D01*
Y905463D01*
G01X55020Y916388D02*
X59020D01*
Y908988D01*
G01X60520Y894705D02*
X63020D01*
Y895746D01*
X62895Y896080D01*
X62728Y896288D01*
X62395Y896371D01*
X62062Y896288D01*
X61853Y896038D01*
X61728Y895746D01*
Y894705D01*
G01Y895746D02*
X60520Y896371D01*
G01X60895Y897721D02*
X60687Y897971D01*
X60562Y898263D01*
X60520Y898638D01*
X60603Y899013D01*
X60770Y899305D01*
X61062Y899513D01*
X61395Y899555D01*
X61728Y899471D01*
X61937Y899263D01*
X62103Y898971D01*
X62145Y898680D01*
X62103Y898388D01*
X61937Y898013D01*
X63020Y898138D01*
Y899263D01*
G01X60520Y901738D02*
X63020D01*
X62520Y901238D01*
G01X60520D02*
Y902238D01*
G01X61562Y904046D02*
X61853Y904338D01*
X62020Y904588D01*
X62103Y904921D01*
X62020Y905213D01*
X61853Y905421D01*
X61603Y905588D01*
X61312Y905630D01*
X61062Y905588D01*
X60812Y905421D01*
X60603Y905171D01*
X60520Y904880D01*
X60603Y904546D01*
X60853Y904255D01*
X61228Y904088D01*
X61645Y904046D01*
X62187Y904130D01*
X62478Y904255D01*
X62770Y904463D01*
X62978Y904755D01*
X63020Y905046D01*
X62937Y905338D01*
X62728Y905546D01*
G01X59520Y916388D02*
X63520D01*
Y908988D01*
G01X65020Y894705D02*
X67520D01*
Y895746D01*
X67395Y896080D01*
X67228Y896288D01*
X66895Y896371D01*
X66562Y896288D01*
X66353Y896038D01*
X66228Y895746D01*
Y894705D01*
G01Y895746D02*
X65020Y896371D01*
G01X65395Y897721D02*
X65187Y897971D01*
X65062Y898263D01*
X65020Y898638D01*
X65103Y899013D01*
X65270Y899305D01*
X65562Y899513D01*
X65895Y899555D01*
X66228Y899471D01*
X66437Y899263D01*
X66603Y898971D01*
X66645Y898680D01*
X66603Y898388D01*
X66437Y898013D01*
X67520Y898138D01*
Y899263D01*
G01X65020Y901738D02*
X67520D01*
X67020Y901238D01*
G01X65020D02*
Y902238D01*
G01Y904755D02*
X65562Y904838D01*
X66020Y904963D01*
X66437Y905130D01*
X66895Y905338D01*
X67520Y905671D01*
Y904005D01*
G01X64020Y916388D02*
X68020D01*
Y908988D01*
G01X77575Y403243D02*
X77700Y402993D01*
X77783Y402701D01*
Y402368D01*
X77658Y401993D01*
X77450Y401701D01*
X77200Y401493D01*
X76783Y401326D01*
X76408Y401284D01*
X76033Y401368D01*
X75783Y401493D01*
X75533Y401743D01*
X75366Y402034D01*
X75283Y402326D01*
Y402618D01*
X75366Y402909D01*
X75491Y403159D01*
X75658Y403368D01*
G01X75283Y405426D02*
X77783D01*
X77283Y404926D01*
G01X75283D02*
Y405926D01*
G01X75783Y407609D02*
X75491Y407859D01*
X75325Y408193D01*
X75283Y408568D01*
X75325Y408901D01*
X75533Y409234D01*
X75783Y409443D01*
X76033Y409484D01*
X76325Y409401D01*
X76533Y409109D01*
X76616Y408818D01*
Y408443D01*
G01Y408818D02*
X76741Y409068D01*
X76950Y409276D01*
X77200Y409359D01*
X77450Y409276D01*
X77658Y409068D01*
X77783Y408693D01*
X77741Y408318D01*
X77575Y407943D01*
G01X76325Y410834D02*
X76616Y411126D01*
X76783Y411376D01*
X76866Y411709D01*
X76783Y412001D01*
X76616Y412209D01*
X76366Y412376D01*
X76075Y412418D01*
X75825Y412376D01*
X75575Y412209D01*
X75366Y411959D01*
X75283Y411668D01*
X75366Y411334D01*
X75616Y411043D01*
X75991Y410876D01*
X76408Y410834D01*
X76950Y410918D01*
X77241Y411043D01*
X77533Y411251D01*
X77741Y411543D01*
X77783Y411834D01*
X77700Y412126D01*
X77491Y412334D01*
G01X73575Y403243D02*
X73700Y402993D01*
X73783Y402701D01*
Y402368D01*
X73658Y401993D01*
X73450Y401701D01*
X73200Y401493D01*
X72783Y401326D01*
X72408Y401284D01*
X72033Y401368D01*
X71783Y401493D01*
X71533Y401743D01*
X71366Y402034D01*
X71283Y402326D01*
Y402618D01*
X71366Y402909D01*
X71491Y403159D01*
X71658Y403368D01*
G01X71283Y405426D02*
X73783D01*
X73283Y404926D01*
G01X71283D02*
Y405926D01*
G01X71783Y407609D02*
X71491Y407859D01*
X71325Y408193D01*
X71283Y408568D01*
X71325Y408901D01*
X71533Y409234D01*
X71783Y409443D01*
X72033Y409484D01*
X72325Y409401D01*
X72533Y409109D01*
X72616Y408818D01*
Y408443D01*
G01Y408818D02*
X72741Y409068D01*
X72950Y409276D01*
X73200Y409359D01*
X73450Y409276D01*
X73658Y409068D01*
X73783Y408693D01*
X73741Y408318D01*
X73575Y407943D01*
G01X71658Y410709D02*
X71450Y410959D01*
X71325Y411251D01*
X71283Y411626D01*
X71366Y412001D01*
X71533Y412293D01*
X71825Y412501D01*
X72158Y412543D01*
X72491Y412459D01*
X72700Y412251D01*
X72866Y411959D01*
X72908Y411668D01*
X72866Y411376D01*
X72700Y411001D01*
X73783Y411126D01*
Y412251D01*
G01X89879Y724053D02*
X89546Y723845D01*
X89171Y723720D01*
X88837D01*
X88504Y723845D01*
X88254Y724053D01*
X88129Y724345D01*
X88212Y724637D01*
X88421Y724887D01*
X88796Y725053D01*
X89296Y725137D01*
X89587Y725303D01*
X89712Y725595D01*
X89629Y725887D01*
X89421Y726095D01*
X89129Y726220D01*
X88837D01*
X88546Y726137D01*
X88296Y725928D01*
G01X84987Y726012D02*
X85237Y726137D01*
X85529Y726220D01*
X85862D01*
X86237Y726095D01*
X86529Y725887D01*
X86737Y725637D01*
X86904Y725220D01*
X86946Y724845D01*
X86862Y724470D01*
X86737Y724220D01*
X86487Y723970D01*
X86196Y723803D01*
X85904Y723720D01*
X85612D01*
X85321Y723803D01*
X85071Y723928D01*
X84862Y724095D01*
G01X83721D02*
X83471Y723887D01*
X83179Y723762D01*
X82804Y723720D01*
X82429Y723803D01*
X82137Y723970D01*
X81929Y724262D01*
X81887Y724595D01*
X81971Y724928D01*
X82179Y725137D01*
X82471Y725303D01*
X82762Y725345D01*
X83054Y725303D01*
X83429Y725137D01*
X83304Y726220D01*
X82179D01*
G01X79204Y723720D02*
Y726220D01*
X80746Y724428D01*
X78662D01*
G01X76687Y723720D02*
X76604Y724262D01*
X76479Y724720D01*
X76312Y725137D01*
X76104Y725595D01*
X75771Y726220D01*
X77437D01*
G01X82347Y757837D02*
X82014Y757629D01*
X81639Y757504D01*
X81305D01*
X80972Y757629D01*
X80722Y757837D01*
X80597Y758129D01*
X80680Y758421D01*
X80889Y758671D01*
X81264Y758837D01*
X81764Y758921D01*
X82055Y759087D01*
X82180Y759379D01*
X82097Y759671D01*
X81889Y759879D01*
X81597Y760004D01*
X81305D01*
X81014Y759921D01*
X80764Y759712D01*
G01X77455Y759796D02*
X77705Y759921D01*
X77997Y760004D01*
X78330D01*
X78705Y759879D01*
X78997Y759671D01*
X79205Y759421D01*
X79372Y759004D01*
X79414Y758629D01*
X79330Y758254D01*
X79205Y758004D01*
X78955Y757754D01*
X78664Y757587D01*
X78372Y757504D01*
X78080D01*
X77789Y757587D01*
X77539Y757712D01*
X77330Y757879D01*
G01X76189D02*
X75939Y757671D01*
X75647Y757546D01*
X75272Y757504D01*
X74897Y757587D01*
X74605Y757754D01*
X74397Y758046D01*
X74355Y758379D01*
X74439Y758712D01*
X74647Y758921D01*
X74939Y759087D01*
X75230Y759129D01*
X75522Y759087D01*
X75897Y758921D01*
X75772Y760004D01*
X74647D01*
G01X71672Y757504D02*
Y760004D01*
X73214Y758212D01*
X71130D01*
G01X69989Y757879D02*
X69739Y757671D01*
X69447Y757546D01*
X69072Y757504D01*
X68697Y757587D01*
X68405Y757754D01*
X68197Y758046D01*
X68155Y758379D01*
X68239Y758712D01*
X68447Y758921D01*
X68739Y759087D01*
X69030Y759129D01*
X69322Y759087D01*
X69697Y758921D01*
X69572Y760004D01*
X68447D01*
G01X93379Y858553D02*
X93046Y858345D01*
X92671Y858220D01*
X92337D01*
X92004Y858345D01*
X91754Y858553D01*
X91629Y858845D01*
X91712Y859137D01*
X91921Y859387D01*
X92296Y859553D01*
X92796Y859637D01*
X93087Y859803D01*
X93212Y860095D01*
X93129Y860387D01*
X92921Y860595D01*
X92629Y860720D01*
X92337D01*
X92046Y860637D01*
X91796Y860428D01*
G01X88487Y860512D02*
X88737Y860637D01*
X89029Y860720D01*
X89362D01*
X89737Y860595D01*
X90029Y860387D01*
X90237Y860137D01*
X90404Y859720D01*
X90446Y859345D01*
X90362Y858970D01*
X90237Y858720D01*
X89987Y858470D01*
X89696Y858303D01*
X89404Y858220D01*
X89112D01*
X88821Y858303D01*
X88571Y858428D01*
X88362Y858595D01*
G01X87096Y859262D02*
X86804Y859553D01*
X86554Y859720D01*
X86221Y859803D01*
X85929Y859720D01*
X85721Y859553D01*
X85554Y859303D01*
X85512Y859012D01*
X85554Y858762D01*
X85721Y858512D01*
X85971Y858303D01*
X86262Y858220D01*
X86596Y858303D01*
X86887Y858553D01*
X87054Y858928D01*
X87096Y859345D01*
X87012Y859887D01*
X86887Y860178D01*
X86679Y860470D01*
X86387Y860678D01*
X86096Y860720D01*
X85804Y860637D01*
X85596Y860428D01*
G01X84121Y858720D02*
X83871Y858428D01*
X83537Y858262D01*
X83162Y858220D01*
X82829Y858262D01*
X82496Y858470D01*
X82287Y858720D01*
X82246Y858970D01*
X82329Y859262D01*
X82621Y859470D01*
X82912Y859553D01*
X83287D01*
G01X82912D02*
X82662Y859678D01*
X82454Y859887D01*
X82371Y860137D01*
X82454Y860387D01*
X82662Y860595D01*
X83037Y860720D01*
X83412Y860678D01*
X83787Y860512D01*
G01X79604Y858220D02*
Y860720D01*
X81146Y858928D01*
X79062D01*
G01X102429Y673553D02*
X102096Y673345D01*
X101721Y673220D01*
X101387D01*
X101054Y673345D01*
X100804Y673553D01*
X100679Y673845D01*
X100762Y674137D01*
X100971Y674387D01*
X101346Y674553D01*
X101846Y674637D01*
X102137Y674803D01*
X102262Y675095D01*
X102179Y675387D01*
X101971Y675595D01*
X101679Y675720D01*
X101387D01*
X101096Y675637D01*
X100846Y675428D01*
G01X97537Y675512D02*
X97787Y675637D01*
X98079Y675720D01*
X98412D01*
X98787Y675595D01*
X99079Y675387D01*
X99287Y675137D01*
X99454Y674720D01*
X99496Y674345D01*
X99412Y673970D01*
X99287Y673720D01*
X99037Y673470D01*
X98746Y673303D01*
X98454Y673220D01*
X98162D01*
X97871Y673303D01*
X97621Y673428D01*
X97412Y673595D01*
G01X95354Y673220D02*
Y675720D01*
X95854Y675220D01*
G01Y673220D02*
X94854D01*
G01X92254D02*
Y675720D01*
X92754Y675220D01*
G01Y673220D02*
X91754D01*
G01X89154D02*
Y675720D01*
X89654Y675220D01*
G01Y673220D02*
X88654D01*
G01X85554D02*
Y675720D01*
X87096Y673928D01*
X85012D01*
G01X104961Y702836D02*
X104628Y702628D01*
X104253Y702503D01*
X103919D01*
X103586Y702628D01*
X103336Y702836D01*
X103211Y703128D01*
X103294Y703420D01*
X103503Y703670D01*
X103878Y703836D01*
X104378Y703920D01*
X104669Y704086D01*
X104794Y704378D01*
X104711Y704670D01*
X104503Y704878D01*
X104211Y705003D01*
X103919D01*
X103628Y704920D01*
X103378Y704711D01*
G01X100069Y704795D02*
X100319Y704920D01*
X100611Y705003D01*
X100944D01*
X101319Y704878D01*
X101611Y704670D01*
X101819Y704420D01*
X101986Y704003D01*
X102028Y703628D01*
X101944Y703253D01*
X101819Y703003D01*
X101569Y702753D01*
X101278Y702586D01*
X100986Y702503D01*
X100694D01*
X100403Y702586D01*
X100153Y702711D01*
X99944Y702878D01*
G01X97886Y702503D02*
Y705003D01*
X98386Y704503D01*
G01Y702503D02*
X97386D01*
G01X94786D02*
Y705003D01*
X95286Y704503D01*
G01Y702503D02*
X94286D01*
G01X91686D02*
Y705003D01*
X92186Y704503D01*
G01Y702503D02*
X91186D01*
G01X89378Y704586D02*
X89128Y704836D01*
X88836Y704961D01*
X88503Y705003D01*
X88086Y704920D01*
X87794Y704711D01*
X87711Y704461D01*
X87753Y704211D01*
X87919Y704003D01*
X88753Y703586D01*
X89128Y703295D01*
X89378Y702878D01*
X89461Y702503D01*
X87711D01*
G01X104961Y698336D02*
X104628Y698128D01*
X104253Y698003D01*
X103919D01*
X103586Y698128D01*
X103336Y698336D01*
X103211Y698628D01*
X103294Y698920D01*
X103503Y699170D01*
X103878Y699336D01*
X104378Y699420D01*
X104669Y699586D01*
X104794Y699878D01*
X104711Y700170D01*
X104503Y700378D01*
X104211Y700503D01*
X103919D01*
X103628Y700420D01*
X103378Y700211D01*
G01X100069Y700295D02*
X100319Y700420D01*
X100611Y700503D01*
X100944D01*
X101319Y700378D01*
X101611Y700170D01*
X101819Y699920D01*
X101986Y699503D01*
X102028Y699128D01*
X101944Y698753D01*
X101819Y698503D01*
X101569Y698253D01*
X101278Y698086D01*
X100986Y698003D01*
X100694D01*
X100403Y698086D01*
X100153Y698211D01*
X99944Y698378D01*
G01X97886Y698003D02*
Y700503D01*
X98386Y700003D01*
G01Y698003D02*
X97386D01*
G01X94786D02*
Y700503D01*
X95286Y700003D01*
G01Y698003D02*
X94286D01*
G01X91686D02*
Y700503D01*
X92186Y700003D01*
G01Y698003D02*
X91186D01*
G01X89503Y698503D02*
X89253Y698211D01*
X88919Y698045D01*
X88544Y698003D01*
X88211Y698045D01*
X87878Y698253D01*
X87669Y698503D01*
X87628Y698753D01*
X87711Y699045D01*
X88003Y699253D01*
X88294Y699336D01*
X88669D01*
G01X88294D02*
X88044Y699461D01*
X87836Y699670D01*
X87753Y699920D01*
X87836Y700170D01*
X88044Y700378D01*
X88419Y700503D01*
X88794Y700461D01*
X89169Y700295D01*
G01X97804Y918420D02*
X101804D01*
Y911020D01*
G01X99804Y931737D02*
X102304D01*
Y932778D01*
X102179Y933112D01*
X102012Y933320D01*
X101679Y933403D01*
X101346Y933320D01*
X101137Y933070D01*
X101012Y932778D01*
Y931737D01*
G01Y932778D02*
X99804Y933403D01*
G01X100179Y934753D02*
X99971Y935003D01*
X99846Y935295D01*
X99804Y935670D01*
X99887Y936045D01*
X100054Y936337D01*
X100346Y936545D01*
X100679Y936587D01*
X101012Y936503D01*
X101221Y936295D01*
X101387Y936003D01*
X101429Y935712D01*
X101387Y935420D01*
X101221Y935045D01*
X102304Y935170D01*
Y936295D01*
G01Y938770D02*
X102221Y938437D01*
X102012Y938187D01*
X101762Y938020D01*
X101429Y937895D01*
X101054Y937853D01*
X100679Y937895D01*
X100346Y938020D01*
X100096Y938187D01*
X99887Y938437D01*
X99804Y938770D01*
X99887Y939103D01*
X100096Y939353D01*
X100346Y939520D01*
X100679Y939645D01*
X101054Y939687D01*
X101429Y939645D01*
X101762Y939520D01*
X102012Y939353D01*
X102221Y939103D01*
X102304Y938770D01*
G01X101887Y941078D02*
X102137Y941328D01*
X102262Y941620D01*
X102304Y941953D01*
X102221Y942370D01*
X102012Y942662D01*
X101762Y942745D01*
X101512Y942703D01*
X101304Y942537D01*
X100887Y941703D01*
X100596Y941328D01*
X100179Y941078D01*
X99804Y940995D01*
Y942745D01*
G01X126037Y807012D02*
X126287Y807137D01*
X126579Y807220D01*
X126912D01*
X127287Y807095D01*
X127579Y806887D01*
X127787Y806637D01*
X127954Y806220D01*
X127996Y805845D01*
X127912Y805470D01*
X127787Y805220D01*
X127537Y804970D01*
X127246Y804803D01*
X126954Y804720D01*
X126662D01*
X126371Y804803D01*
X126121Y804928D01*
X125912Y805095D01*
G01X124771Y805220D02*
X124521Y804928D01*
X124187Y804762D01*
X123812Y804720D01*
X123479Y804762D01*
X123146Y804970D01*
X122937Y805220D01*
X122896Y805470D01*
X122979Y805762D01*
X123271Y805970D01*
X123562Y806053D01*
X123937D01*
G01X123562D02*
X123312Y806178D01*
X123104Y806387D01*
X123021Y806637D01*
X123104Y806887D01*
X123312Y807095D01*
X123687Y807220D01*
X124062Y807178D01*
X124437Y807012D01*
G01X121546Y806803D02*
X121296Y807053D01*
X121004Y807178D01*
X120671Y807220D01*
X120254Y807137D01*
X119962Y806928D01*
X119879Y806678D01*
X119921Y806428D01*
X120087Y806220D01*
X120921Y805803D01*
X121296Y805512D01*
X121546Y805095D01*
X121629Y804720D01*
X119879D01*
G01X117654Y807220D02*
X117987Y807137D01*
X118237Y806928D01*
X118404Y806678D01*
X118529Y806345D01*
X118571Y805970D01*
X118529Y805595D01*
X118404Y805262D01*
X118237Y805012D01*
X117987Y804803D01*
X117654Y804720D01*
X117321Y804803D01*
X117071Y805012D01*
X116904Y805262D01*
X116779Y805595D01*
X116737Y805970D01*
X116779Y806345D01*
X116904Y806678D01*
X117071Y806928D01*
X117321Y807137D01*
X117654Y807220D01*
G01X101804Y918420D02*
X105804D01*
Y911020D01*
G01Y918420D02*
X109804D01*
Y911020D01*
G01Y918420D02*
X113804D01*
Y911020D01*
G01Y918420D02*
X117804D01*
Y911020D01*
G01X103804Y931737D02*
X106304D01*
Y932778D01*
X106179Y933112D01*
X106012Y933320D01*
X105679Y933403D01*
X105346Y933320D01*
X105137Y933070D01*
X105012Y932778D01*
Y931737D01*
G01Y932778D02*
X103804Y933403D01*
G01X104179Y934753D02*
X103971Y935003D01*
X103846Y935295D01*
X103804Y935670D01*
X103887Y936045D01*
X104054Y936337D01*
X104346Y936545D01*
X104679Y936587D01*
X105012Y936503D01*
X105221Y936295D01*
X105387Y936003D01*
X105429Y935712D01*
X105387Y935420D01*
X105221Y935045D01*
X106304Y935170D01*
Y936295D01*
G01Y938770D02*
X106221Y938437D01*
X106012Y938187D01*
X105762Y938020D01*
X105429Y937895D01*
X105054Y937853D01*
X104679Y937895D01*
X104346Y938020D01*
X104096Y938187D01*
X103887Y938437D01*
X103804Y938770D01*
X103887Y939103D01*
X104096Y939353D01*
X104346Y939520D01*
X104679Y939645D01*
X105054Y939687D01*
X105429Y939645D01*
X105762Y939520D01*
X106012Y939353D01*
X106221Y939103D01*
X106304Y938770D01*
G01X104304Y940953D02*
X104012Y941203D01*
X103846Y941537D01*
X103804Y941912D01*
X103846Y942245D01*
X104054Y942578D01*
X104304Y942787D01*
X104554Y942828D01*
X104846Y942745D01*
X105054Y942453D01*
X105137Y942162D01*
Y941787D01*
G01Y942162D02*
X105262Y942412D01*
X105471Y942620D01*
X105721Y942703D01*
X105971Y942620D01*
X106179Y942412D01*
X106304Y942037D01*
X106262Y941662D01*
X106096Y941287D01*
G01X107804Y931737D02*
X110304D01*
Y932778D01*
X110179Y933112D01*
X110012Y933320D01*
X109679Y933403D01*
X109346Y933320D01*
X109137Y933070D01*
X109012Y932778D01*
Y931737D01*
G01Y932778D02*
X107804Y933403D01*
G01X108179Y934753D02*
X107971Y935003D01*
X107846Y935295D01*
X107804Y935670D01*
X107887Y936045D01*
X108054Y936337D01*
X108346Y936545D01*
X108679Y936587D01*
X109012Y936503D01*
X109221Y936295D01*
X109387Y936003D01*
X109429Y935712D01*
X109387Y935420D01*
X109221Y935045D01*
X110304Y935170D01*
Y936295D01*
G01Y938770D02*
X110221Y938437D01*
X110012Y938187D01*
X109762Y938020D01*
X109429Y937895D01*
X109054Y937853D01*
X108679Y937895D01*
X108346Y938020D01*
X108096Y938187D01*
X107887Y938437D01*
X107804Y938770D01*
X107887Y939103D01*
X108096Y939353D01*
X108346Y939520D01*
X108679Y939645D01*
X109054Y939687D01*
X109429Y939645D01*
X109762Y939520D01*
X110012Y939353D01*
X110221Y939103D01*
X110304Y938770D01*
G01X107804Y942370D02*
X110304D01*
X108512Y940828D01*
Y942912D01*
G01X111804Y931737D02*
X114304D01*
Y932778D01*
X114179Y933112D01*
X114012Y933320D01*
X113679Y933403D01*
X113346Y933320D01*
X113137Y933070D01*
X113012Y932778D01*
Y931737D01*
G01Y932778D02*
X111804Y933403D01*
G01X112179Y934753D02*
X111971Y935003D01*
X111846Y935295D01*
X111804Y935670D01*
X111887Y936045D01*
X112054Y936337D01*
X112346Y936545D01*
X112679Y936587D01*
X113012Y936503D01*
X113221Y936295D01*
X113387Y936003D01*
X113429Y935712D01*
X113387Y935420D01*
X113221Y935045D01*
X114304Y935170D01*
Y936295D01*
G01Y938770D02*
X114221Y938437D01*
X114012Y938187D01*
X113762Y938020D01*
X113429Y937895D01*
X113054Y937853D01*
X112679Y937895D01*
X112346Y938020D01*
X112096Y938187D01*
X111887Y938437D01*
X111804Y938770D01*
X111887Y939103D01*
X112096Y939353D01*
X112346Y939520D01*
X112679Y939645D01*
X113054Y939687D01*
X113429Y939645D01*
X113762Y939520D01*
X114012Y939353D01*
X114221Y939103D01*
X114304Y938770D01*
G01X112179Y940953D02*
X111971Y941203D01*
X111846Y941495D01*
X111804Y941870D01*
X111887Y942245D01*
X112054Y942537D01*
X112346Y942745D01*
X112679Y942787D01*
X113012Y942703D01*
X113221Y942495D01*
X113387Y942203D01*
X113429Y941912D01*
X113387Y941620D01*
X113221Y941245D01*
X114304Y941370D01*
Y942495D01*
G01X115804Y931737D02*
X118304D01*
Y932778D01*
X118179Y933112D01*
X118012Y933320D01*
X117679Y933403D01*
X117346Y933320D01*
X117137Y933070D01*
X117012Y932778D01*
Y931737D01*
G01Y932778D02*
X115804Y933403D01*
G01X116179Y934753D02*
X115971Y935003D01*
X115846Y935295D01*
X115804Y935670D01*
X115887Y936045D01*
X116054Y936337D01*
X116346Y936545D01*
X116679Y936587D01*
X117012Y936503D01*
X117221Y936295D01*
X117387Y936003D01*
X117429Y935712D01*
X117387Y935420D01*
X117221Y935045D01*
X118304Y935170D01*
Y936295D01*
G01Y938770D02*
X118221Y938437D01*
X118012Y938187D01*
X117762Y938020D01*
X117429Y937895D01*
X117054Y937853D01*
X116679Y937895D01*
X116346Y938020D01*
X116096Y938187D01*
X115887Y938437D01*
X115804Y938770D01*
X115887Y939103D01*
X116096Y939353D01*
X116346Y939520D01*
X116679Y939645D01*
X117054Y939687D01*
X117429Y939645D01*
X117762Y939520D01*
X118012Y939353D01*
X118221Y939103D01*
X118304Y938770D01*
G01X116846Y941078D02*
X117137Y941370D01*
X117304Y941620D01*
X117387Y941953D01*
X117304Y942245D01*
X117137Y942453D01*
X116887Y942620D01*
X116596Y942662D01*
X116346Y942620D01*
X116096Y942453D01*
X115887Y942203D01*
X115804Y941912D01*
X115887Y941578D01*
X116137Y941287D01*
X116512Y941120D01*
X116929Y941078D01*
X117471Y941162D01*
X117762Y941287D01*
X118054Y941495D01*
X118262Y941787D01*
X118304Y942078D01*
X118221Y942370D01*
X118012Y942578D01*
G01X126537Y793012D02*
X126787Y793137D01*
X127079Y793220D01*
X127412D01*
X127787Y793095D01*
X128079Y792887D01*
X128287Y792637D01*
X128454Y792220D01*
X128496Y791845D01*
X128412Y791470D01*
X128287Y791220D01*
X128037Y790970D01*
X127746Y790803D01*
X127454Y790720D01*
X127162D01*
X126871Y790803D01*
X126621Y790928D01*
X126412Y791095D01*
G01X125271Y791220D02*
X125021Y790928D01*
X124687Y790762D01*
X124312Y790720D01*
X123979Y790762D01*
X123646Y790970D01*
X123437Y791220D01*
X123396Y791470D01*
X123479Y791762D01*
X123771Y791970D01*
X124062Y792053D01*
X124437D01*
G01X124062D02*
X123812Y792178D01*
X123604Y792387D01*
X123521Y792637D01*
X123604Y792887D01*
X123812Y793095D01*
X124187Y793220D01*
X124562Y793178D01*
X124937Y793012D01*
G01X122046Y792803D02*
X121796Y793053D01*
X121504Y793178D01*
X121171Y793220D01*
X120754Y793137D01*
X120462Y792928D01*
X120379Y792678D01*
X120421Y792428D01*
X120587Y792220D01*
X121421Y791803D01*
X121796Y791512D01*
X122046Y791095D01*
X122129Y790720D01*
X120379D01*
G01X119071Y791220D02*
X118821Y790928D01*
X118487Y790762D01*
X118112Y790720D01*
X117779Y790762D01*
X117446Y790970D01*
X117237Y791220D01*
X117196Y791470D01*
X117279Y791762D01*
X117571Y791970D01*
X117862Y792053D01*
X118237D01*
G01X117862D02*
X117612Y792178D01*
X117404Y792387D01*
X117321Y792637D01*
X117404Y792887D01*
X117612Y793095D01*
X117987Y793220D01*
X118362Y793178D01*
X118737Y793012D01*
G01X117804Y918420D02*
X121804D01*
Y911020D01*
G01Y918420D02*
X125804D01*
Y911020D01*
G01Y918420D02*
X129804D01*
Y911020D01*
G01Y918420D02*
X133804D01*
Y911020D01*
G01X119804Y931737D02*
X122304D01*
Y932778D01*
X122179Y933112D01*
X122012Y933320D01*
X121679Y933403D01*
X121346Y933320D01*
X121137Y933070D01*
X121012Y932778D01*
Y931737D01*
G01Y932778D02*
X119804Y933403D01*
G01X120179Y934753D02*
X119971Y935003D01*
X119846Y935295D01*
X119804Y935670D01*
X119887Y936045D01*
X120054Y936337D01*
X120346Y936545D01*
X120679Y936587D01*
X121012Y936503D01*
X121221Y936295D01*
X121387Y936003D01*
X121429Y935712D01*
X121387Y935420D01*
X121221Y935045D01*
X122304Y935170D01*
Y936295D01*
G01Y938770D02*
X122221Y938437D01*
X122012Y938187D01*
X121762Y938020D01*
X121429Y937895D01*
X121054Y937853D01*
X120679Y937895D01*
X120346Y938020D01*
X120096Y938187D01*
X119887Y938437D01*
X119804Y938770D01*
X119887Y939103D01*
X120096Y939353D01*
X120346Y939520D01*
X120679Y939645D01*
X121054Y939687D01*
X121429Y939645D01*
X121762Y939520D01*
X122012Y939353D01*
X122221Y939103D01*
X122304Y938770D01*
G01X119804Y941787D02*
X120346Y941870D01*
X120804Y941995D01*
X121221Y942162D01*
X121679Y942370D01*
X122304Y942703D01*
Y941037D01*
G01X123804Y931737D02*
X126304D01*
Y932778D01*
X126179Y933112D01*
X126012Y933320D01*
X125679Y933403D01*
X125346Y933320D01*
X125137Y933070D01*
X125012Y932778D01*
Y931737D01*
G01Y932778D02*
X123804Y933403D01*
G01X124179Y934753D02*
X123971Y935003D01*
X123846Y935295D01*
X123804Y935670D01*
X123887Y936045D01*
X124054Y936337D01*
X124346Y936545D01*
X124679Y936587D01*
X125012Y936503D01*
X125221Y936295D01*
X125387Y936003D01*
X125429Y935712D01*
X125387Y935420D01*
X125221Y935045D01*
X126304Y935170D01*
Y936295D01*
G01Y938770D02*
X126221Y938437D01*
X126012Y938187D01*
X125762Y938020D01*
X125429Y937895D01*
X125054Y937853D01*
X124679Y937895D01*
X124346Y938020D01*
X124096Y938187D01*
X123887Y938437D01*
X123804Y938770D01*
X123887Y939103D01*
X124096Y939353D01*
X124346Y939520D01*
X124679Y939645D01*
X125054Y939687D01*
X125429Y939645D01*
X125762Y939520D01*
X126012Y939353D01*
X126221Y939103D01*
X126304Y938770D01*
G01X123804Y941870D02*
X123846Y942162D01*
X123971Y942495D01*
X124179Y942703D01*
X124471Y942787D01*
X124762Y942703D01*
X125012Y942453D01*
X125137Y942078D01*
Y941662D01*
X125221Y941412D01*
X125429Y941203D01*
X125721Y941120D01*
X126012Y941245D01*
X126221Y941537D01*
X126304Y941870D01*
X126221Y942203D01*
X126012Y942495D01*
X125721Y942620D01*
X125429Y942537D01*
X125221Y942328D01*
X125137Y942078D01*
Y941662D01*
X125012Y941287D01*
X124762Y941037D01*
X124471Y940953D01*
X124179Y941037D01*
X123971Y941245D01*
X123846Y941578D01*
X123804Y941870D01*
G01X127804Y931737D02*
X130304D01*
Y932778D01*
X130179Y933112D01*
X130012Y933320D01*
X129679Y933403D01*
X129346Y933320D01*
X129137Y933070D01*
X129012Y932778D01*
Y931737D01*
G01Y932778D02*
X127804Y933403D01*
G01X128179Y934753D02*
X127971Y935003D01*
X127846Y935295D01*
X127804Y935670D01*
X127887Y936045D01*
X128054Y936337D01*
X128346Y936545D01*
X128679Y936587D01*
X129012Y936503D01*
X129221Y936295D01*
X129387Y936003D01*
X129429Y935712D01*
X129387Y935420D01*
X129221Y935045D01*
X130304Y935170D01*
Y936295D01*
G01Y938770D02*
X130221Y938437D01*
X130012Y938187D01*
X129762Y938020D01*
X129429Y937895D01*
X129054Y937853D01*
X128679Y937895D01*
X128346Y938020D01*
X128096Y938187D01*
X127887Y938437D01*
X127804Y938770D01*
X127887Y939103D01*
X128096Y939353D01*
X128346Y939520D01*
X128679Y939645D01*
X129054Y939687D01*
X129429Y939645D01*
X129762Y939520D01*
X130012Y939353D01*
X130221Y939103D01*
X130304Y938770D01*
G01X128096Y941162D02*
X127887Y941453D01*
X127804Y941787D01*
X127887Y942120D01*
X128137Y942412D01*
X128512Y942620D01*
X128887Y942703D01*
X129346D01*
X129721Y942620D01*
X130054Y942412D01*
X130221Y942162D01*
X130304Y941870D01*
X130221Y941537D01*
X130054Y941287D01*
X129804Y941120D01*
X129471Y941037D01*
X129179Y941120D01*
X128887Y941328D01*
X128721Y941578D01*
X128679Y941870D01*
X128762Y942203D01*
X128971Y942453D01*
X129346Y942703D01*
G01X131804Y931737D02*
X134304D01*
Y932778D01*
X134179Y933112D01*
X134012Y933320D01*
X133679Y933403D01*
X133346Y933320D01*
X133137Y933070D01*
X133012Y932778D01*
Y931737D01*
G01Y932778D02*
X131804Y933403D01*
G01X132179Y934753D02*
X131971Y935003D01*
X131846Y935295D01*
X131804Y935670D01*
X131887Y936045D01*
X132054Y936337D01*
X132346Y936545D01*
X132679Y936587D01*
X133012Y936503D01*
X133221Y936295D01*
X133387Y936003D01*
X133429Y935712D01*
X133387Y935420D01*
X133221Y935045D01*
X134304Y935170D01*
Y936295D01*
G01X131804Y938770D02*
X134304D01*
X133804Y938270D01*
G01X131804D02*
Y939270D01*
G01X134304Y941870D02*
X134221Y941537D01*
X134012Y941287D01*
X133762Y941120D01*
X133429Y940995D01*
X133054Y940953D01*
X132679Y940995D01*
X132346Y941120D01*
X132096Y941287D01*
X131887Y941537D01*
X131804Y941870D01*
X131887Y942203D01*
X132096Y942453D01*
X132346Y942620D01*
X132679Y942745D01*
X133054Y942787D01*
X133429Y942745D01*
X133762Y942620D01*
X134012Y942453D01*
X134221Y942203D01*
X134304Y941870D01*
G01X146628Y299584D02*
X146420Y299917D01*
X146295Y300292D01*
Y300626D01*
X146420Y300959D01*
X146628Y301209D01*
X146920Y301334D01*
X147212Y301251D01*
X147462Y301042D01*
X147628Y300667D01*
X147712Y300167D01*
X147878Y299876D01*
X148170Y299751D01*
X148462Y299834D01*
X148670Y300042D01*
X148795Y300334D01*
Y300626D01*
X148712Y300917D01*
X148503Y301167D01*
G01X148587Y304476D02*
X148712Y304226D01*
X148795Y303934D01*
Y303601D01*
X148670Y303226D01*
X148462Y302934D01*
X148212Y302726D01*
X147795Y302559D01*
X147420Y302517D01*
X147045Y302601D01*
X146795Y302726D01*
X146545Y302976D01*
X146378Y303267D01*
X146295Y303559D01*
Y303851D01*
X146378Y304142D01*
X146503Y304392D01*
X146670Y304601D01*
G01X146295Y306659D02*
X148795D01*
X148295Y306159D01*
G01X146295D02*
Y307159D01*
G01X148378Y308967D02*
X148628Y309217D01*
X148753Y309509D01*
X148795Y309842D01*
X148712Y310259D01*
X148503Y310551D01*
X148253Y310634D01*
X148003Y310592D01*
X147795Y310426D01*
X147378Y309592D01*
X147087Y309217D01*
X146670Y308967D01*
X146295Y308884D01*
Y310634D01*
G01Y312776D02*
X146837Y312859D01*
X147295Y312984D01*
X147712Y313151D01*
X148170Y313359D01*
X148795Y313692D01*
Y312026D01*
G01X146295Y316459D02*
X148795D01*
X147003Y314917D01*
Y317001D01*
G01X133804Y918420D02*
X137804D01*
Y911020D01*
G01X135804Y931737D02*
X138304D01*
Y932778D01*
X138179Y933112D01*
X138012Y933320D01*
X137679Y933403D01*
X137346Y933320D01*
X137137Y933070D01*
X137012Y932778D01*
Y931737D01*
G01Y932778D02*
X135804Y933403D01*
G01X136179Y934753D02*
X135971Y935003D01*
X135846Y935295D01*
X135804Y935670D01*
X135887Y936045D01*
X136054Y936337D01*
X136346Y936545D01*
X136679Y936587D01*
X137012Y936503D01*
X137221Y936295D01*
X137387Y936003D01*
X137429Y935712D01*
X137387Y935420D01*
X137221Y935045D01*
X138304Y935170D01*
Y936295D01*
G01X135804Y938770D02*
X138304D01*
X137804Y938270D01*
G01X135804D02*
Y939270D01*
G01Y941870D02*
X138304D01*
X137804Y941370D01*
G01X135804D02*
Y942370D01*
G01X160128Y299584D02*
X159920Y299917D01*
X159795Y300292D01*
Y300626D01*
X159920Y300959D01*
X160128Y301209D01*
X160420Y301334D01*
X160712Y301251D01*
X160962Y301042D01*
X161128Y300667D01*
X161212Y300167D01*
X161378Y299876D01*
X161670Y299751D01*
X161962Y299834D01*
X162170Y300042D01*
X162295Y300334D01*
Y300626D01*
X162212Y300917D01*
X162003Y301167D01*
G01X162087Y304476D02*
X162212Y304226D01*
X162295Y303934D01*
Y303601D01*
X162170Y303226D01*
X161962Y302934D01*
X161712Y302726D01*
X161295Y302559D01*
X160920Y302517D01*
X160545Y302601D01*
X160295Y302726D01*
X160045Y302976D01*
X159878Y303267D01*
X159795Y303559D01*
Y303851D01*
X159878Y304142D01*
X160003Y304392D01*
X160170Y304601D01*
G01X159795Y306659D02*
X162295D01*
X161795Y306159D01*
G01X159795D02*
Y307159D01*
G01X161878Y308967D02*
X162128Y309217D01*
X162253Y309509D01*
X162295Y309842D01*
X162212Y310259D01*
X162003Y310551D01*
X161753Y310634D01*
X161503Y310592D01*
X161295Y310426D01*
X160878Y309592D01*
X160587Y309217D01*
X160170Y308967D01*
X159795Y308884D01*
Y310634D01*
G01Y312776D02*
X160337Y312859D01*
X160795Y312984D01*
X161212Y313151D01*
X161670Y313359D01*
X162295Y313692D01*
Y312026D01*
G01X159795Y315876D02*
X160337Y315959D01*
X160795Y316084D01*
X161212Y316251D01*
X161670Y316459D01*
X162295Y316792D01*
Y315126D01*
G01X156128Y299584D02*
X155920Y299917D01*
X155795Y300292D01*
Y300626D01*
X155920Y300959D01*
X156128Y301209D01*
X156420Y301334D01*
X156712Y301251D01*
X156962Y301042D01*
X157128Y300667D01*
X157212Y300167D01*
X157378Y299876D01*
X157670Y299751D01*
X157962Y299834D01*
X158170Y300042D01*
X158295Y300334D01*
Y300626D01*
X158212Y300917D01*
X158003Y301167D01*
G01X158087Y304476D02*
X158212Y304226D01*
X158295Y303934D01*
Y303601D01*
X158170Y303226D01*
X157962Y302934D01*
X157712Y302726D01*
X157295Y302559D01*
X156920Y302517D01*
X156545Y302601D01*
X156295Y302726D01*
X156045Y302976D01*
X155878Y303267D01*
X155795Y303559D01*
Y303851D01*
X155878Y304142D01*
X156003Y304392D01*
X156170Y304601D01*
G01X155795Y306659D02*
X158295D01*
X157795Y306159D01*
G01X155795D02*
Y307159D01*
G01X157878Y308967D02*
X158128Y309217D01*
X158253Y309509D01*
X158295Y309842D01*
X158212Y310259D01*
X158003Y310551D01*
X157753Y310634D01*
X157503Y310592D01*
X157295Y310426D01*
X156878Y309592D01*
X156587Y309217D01*
X156170Y308967D01*
X155795Y308884D01*
Y310634D01*
G01Y312776D02*
X156337Y312859D01*
X156795Y312984D01*
X157212Y313151D01*
X157670Y313359D01*
X158295Y313692D01*
Y312026D01*
G01X156837Y315167D02*
X157128Y315459D01*
X157295Y315709D01*
X157378Y316042D01*
X157295Y316334D01*
X157128Y316542D01*
X156878Y316709D01*
X156587Y316751D01*
X156337Y316709D01*
X156087Y316542D01*
X155878Y316292D01*
X155795Y316001D01*
X155878Y315667D01*
X156128Y315376D01*
X156503Y315209D01*
X156920Y315167D01*
X157462Y315251D01*
X157753Y315376D01*
X158045Y315584D01*
X158253Y315876D01*
X158295Y316167D01*
X158212Y316459D01*
X158003Y316667D01*
G01X150628Y299584D02*
X150420Y299917D01*
X150295Y300292D01*
Y300626D01*
X150420Y300959D01*
X150628Y301209D01*
X150920Y301334D01*
X151212Y301251D01*
X151462Y301042D01*
X151628Y300667D01*
X151712Y300167D01*
X151878Y299876D01*
X152170Y299751D01*
X152462Y299834D01*
X152670Y300042D01*
X152795Y300334D01*
Y300626D01*
X152712Y300917D01*
X152503Y301167D01*
G01X152587Y304476D02*
X152712Y304226D01*
X152795Y303934D01*
Y303601D01*
X152670Y303226D01*
X152462Y302934D01*
X152212Y302726D01*
X151795Y302559D01*
X151420Y302517D01*
X151045Y302601D01*
X150795Y302726D01*
X150545Y302976D01*
X150378Y303267D01*
X150295Y303559D01*
Y303851D01*
X150378Y304142D01*
X150503Y304392D01*
X150670Y304601D01*
G01X150295Y306659D02*
X152795D01*
X152295Y306159D01*
G01X150295D02*
Y307159D01*
G01X152378Y308967D02*
X152628Y309217D01*
X152753Y309509D01*
X152795Y309842D01*
X152712Y310259D01*
X152503Y310551D01*
X152253Y310634D01*
X152003Y310592D01*
X151795Y310426D01*
X151378Y309592D01*
X151087Y309217D01*
X150670Y308967D01*
X150295Y308884D01*
Y310634D01*
G01Y312776D02*
X150837Y312859D01*
X151295Y312984D01*
X151712Y313151D01*
X152170Y313359D01*
X152795Y313692D01*
Y312026D01*
G01X150670Y315042D02*
X150462Y315292D01*
X150337Y315584D01*
X150295Y315959D01*
X150378Y316334D01*
X150545Y316626D01*
X150837Y316834D01*
X151170Y316876D01*
X151503Y316792D01*
X151712Y316584D01*
X151878Y316292D01*
X151920Y316001D01*
X151878Y315709D01*
X151712Y315334D01*
X152795Y315459D01*
Y316584D01*
G01X182995Y320709D02*
Y318209D01*
G01X183953Y320709D02*
X182037D01*
G01X180728Y318209D02*
Y320709D01*
X179728D01*
X179395Y320584D01*
X179145Y320292D01*
X179062Y319959D01*
X179145Y319626D01*
X179353Y319376D01*
X179728Y319251D01*
X180728D01*
G01X176795Y318209D02*
Y320709D01*
X177295Y320209D01*
G01Y318209D02*
X176295D01*
G01X173695D02*
X173403Y318251D01*
X173070Y318376D01*
X172862Y318584D01*
X172778Y318876D01*
X172862Y319167D01*
X173112Y319417D01*
X173487Y319542D01*
X173903D01*
X174153Y319626D01*
X174362Y319834D01*
X174445Y320126D01*
X174320Y320417D01*
X174028Y320626D01*
X173695Y320709D01*
X173362Y320626D01*
X173070Y320417D01*
X172945Y320126D01*
X173028Y319834D01*
X173237Y319626D01*
X173487Y319542D01*
X173903D01*
X174278Y319417D01*
X174528Y319167D01*
X174612Y318876D01*
X174528Y318584D01*
X174320Y318376D01*
X173987Y318251D01*
X173695Y318209D01*
G01X170595D02*
X170303Y318251D01*
X169970Y318376D01*
X169762Y318584D01*
X169678Y318876D01*
X169762Y319167D01*
X170012Y319417D01*
X170387Y319542D01*
X170803D01*
X171053Y319626D01*
X171262Y319834D01*
X171345Y320126D01*
X171220Y320417D01*
X170928Y320626D01*
X170595Y320709D01*
X170262Y320626D01*
X169970Y320417D01*
X169845Y320126D01*
X169928Y319834D01*
X170137Y319626D01*
X170387Y319542D01*
X170803D01*
X171178Y319417D01*
X171428Y319167D01*
X171512Y318876D01*
X171428Y318584D01*
X171220Y318376D01*
X170887Y318251D01*
X170595Y318209D01*
G01X182995Y329709D02*
Y327209D01*
G01X183953Y329709D02*
X182037D01*
G01X180728Y327209D02*
Y329709D01*
X179728D01*
X179395Y329584D01*
X179145Y329292D01*
X179062Y328959D01*
X179145Y328626D01*
X179353Y328376D01*
X179728Y328251D01*
X180728D01*
G01X176795Y327209D02*
Y329709D01*
X177295Y329209D01*
G01Y327209D02*
X176295D01*
G01X173195D02*
Y329709D01*
X174737Y327917D01*
X172653D01*
G01X170678Y327209D02*
X170595Y327751D01*
X170470Y328209D01*
X170303Y328626D01*
X170095Y329084D01*
X169762Y329709D01*
X171428D01*
G01X182995Y325209D02*
Y322709D01*
G01X183953Y325209D02*
X182037D01*
G01X180728Y322709D02*
Y325209D01*
X179728D01*
X179395Y325084D01*
X179145Y324792D01*
X179062Y324459D01*
X179145Y324126D01*
X179353Y323876D01*
X179728Y323751D01*
X180728D01*
G01X176795Y322709D02*
Y325209D01*
X177295Y324709D01*
G01Y322709D02*
X176295D01*
G01X173695D02*
X173403Y322751D01*
X173070Y322876D01*
X172862Y323084D01*
X172778Y323376D01*
X172862Y323667D01*
X173112Y323917D01*
X173487Y324042D01*
X173903D01*
X174153Y324126D01*
X174362Y324334D01*
X174445Y324626D01*
X174320Y324917D01*
X174028Y325126D01*
X173695Y325209D01*
X173362Y325126D01*
X173070Y324917D01*
X172945Y324626D01*
X173028Y324334D01*
X173237Y324126D01*
X173487Y324042D01*
X173903D01*
X174278Y323917D01*
X174528Y323667D01*
X174612Y323376D01*
X174528Y323084D01*
X174320Y322876D01*
X173987Y322751D01*
X173695Y322709D01*
G01X171512Y323084D02*
X171262Y322876D01*
X170970Y322751D01*
X170595Y322709D01*
X170220Y322792D01*
X169928Y322959D01*
X169720Y323251D01*
X169678Y323584D01*
X169762Y323917D01*
X169970Y324126D01*
X170262Y324292D01*
X170553Y324334D01*
X170845Y324292D01*
X171220Y324126D01*
X171095Y325209D01*
X169970D01*
G01X195295Y284509D02*
X192795D01*
G01X195295Y283551D02*
Y285467D01*
G01X192795Y286776D02*
X195295D01*
Y287776D01*
X195170Y288109D01*
X194878Y288359D01*
X194545Y288442D01*
X194212Y288359D01*
X193962Y288151D01*
X193837Y287776D01*
Y286776D01*
G01X192795Y290709D02*
X195295D01*
X194795Y290209D01*
G01X192795D02*
Y291209D01*
G01Y293809D02*
X192837Y294101D01*
X192962Y294434D01*
X193170Y294642D01*
X193462Y294726D01*
X193753Y294642D01*
X194003Y294392D01*
X194128Y294017D01*
Y293601D01*
X194212Y293351D01*
X194420Y293142D01*
X194712Y293059D01*
X195003Y293184D01*
X195212Y293476D01*
X195295Y293809D01*
X195212Y294142D01*
X195003Y294434D01*
X194712Y294559D01*
X194420Y294476D01*
X194212Y294267D01*
X194128Y294017D01*
Y293601D01*
X194003Y293226D01*
X193753Y292976D01*
X193462Y292892D01*
X193170Y292976D01*
X192962Y293184D01*
X192837Y293517D01*
X192795Y293809D01*
G01X193837Y296117D02*
X194128Y296409D01*
X194295Y296659D01*
X194378Y296992D01*
X194295Y297284D01*
X194128Y297492D01*
X193878Y297659D01*
X193587Y297701D01*
X193337Y297659D01*
X193087Y297492D01*
X192878Y297242D01*
X192795Y296951D01*
X192878Y296617D01*
X193128Y296326D01*
X193503Y296159D01*
X193920Y296117D01*
X194462Y296201D01*
X194753Y296326D01*
X195045Y296534D01*
X195253Y296826D01*
X195295Y297117D01*
X195212Y297409D01*
X195003Y297617D01*
G01X185795Y284509D02*
X183295D01*
G01X185795Y283551D02*
Y285467D01*
G01X183295Y286776D02*
X185795D01*
Y287776D01*
X185670Y288109D01*
X185378Y288359D01*
X185045Y288442D01*
X184712Y288359D01*
X184462Y288151D01*
X184337Y287776D01*
Y286776D01*
G01X183295Y290709D02*
X185795D01*
X185295Y290209D01*
G01X183295D02*
Y291209D01*
G01Y293809D02*
X183337Y294101D01*
X183462Y294434D01*
X183670Y294642D01*
X183962Y294726D01*
X184253Y294642D01*
X184503Y294392D01*
X184628Y294017D01*
Y293601D01*
X184712Y293351D01*
X184920Y293142D01*
X185212Y293059D01*
X185503Y293184D01*
X185712Y293476D01*
X185795Y293809D01*
X185712Y294142D01*
X185503Y294434D01*
X185212Y294559D01*
X184920Y294476D01*
X184712Y294267D01*
X184628Y294017D01*
Y293601D01*
X184503Y293226D01*
X184253Y292976D01*
X183962Y292892D01*
X183670Y292976D01*
X183462Y293184D01*
X183337Y293517D01*
X183295Y293809D01*
G01Y297409D02*
X185795D01*
X184003Y295867D01*
Y297951D01*
G01X199995Y329709D02*
Y327209D01*
G01X200953Y329709D02*
X199037D01*
G01X197728Y327209D02*
Y329709D01*
X196728D01*
X196395Y329584D01*
X196145Y329292D01*
X196062Y328959D01*
X196145Y328626D01*
X196353Y328376D01*
X196728Y328251D01*
X197728D01*
G01X193795Y327209D02*
Y329709D01*
X194295Y329209D01*
G01Y327209D02*
X193295D01*
G01X190695D02*
X190403Y327251D01*
X190070Y327376D01*
X189862Y327584D01*
X189778Y327876D01*
X189862Y328167D01*
X190112Y328417D01*
X190487Y328542D01*
X190903D01*
X191153Y328626D01*
X191362Y328834D01*
X191445Y329126D01*
X191320Y329417D01*
X191028Y329626D01*
X190695Y329709D01*
X190362Y329626D01*
X190070Y329417D01*
X189945Y329126D01*
X190028Y328834D01*
X190237Y328626D01*
X190487Y328542D01*
X190903D01*
X191278Y328417D01*
X191528Y328167D01*
X191612Y327876D01*
X191528Y327584D01*
X191320Y327376D01*
X190987Y327251D01*
X190695Y327209D01*
G01X187678D02*
X187595Y327751D01*
X187470Y328209D01*
X187303Y328626D01*
X187095Y329084D01*
X186762Y329709D01*
X188428D01*
G01X199995Y325209D02*
Y322709D01*
G01X200953Y325209D02*
X199037D01*
G01X197728Y322709D02*
Y325209D01*
X196728D01*
X196395Y325084D01*
X196145Y324792D01*
X196062Y324459D01*
X196145Y324126D01*
X196353Y323876D01*
X196728Y323751D01*
X197728D01*
G01X193795Y322709D02*
Y325209D01*
X194295Y324709D01*
G01Y322709D02*
X193295D01*
G01X190195D02*
Y325209D01*
X191737Y323417D01*
X189653D01*
G01X187595Y322709D02*
X187303Y322751D01*
X186970Y322876D01*
X186762Y323084D01*
X186678Y323376D01*
X186762Y323667D01*
X187012Y323917D01*
X187387Y324042D01*
X187803D01*
X188053Y324126D01*
X188262Y324334D01*
X188345Y324626D01*
X188220Y324917D01*
X187928Y325126D01*
X187595Y325209D01*
X187262Y325126D01*
X186970Y324917D01*
X186845Y324626D01*
X186928Y324334D01*
X187137Y324126D01*
X187387Y324042D01*
X187803D01*
X188178Y323917D01*
X188428Y323667D01*
X188512Y323376D01*
X188428Y323084D01*
X188220Y322876D01*
X187887Y322751D01*
X187595Y322709D01*
G01X217495Y325209D02*
Y322709D01*
G01X218453Y325209D02*
X216537D01*
G01X215228Y322709D02*
Y325209D01*
X214228D01*
X213895Y325084D01*
X213645Y324792D01*
X213562Y324459D01*
X213645Y324126D01*
X213853Y323876D01*
X214228Y323751D01*
X215228D01*
G01X211295Y322709D02*
Y325209D01*
X211795Y324709D01*
G01Y322709D02*
X210795D01*
G01X208195D02*
X207903Y322751D01*
X207570Y322876D01*
X207362Y323084D01*
X207278Y323376D01*
X207362Y323667D01*
X207612Y323917D01*
X207987Y324042D01*
X208403D01*
X208653Y324126D01*
X208862Y324334D01*
X208945Y324626D01*
X208820Y324917D01*
X208528Y325126D01*
X208195Y325209D01*
X207862Y325126D01*
X207570Y324917D01*
X207445Y324626D01*
X207528Y324334D01*
X207737Y324126D01*
X207987Y324042D01*
X208403D01*
X208778Y323917D01*
X209028Y323667D01*
X209112Y323376D01*
X209028Y323084D01*
X208820Y322876D01*
X208487Y322751D01*
X208195Y322709D01*
G01X205803Y323001D02*
X205512Y322792D01*
X205178Y322709D01*
X204845Y322792D01*
X204553Y323042D01*
X204345Y323417D01*
X204262Y323792D01*
Y324251D01*
X204345Y324626D01*
X204553Y324959D01*
X204803Y325126D01*
X205095Y325209D01*
X205428Y325126D01*
X205678Y324959D01*
X205845Y324709D01*
X205928Y324376D01*
X205845Y324084D01*
X205637Y323792D01*
X205387Y323626D01*
X205095Y323584D01*
X204762Y323667D01*
X204512Y323876D01*
X204262Y324251D01*
G01X232128Y295084D02*
X231920Y295417D01*
X231795Y295792D01*
Y296126D01*
X231920Y296459D01*
X232128Y296709D01*
X232420Y296834D01*
X232712Y296751D01*
X232962Y296542D01*
X233128Y296167D01*
X233212Y295667D01*
X233378Y295376D01*
X233670Y295251D01*
X233962Y295334D01*
X234170Y295542D01*
X234295Y295834D01*
Y296126D01*
X234212Y296417D01*
X234003Y296667D01*
G01X234087Y299976D02*
X234212Y299726D01*
X234295Y299434D01*
Y299101D01*
X234170Y298726D01*
X233962Y298434D01*
X233712Y298226D01*
X233295Y298059D01*
X232920Y298017D01*
X232545Y298101D01*
X232295Y298226D01*
X232045Y298476D01*
X231878Y298767D01*
X231795Y299059D01*
Y299351D01*
X231878Y299642D01*
X232003Y299892D01*
X232170Y300101D01*
G01X231795Y302159D02*
X234295D01*
X233795Y301659D01*
G01X231795D02*
Y302659D01*
G01X233878Y304467D02*
X234128Y304717D01*
X234253Y305009D01*
X234295Y305342D01*
X234212Y305759D01*
X234003Y306051D01*
X233753Y306134D01*
X233503Y306092D01*
X233295Y305926D01*
X232878Y305092D01*
X232587Y304717D01*
X232170Y304467D01*
X231795Y304384D01*
Y306134D01*
G01Y308359D02*
X231837Y308651D01*
X231962Y308984D01*
X232170Y309192D01*
X232462Y309276D01*
X232753Y309192D01*
X233003Y308942D01*
X233128Y308567D01*
Y308151D01*
X233212Y307901D01*
X233420Y307692D01*
X233712Y307609D01*
X234003Y307734D01*
X234212Y308026D01*
X234295Y308359D01*
X234212Y308692D01*
X234003Y308984D01*
X233712Y309109D01*
X233420Y309026D01*
X233212Y308817D01*
X233128Y308567D01*
Y308151D01*
X233003Y307776D01*
X232753Y307526D01*
X232462Y307442D01*
X232170Y307526D01*
X231962Y307734D01*
X231837Y308067D01*
X231795Y308359D01*
G01Y311459D02*
X234295D01*
X233795Y310959D01*
G01X231795D02*
Y311959D01*
G01X227628Y295084D02*
X227420Y295417D01*
X227295Y295792D01*
Y296126D01*
X227420Y296459D01*
X227628Y296709D01*
X227920Y296834D01*
X228212Y296751D01*
X228462Y296542D01*
X228628Y296167D01*
X228712Y295667D01*
X228878Y295376D01*
X229170Y295251D01*
X229462Y295334D01*
X229670Y295542D01*
X229795Y295834D01*
Y296126D01*
X229712Y296417D01*
X229503Y296667D01*
G01X229587Y299976D02*
X229712Y299726D01*
X229795Y299434D01*
Y299101D01*
X229670Y298726D01*
X229462Y298434D01*
X229212Y298226D01*
X228795Y298059D01*
X228420Y298017D01*
X228045Y298101D01*
X227795Y298226D01*
X227545Y298476D01*
X227378Y298767D01*
X227295Y299059D01*
Y299351D01*
X227378Y299642D01*
X227503Y299892D01*
X227670Y300101D01*
G01X227295Y302159D02*
X229795D01*
X229295Y301659D01*
G01X227295D02*
Y302659D01*
G01X229378Y304467D02*
X229628Y304717D01*
X229753Y305009D01*
X229795Y305342D01*
X229712Y305759D01*
X229503Y306051D01*
X229253Y306134D01*
X229003Y306092D01*
X228795Y305926D01*
X228378Y305092D01*
X228087Y304717D01*
X227670Y304467D01*
X227295Y304384D01*
Y306134D01*
G01Y308359D02*
X227337Y308651D01*
X227462Y308984D01*
X227670Y309192D01*
X227962Y309276D01*
X228253Y309192D01*
X228503Y308942D01*
X228628Y308567D01*
Y308151D01*
X228712Y307901D01*
X228920Y307692D01*
X229212Y307609D01*
X229503Y307734D01*
X229712Y308026D01*
X229795Y308359D01*
X229712Y308692D01*
X229503Y308984D01*
X229212Y309109D01*
X228920Y309026D01*
X228712Y308817D01*
X228628Y308567D01*
Y308151D01*
X228503Y307776D01*
X228253Y307526D01*
X227962Y307442D01*
X227670Y307526D01*
X227462Y307734D01*
X227337Y308067D01*
X227295Y308359D01*
G01X229795Y311459D02*
X229712Y311126D01*
X229503Y310876D01*
X229253Y310709D01*
X228920Y310584D01*
X228545Y310542D01*
X228170Y310584D01*
X227837Y310709D01*
X227587Y310876D01*
X227378Y311126D01*
X227295Y311459D01*
X227378Y311792D01*
X227587Y312042D01*
X227837Y312209D01*
X228170Y312334D01*
X228545Y312376D01*
X228920Y312334D01*
X229253Y312209D01*
X229503Y312042D01*
X229712Y311792D01*
X229795Y311459D01*
G01X223128Y295084D02*
X222920Y295417D01*
X222795Y295792D01*
Y296126D01*
X222920Y296459D01*
X223128Y296709D01*
X223420Y296834D01*
X223712Y296751D01*
X223962Y296542D01*
X224128Y296167D01*
X224212Y295667D01*
X224378Y295376D01*
X224670Y295251D01*
X224962Y295334D01*
X225170Y295542D01*
X225295Y295834D01*
Y296126D01*
X225212Y296417D01*
X225003Y296667D01*
G01X225087Y299976D02*
X225212Y299726D01*
X225295Y299434D01*
Y299101D01*
X225170Y298726D01*
X224962Y298434D01*
X224712Y298226D01*
X224295Y298059D01*
X223920Y298017D01*
X223545Y298101D01*
X223295Y298226D01*
X223045Y298476D01*
X222878Y298767D01*
X222795Y299059D01*
Y299351D01*
X222878Y299642D01*
X223003Y299892D01*
X223170Y300101D01*
G01X222795Y302159D02*
X225295D01*
X224795Y301659D01*
G01X222795D02*
Y302659D01*
G01X224878Y304467D02*
X225128Y304717D01*
X225253Y305009D01*
X225295Y305342D01*
X225212Y305759D01*
X225003Y306051D01*
X224753Y306134D01*
X224503Y306092D01*
X224295Y305926D01*
X223878Y305092D01*
X223587Y304717D01*
X223170Y304467D01*
X222795Y304384D01*
Y306134D01*
G01Y308276D02*
X223337Y308359D01*
X223795Y308484D01*
X224212Y308651D01*
X224670Y308859D01*
X225295Y309192D01*
Y307526D01*
G01X223087Y310751D02*
X222878Y311042D01*
X222795Y311376D01*
X222878Y311709D01*
X223128Y312001D01*
X223503Y312209D01*
X223878Y312292D01*
X224337D01*
X224712Y312209D01*
X225045Y312001D01*
X225212Y311751D01*
X225295Y311459D01*
X225212Y311126D01*
X225045Y310876D01*
X224795Y310709D01*
X224462Y310626D01*
X224170Y310709D01*
X223878Y310917D01*
X223712Y311167D01*
X223670Y311459D01*
X223753Y311792D01*
X223962Y312042D01*
X224337Y312292D01*
G01X218128Y295084D02*
X217920Y295417D01*
X217795Y295792D01*
Y296126D01*
X217920Y296459D01*
X218128Y296709D01*
X218420Y296834D01*
X218712Y296751D01*
X218962Y296542D01*
X219128Y296167D01*
X219212Y295667D01*
X219378Y295376D01*
X219670Y295251D01*
X219962Y295334D01*
X220170Y295542D01*
X220295Y295834D01*
Y296126D01*
X220212Y296417D01*
X220003Y296667D01*
G01X220087Y299976D02*
X220212Y299726D01*
X220295Y299434D01*
Y299101D01*
X220170Y298726D01*
X219962Y298434D01*
X219712Y298226D01*
X219295Y298059D01*
X218920Y298017D01*
X218545Y298101D01*
X218295Y298226D01*
X218045Y298476D01*
X217878Y298767D01*
X217795Y299059D01*
Y299351D01*
X217878Y299642D01*
X218003Y299892D01*
X218170Y300101D01*
G01X217795Y302159D02*
X220295D01*
X219795Y301659D01*
G01X217795D02*
Y302659D01*
G01X219878Y304467D02*
X220128Y304717D01*
X220253Y305009D01*
X220295Y305342D01*
X220212Y305759D01*
X220003Y306051D01*
X219753Y306134D01*
X219503Y306092D01*
X219295Y305926D01*
X218878Y305092D01*
X218587Y304717D01*
X218170Y304467D01*
X217795Y304384D01*
Y306134D01*
G01Y308276D02*
X218337Y308359D01*
X218795Y308484D01*
X219212Y308651D01*
X219670Y308859D01*
X220295Y309192D01*
Y307526D01*
G01X217795Y311459D02*
X217837Y311751D01*
X217962Y312084D01*
X218170Y312292D01*
X218462Y312376D01*
X218753Y312292D01*
X219003Y312042D01*
X219128Y311667D01*
Y311251D01*
X219212Y311001D01*
X219420Y310792D01*
X219712Y310709D01*
X220003Y310834D01*
X220212Y311126D01*
X220295Y311459D01*
X220212Y311792D01*
X220003Y312084D01*
X219712Y312209D01*
X219420Y312126D01*
X219212Y311917D01*
X219128Y311667D01*
Y311251D01*
X219003Y310876D01*
X218753Y310626D01*
X218462Y310542D01*
X218170Y310626D01*
X217962Y310834D01*
X217837Y311167D01*
X217795Y311459D01*
G01X270470Y971767D02*
X270595Y971517D01*
X270678Y971225D01*
Y970892D01*
X270553Y970517D01*
X270345Y970225D01*
X270095Y970017D01*
X269678Y969850D01*
X269303Y969808D01*
X268928Y969892D01*
X268678Y970017D01*
X268428Y970267D01*
X268261Y970558D01*
X268178Y970850D01*
Y971142D01*
X268261Y971433D01*
X268386Y971683D01*
X268553Y971892D01*
G01X270261Y973158D02*
X270511Y973408D01*
X270636Y973700D01*
X270678Y974033D01*
X270595Y974450D01*
X270386Y974742D01*
X270136Y974825D01*
X269886Y974783D01*
X269678Y974617D01*
X269261Y973783D01*
X268970Y973408D01*
X268553Y973158D01*
X268178Y973075D01*
Y974825D01*
G01X268470Y976342D02*
X268261Y976633D01*
X268178Y976967D01*
X268261Y977300D01*
X268511Y977592D01*
X268886Y977800D01*
X269261Y977883D01*
X269720D01*
X270095Y977800D01*
X270428Y977592D01*
X270595Y977342D01*
X270678Y977050D01*
X270595Y976717D01*
X270428Y976467D01*
X270178Y976300D01*
X269845Y976217D01*
X269553Y976300D01*
X269261Y976508D01*
X269095Y976758D01*
X269053Y977050D01*
X269136Y977383D01*
X269345Y977633D01*
X269720Y977883D01*
G01X268178Y980067D02*
X268720Y980150D01*
X269178Y980275D01*
X269595Y980442D01*
X270053Y980650D01*
X270678Y980983D01*
Y979317D01*
G01X274470Y971767D02*
X274595Y971517D01*
X274678Y971225D01*
Y970892D01*
X274553Y970517D01*
X274345Y970225D01*
X274095Y970017D01*
X273678Y969850D01*
X273303Y969808D01*
X272928Y969892D01*
X272678Y970017D01*
X272428Y970267D01*
X272261Y970558D01*
X272178Y970850D01*
Y971142D01*
X272261Y971433D01*
X272386Y971683D01*
X272553Y971892D01*
G01X274261Y973158D02*
X274511Y973408D01*
X274636Y973700D01*
X274678Y974033D01*
X274595Y974450D01*
X274386Y974742D01*
X274136Y974825D01*
X273886Y974783D01*
X273678Y974617D01*
X273261Y973783D01*
X272970Y973408D01*
X272553Y973158D01*
X272178Y973075D01*
Y974825D01*
G01X272470Y976342D02*
X272261Y976633D01*
X272178Y976967D01*
X272261Y977300D01*
X272511Y977592D01*
X272886Y977800D01*
X273261Y977883D01*
X273720D01*
X274095Y977800D01*
X274428Y977592D01*
X274595Y977342D01*
X274678Y977050D01*
X274595Y976717D01*
X274428Y976467D01*
X274178Y976300D01*
X273845Y976217D01*
X273553Y976300D01*
X273261Y976508D01*
X273095Y976758D01*
X273053Y977050D01*
X273136Y977383D01*
X273345Y977633D01*
X273720Y977883D01*
G01X272178Y980150D02*
X272220Y980442D01*
X272345Y980775D01*
X272553Y980983D01*
X272845Y981067D01*
X273136Y980983D01*
X273386Y980733D01*
X273511Y980358D01*
Y979942D01*
X273595Y979692D01*
X273803Y979483D01*
X274095Y979400D01*
X274386Y979525D01*
X274595Y979817D01*
X274678Y980150D01*
X274595Y980483D01*
X274386Y980775D01*
X274095Y980900D01*
X273803Y980817D01*
X273595Y980608D01*
X273511Y980358D01*
Y979942D01*
X273386Y979567D01*
X273136Y979317D01*
X272845Y979233D01*
X272553Y979317D01*
X272345Y979525D01*
X272220Y979858D01*
X272178Y980150D01*
G01X287833Y82975D02*
X287625Y83308D01*
X287500Y83683D01*
Y84017D01*
X287625Y84350D01*
X287833Y84600D01*
X288125Y84725D01*
X288417Y84642D01*
X288667Y84433D01*
X288833Y84058D01*
X288917Y83558D01*
X289083Y83267D01*
X289375Y83142D01*
X289667Y83225D01*
X289875Y83433D01*
X290000Y83725D01*
Y84017D01*
X289917Y84308D01*
X289708Y84558D01*
G01X287500Y86950D02*
X287542Y86617D01*
X287708Y86325D01*
X287958Y86075D01*
X288250Y85908D01*
X288583Y85825D01*
X288917D01*
X289250Y85908D01*
X289542Y86075D01*
X289792Y86325D01*
X289958Y86617D01*
X290000Y86950D01*
X289958Y87283D01*
X289792Y87575D01*
X289542Y87825D01*
X289250Y87992D01*
X288917Y88075D01*
X288583D01*
X288250Y87992D01*
X287958Y87825D01*
X287708Y87575D01*
X287542Y87283D01*
X287500Y86950D01*
G01X288167Y87283D02*
X287500Y87783D01*
G01Y90050D02*
X290000D01*
X289500Y89550D01*
G01X287500D02*
Y90550D01*
G01Y93150D02*
X287542Y93442D01*
X287667Y93775D01*
X287875Y93983D01*
X288167Y94067D01*
X288458Y93983D01*
X288708Y93733D01*
X288833Y93358D01*
Y92942D01*
X288917Y92692D01*
X289125Y92483D01*
X289417Y92400D01*
X289708Y92525D01*
X289917Y92817D01*
X290000Y93150D01*
X289917Y93483D01*
X289708Y93775D01*
X289417Y93900D01*
X289125Y93817D01*
X288917Y93608D01*
X288833Y93358D01*
Y92942D01*
X288708Y92567D01*
X288458Y92317D01*
X288167Y92233D01*
X287875Y92317D01*
X287667Y92525D01*
X287542Y92858D01*
X287500Y93150D01*
G01X296500Y81500D02*
Y94500D01*
G01X310500Y81500D02*
X296500D01*
G01X292333Y81425D02*
X292125Y81758D01*
X292000Y82133D01*
Y82467D01*
X292125Y82800D01*
X292333Y83050D01*
X292625Y83175D01*
X292917Y83092D01*
X293167Y82883D01*
X293333Y82508D01*
X293417Y82008D01*
X293583Y81717D01*
X293875Y81592D01*
X294167Y81675D01*
X294375Y81883D01*
X294500Y82175D01*
Y82467D01*
X294417Y82758D01*
X294208Y83008D01*
G01X292000Y84567D02*
X294500D01*
Y85608D01*
X294375Y85942D01*
X294208Y86150D01*
X293875Y86233D01*
X293542Y86150D01*
X293333Y85900D01*
X293208Y85608D01*
Y84567D01*
G01Y85608D02*
X292000Y86233D01*
G01X292292Y87792D02*
X292083Y88083D01*
X292000Y88417D01*
X292083Y88750D01*
X292333Y89042D01*
X292708Y89250D01*
X293083Y89333D01*
X293542D01*
X293917Y89250D01*
X294250Y89042D01*
X294417Y88792D01*
X294500Y88500D01*
X294417Y88167D01*
X294250Y87917D01*
X294000Y87750D01*
X293667Y87667D01*
X293375Y87750D01*
X293083Y87958D01*
X292917Y88208D01*
X292875Y88500D01*
X292958Y88833D01*
X293167Y89083D01*
X293542Y89333D01*
G01X292500Y90683D02*
X292208Y90933D01*
X292042Y91267D01*
X292000Y91642D01*
X292042Y91975D01*
X292250Y92308D01*
X292500Y92517D01*
X292750Y92558D01*
X293042Y92475D01*
X293250Y92183D01*
X293333Y91892D01*
Y91517D01*
G01Y91892D02*
X293458Y92142D01*
X293667Y92350D01*
X293917Y92433D01*
X294167Y92350D01*
X294375Y92142D01*
X294500Y91767D01*
X294458Y91392D01*
X294292Y91017D01*
G01X294083Y93908D02*
X294333Y94158D01*
X294458Y94450D01*
X294500Y94783D01*
X294417Y95200D01*
X294208Y95492D01*
X293958Y95575D01*
X293708Y95533D01*
X293500Y95367D01*
X293083Y94533D01*
X292792Y94158D01*
X292375Y93908D01*
X292000Y93825D01*
Y95575D01*
G01X296500Y94500D02*
X310500D01*
G01X302075Y102333D02*
X301742Y102125D01*
X301367Y102000D01*
X301033D01*
X300700Y102125D01*
X300450Y102333D01*
X300325Y102625D01*
X300408Y102917D01*
X300617Y103167D01*
X300992Y103333D01*
X301492Y103417D01*
X301783Y103583D01*
X301908Y103875D01*
X301825Y104167D01*
X301617Y104375D01*
X301325Y104500D01*
X301033D01*
X300742Y104417D01*
X300492Y104208D01*
G01X298933Y102000D02*
Y104500D01*
X297892D01*
X297558Y104375D01*
X297350Y104208D01*
X297267Y103875D01*
X297350Y103542D01*
X297600Y103333D01*
X297892Y103208D01*
X298933D01*
G01X297892D02*
X297267Y102000D01*
G01X295708Y102292D02*
X295417Y102083D01*
X295083Y102000D01*
X294750Y102083D01*
X294458Y102333D01*
X294250Y102708D01*
X294167Y103083D01*
Y103542D01*
X294250Y103917D01*
X294458Y104250D01*
X294708Y104417D01*
X295000Y104500D01*
X295333Y104417D01*
X295583Y104250D01*
X295750Y104000D01*
X295833Y103667D01*
X295750Y103375D01*
X295542Y103083D01*
X295292Y102917D01*
X295000Y102875D01*
X294667Y102958D01*
X294417Y103167D01*
X294167Y103542D01*
G01X292817Y102500D02*
X292567Y102208D01*
X292233Y102042D01*
X291858Y102000D01*
X291525Y102042D01*
X291192Y102250D01*
X290983Y102500D01*
X290942Y102750D01*
X291025Y103042D01*
X291317Y103250D01*
X291608Y103333D01*
X291983D01*
G01X291608D02*
X291358Y103458D01*
X291150Y103667D01*
X291067Y103917D01*
X291150Y104167D01*
X291358Y104375D01*
X291733Y104500D01*
X292108Y104458D01*
X292483Y104292D01*
G01X288800Y102000D02*
Y104500D01*
X289300Y104000D01*
G01Y102000D02*
X288300D01*
G01X303200Y100500D02*
Y96500D01*
X295800D01*
G01X296004Y187333D02*
X295671Y187125D01*
X295296Y187000D01*
X294962D01*
X294629Y187125D01*
X294379Y187333D01*
X294254Y187625D01*
X294337Y187917D01*
X294546Y188167D01*
X294921Y188333D01*
X295421Y188417D01*
X295712Y188583D01*
X295837Y188875D01*
X295754Y189167D01*
X295546Y189375D01*
X295254Y189500D01*
X294962D01*
X294671Y189417D01*
X294421Y189208D01*
G01X292862Y187000D02*
Y189500D01*
X291821D01*
X291487Y189375D01*
X291279Y189208D01*
X291196Y188875D01*
X291279Y188542D01*
X291529Y188333D01*
X291821Y188208D01*
X292862D01*
G01X291821D02*
X291196Y187000D01*
G01X289721Y188042D02*
X289429Y188333D01*
X289179Y188500D01*
X288846Y188583D01*
X288554Y188500D01*
X288346Y188333D01*
X288179Y188083D01*
X288137Y187792D01*
X288179Y187542D01*
X288346Y187292D01*
X288596Y187083D01*
X288887Y187000D01*
X289221Y187083D01*
X289512Y187333D01*
X289679Y187708D01*
X289721Y188125D01*
X289637Y188667D01*
X289512Y188958D01*
X289304Y189250D01*
X289012Y189458D01*
X288721Y189500D01*
X288429Y189417D01*
X288221Y189208D01*
G01X286621Y189083D02*
X286371Y189333D01*
X286079Y189458D01*
X285746Y189500D01*
X285329Y189417D01*
X285037Y189208D01*
X284954Y188958D01*
X284996Y188708D01*
X285162Y188500D01*
X285996Y188083D01*
X286371Y187792D01*
X286621Y187375D01*
X286704Y187000D01*
X284954D01*
G01X282812D02*
X282729Y187542D01*
X282604Y188000D01*
X282437Y188417D01*
X282229Y188875D01*
X281896Y189500D01*
X283562D01*
G01X296115Y191333D02*
X295782Y191125D01*
X295407Y191000D01*
X295073D01*
X294740Y191125D01*
X294490Y191333D01*
X294365Y191625D01*
X294448Y191917D01*
X294657Y192167D01*
X295032Y192333D01*
X295532Y192417D01*
X295823Y192583D01*
X295948Y192875D01*
X295865Y193167D01*
X295657Y193375D01*
X295365Y193500D01*
X295073D01*
X294782Y193417D01*
X294532Y193208D01*
G01X292973Y191000D02*
Y193500D01*
X291932D01*
X291598Y193375D01*
X291390Y193208D01*
X291307Y192875D01*
X291390Y192542D01*
X291640Y192333D01*
X291932Y192208D01*
X292973D01*
G01X291932D02*
X291307Y191000D01*
G01X289832Y192042D02*
X289540Y192333D01*
X289290Y192500D01*
X288957Y192583D01*
X288665Y192500D01*
X288457Y192333D01*
X288290Y192083D01*
X288248Y191792D01*
X288290Y191542D01*
X288457Y191292D01*
X288707Y191083D01*
X288998Y191000D01*
X289332Y191083D01*
X289623Y191333D01*
X289790Y191708D01*
X289832Y192125D01*
X289748Y192667D01*
X289623Y192958D01*
X289415Y193250D01*
X289123Y193458D01*
X288832Y193500D01*
X288540Y193417D01*
X288332Y193208D01*
G01X286732Y193083D02*
X286482Y193333D01*
X286190Y193458D01*
X285857Y193500D01*
X285440Y193417D01*
X285148Y193208D01*
X285065Y192958D01*
X285107Y192708D01*
X285273Y192500D01*
X286107Y192083D01*
X286482Y191792D01*
X286732Y191375D01*
X286815Y191000D01*
X285065D01*
G01X283632Y192042D02*
X283340Y192333D01*
X283090Y192500D01*
X282757Y192583D01*
X282465Y192500D01*
X282257Y192333D01*
X282090Y192083D01*
X282048Y191792D01*
X282090Y191542D01*
X282257Y191292D01*
X282507Y191083D01*
X282798Y191000D01*
X283132Y191083D01*
X283423Y191333D01*
X283590Y191708D01*
X283632Y192125D01*
X283548Y192667D01*
X283423Y192958D01*
X283215Y193250D01*
X282923Y193458D01*
X282632Y193500D01*
X282340Y193417D01*
X282132Y193208D01*
G01X296115Y195833D02*
X295782Y195625D01*
X295407Y195500D01*
X295073D01*
X294740Y195625D01*
X294490Y195833D01*
X294365Y196125D01*
X294448Y196417D01*
X294657Y196667D01*
X295032Y196833D01*
X295532Y196917D01*
X295823Y197083D01*
X295948Y197375D01*
X295865Y197667D01*
X295657Y197875D01*
X295365Y198000D01*
X295073D01*
X294782Y197917D01*
X294532Y197708D01*
G01X292973Y195500D02*
Y198000D01*
X291932D01*
X291598Y197875D01*
X291390Y197708D01*
X291307Y197375D01*
X291390Y197042D01*
X291640Y196833D01*
X291932Y196708D01*
X292973D01*
G01X291932D02*
X291307Y195500D01*
G01X289832Y196542D02*
X289540Y196833D01*
X289290Y197000D01*
X288957Y197083D01*
X288665Y197000D01*
X288457Y196833D01*
X288290Y196583D01*
X288248Y196292D01*
X288290Y196042D01*
X288457Y195792D01*
X288707Y195583D01*
X288998Y195500D01*
X289332Y195583D01*
X289623Y195833D01*
X289790Y196208D01*
X289832Y196625D01*
X289748Y197167D01*
X289623Y197458D01*
X289415Y197750D01*
X289123Y197958D01*
X288832Y198000D01*
X288540Y197917D01*
X288332Y197708D01*
G01X286857Y196000D02*
X286607Y195708D01*
X286273Y195542D01*
X285898Y195500D01*
X285565Y195542D01*
X285232Y195750D01*
X285023Y196000D01*
X284982Y196250D01*
X285065Y196542D01*
X285357Y196750D01*
X285648Y196833D01*
X286023D01*
G01X285648D02*
X285398Y196958D01*
X285190Y197167D01*
X285107Y197417D01*
X285190Y197667D01*
X285398Y197875D01*
X285773Y198000D01*
X286148Y197958D01*
X286523Y197792D01*
G01X283632Y197583D02*
X283382Y197833D01*
X283090Y197958D01*
X282757Y198000D01*
X282340Y197917D01*
X282048Y197708D01*
X281965Y197458D01*
X282007Y197208D01*
X282173Y197000D01*
X283007Y196583D01*
X283382Y196292D01*
X283632Y195875D01*
X283715Y195500D01*
X281965D01*
G01X296004Y199833D02*
X295671Y199625D01*
X295296Y199500D01*
X294962D01*
X294629Y199625D01*
X294379Y199833D01*
X294254Y200125D01*
X294337Y200417D01*
X294546Y200667D01*
X294921Y200833D01*
X295421Y200917D01*
X295712Y201083D01*
X295837Y201375D01*
X295754Y201667D01*
X295546Y201875D01*
X295254Y202000D01*
X294962D01*
X294671Y201917D01*
X294421Y201708D01*
G01X291112Y201792D02*
X291362Y201917D01*
X291654Y202000D01*
X291987D01*
X292362Y201875D01*
X292654Y201667D01*
X292862Y201417D01*
X293029Y201000D01*
X293071Y200625D01*
X292987Y200250D01*
X292862Y200000D01*
X292612Y199750D01*
X292321Y199583D01*
X292029Y199500D01*
X291737D01*
X291446Y199583D01*
X291196Y199708D01*
X290987Y199875D01*
G01X289637Y199792D02*
X289346Y199583D01*
X289012Y199500D01*
X288679Y199583D01*
X288387Y199833D01*
X288179Y200208D01*
X288096Y200583D01*
Y201042D01*
X288179Y201417D01*
X288387Y201750D01*
X288637Y201917D01*
X288929Y202000D01*
X289262Y201917D01*
X289512Y201750D01*
X289679Y201500D01*
X289762Y201167D01*
X289679Y200875D01*
X289471Y200583D01*
X289221Y200417D01*
X288929Y200375D01*
X288596Y200458D01*
X288346Y200667D01*
X288096Y201042D01*
G01X286621Y200542D02*
X286329Y200833D01*
X286079Y201000D01*
X285746Y201083D01*
X285454Y201000D01*
X285246Y200833D01*
X285079Y200583D01*
X285037Y200292D01*
X285079Y200042D01*
X285246Y199792D01*
X285496Y199583D01*
X285787Y199500D01*
X286121Y199583D01*
X286412Y199833D01*
X286579Y200208D01*
X286621Y200625D01*
X286537Y201167D01*
X286412Y201458D01*
X286204Y201750D01*
X285912Y201958D01*
X285621Y202000D01*
X285329Y201917D01*
X285121Y201708D01*
G01X283437Y199792D02*
X283146Y199583D01*
X282812Y199500D01*
X282479Y199583D01*
X282187Y199833D01*
X281979Y200208D01*
X281896Y200583D01*
Y201042D01*
X281979Y201417D01*
X282187Y201750D01*
X282437Y201917D01*
X282729Y202000D01*
X283062Y201917D01*
X283312Y201750D01*
X283479Y201500D01*
X283562Y201167D01*
X283479Y200875D01*
X283271Y200583D01*
X283021Y200417D01*
X282729Y200375D01*
X282396Y200458D01*
X282146Y200667D01*
X281896Y201042D01*
G01X301504Y218833D02*
X301171Y218625D01*
X300796Y218500D01*
X300462D01*
X300129Y218625D01*
X299879Y218833D01*
X299754Y219125D01*
X299837Y219417D01*
X300046Y219667D01*
X300421Y219833D01*
X300921Y219917D01*
X301212Y220083D01*
X301337Y220375D01*
X301254Y220667D01*
X301046Y220875D01*
X300754Y221000D01*
X300462D01*
X300171Y220917D01*
X299921Y220708D01*
G01X296612Y220792D02*
X296862Y220917D01*
X297154Y221000D01*
X297487D01*
X297862Y220875D01*
X298154Y220667D01*
X298362Y220417D01*
X298529Y220000D01*
X298571Y219625D01*
X298487Y219250D01*
X298362Y219000D01*
X298112Y218750D01*
X297821Y218583D01*
X297529Y218500D01*
X297237D01*
X296946Y218583D01*
X296696Y218708D01*
X296487Y218875D01*
G01X295137Y218792D02*
X294846Y218583D01*
X294512Y218500D01*
X294179Y218583D01*
X293887Y218833D01*
X293679Y219208D01*
X293596Y219583D01*
Y220042D01*
X293679Y220417D01*
X293887Y220750D01*
X294137Y220917D01*
X294429Y221000D01*
X294762Y220917D01*
X295012Y220750D01*
X295179Y220500D01*
X295262Y220167D01*
X295179Y219875D01*
X294971Y219583D01*
X294721Y219417D01*
X294429Y219375D01*
X294096Y219458D01*
X293846Y219667D01*
X293596Y220042D01*
G01X292121Y220583D02*
X291871Y220833D01*
X291579Y220958D01*
X291246Y221000D01*
X290829Y220917D01*
X290537Y220708D01*
X290454Y220458D01*
X290496Y220208D01*
X290662Y220000D01*
X291496Y219583D01*
X291871Y219292D01*
X292121Y218875D01*
X292204Y218500D01*
X290454D01*
G01X289146Y218875D02*
X288896Y218667D01*
X288604Y218542D01*
X288229Y218500D01*
X287854Y218583D01*
X287562Y218750D01*
X287354Y219042D01*
X287312Y219375D01*
X287396Y219708D01*
X287604Y219917D01*
X287896Y220083D01*
X288187Y220125D01*
X288479Y220083D01*
X288854Y219917D01*
X288729Y221000D01*
X287604D01*
G01X301504Y214333D02*
X301171Y214125D01*
X300796Y214000D01*
X300462D01*
X300129Y214125D01*
X299879Y214333D01*
X299754Y214625D01*
X299837Y214917D01*
X300046Y215167D01*
X300421Y215333D01*
X300921Y215417D01*
X301212Y215583D01*
X301337Y215875D01*
X301254Y216167D01*
X301046Y216375D01*
X300754Y216500D01*
X300462D01*
X300171Y216417D01*
X299921Y216208D01*
G01X296612Y216292D02*
X296862Y216417D01*
X297154Y216500D01*
X297487D01*
X297862Y216375D01*
X298154Y216167D01*
X298362Y215917D01*
X298529Y215500D01*
X298571Y215125D01*
X298487Y214750D01*
X298362Y214500D01*
X298112Y214250D01*
X297821Y214083D01*
X297529Y214000D01*
X297237D01*
X296946Y214083D01*
X296696Y214208D01*
X296487Y214375D01*
G01X295137Y214292D02*
X294846Y214083D01*
X294512Y214000D01*
X294179Y214083D01*
X293887Y214333D01*
X293679Y214708D01*
X293596Y215083D01*
Y215542D01*
X293679Y215917D01*
X293887Y216250D01*
X294137Y216417D01*
X294429Y216500D01*
X294762Y216417D01*
X295012Y216250D01*
X295179Y216000D01*
X295262Y215667D01*
X295179Y215375D01*
X294971Y215083D01*
X294721Y214917D01*
X294429Y214875D01*
X294096Y214958D01*
X293846Y215167D01*
X293596Y215542D01*
G01X292121Y216083D02*
X291871Y216333D01*
X291579Y216458D01*
X291246Y216500D01*
X290829Y216417D01*
X290537Y216208D01*
X290454Y215958D01*
X290496Y215708D01*
X290662Y215500D01*
X291496Y215083D01*
X291871Y214792D01*
X292121Y214375D01*
X292204Y214000D01*
X290454D01*
G01X289021Y215042D02*
X288729Y215333D01*
X288479Y215500D01*
X288146Y215583D01*
X287854Y215500D01*
X287646Y215333D01*
X287479Y215083D01*
X287437Y214792D01*
X287479Y214542D01*
X287646Y214292D01*
X287896Y214083D01*
X288187Y214000D01*
X288521Y214083D01*
X288812Y214333D01*
X288979Y214708D01*
X289021Y215125D01*
X288937Y215667D01*
X288812Y215958D01*
X288604Y216250D01*
X288312Y216458D01*
X288021Y216500D01*
X287729Y216417D01*
X287521Y216208D01*
G01X301528Y236185D02*
X301195Y235977D01*
X300820Y235852D01*
X300486D01*
X300153Y235977D01*
X299903Y236185D01*
X299778Y236477D01*
X299861Y236769D01*
X300070Y237019D01*
X300445Y237185D01*
X300945Y237269D01*
X301236Y237435D01*
X301361Y237727D01*
X301278Y238019D01*
X301070Y238227D01*
X300778Y238352D01*
X300486D01*
X300195Y238269D01*
X299945Y238060D01*
G01X296636Y238144D02*
X296886Y238269D01*
X297178Y238352D01*
X297511D01*
X297886Y238227D01*
X298178Y238019D01*
X298386Y237769D01*
X298553Y237352D01*
X298595Y236977D01*
X298511Y236602D01*
X298386Y236352D01*
X298136Y236102D01*
X297845Y235935D01*
X297553Y235852D01*
X297261D01*
X296970Y235935D01*
X296720Y236060D01*
X296511Y236227D01*
G01X295161Y236144D02*
X294870Y235935D01*
X294536Y235852D01*
X294203Y235935D01*
X293911Y236185D01*
X293703Y236560D01*
X293620Y236935D01*
Y237394D01*
X293703Y237769D01*
X293911Y238102D01*
X294161Y238269D01*
X294453Y238352D01*
X294786Y238269D01*
X295036Y238102D01*
X295203Y237852D01*
X295286Y237519D01*
X295203Y237227D01*
X294995Y236935D01*
X294745Y236769D01*
X294453Y236727D01*
X294120Y236810D01*
X293870Y237019D01*
X293620Y237394D01*
G01X292145Y237935D02*
X291895Y238185D01*
X291603Y238310D01*
X291270Y238352D01*
X290853Y238269D01*
X290561Y238060D01*
X290478Y237810D01*
X290520Y237560D01*
X290686Y237352D01*
X291520Y236935D01*
X291895Y236644D01*
X292145Y236227D01*
X292228Y235852D01*
X290478D01*
G01X289170Y236352D02*
X288920Y236060D01*
X288586Y235894D01*
X288211Y235852D01*
X287878Y235894D01*
X287545Y236102D01*
X287336Y236352D01*
X287295Y236602D01*
X287378Y236894D01*
X287670Y237102D01*
X287961Y237185D01*
X288336D01*
G01X287961D02*
X287711Y237310D01*
X287503Y237519D01*
X287420Y237769D01*
X287503Y238019D01*
X287711Y238227D01*
X288086Y238352D01*
X288461Y238310D01*
X288836Y238144D01*
G01X301528Y228185D02*
X301195Y227977D01*
X300820Y227852D01*
X300486D01*
X300153Y227977D01*
X299903Y228185D01*
X299778Y228477D01*
X299861Y228769D01*
X300070Y229019D01*
X300445Y229185D01*
X300945Y229269D01*
X301236Y229435D01*
X301361Y229727D01*
X301278Y230019D01*
X301070Y230227D01*
X300778Y230352D01*
X300486D01*
X300195Y230269D01*
X299945Y230060D01*
G01X296636Y230144D02*
X296886Y230269D01*
X297178Y230352D01*
X297511D01*
X297886Y230227D01*
X298178Y230019D01*
X298386Y229769D01*
X298553Y229352D01*
X298595Y228977D01*
X298511Y228602D01*
X298386Y228352D01*
X298136Y228102D01*
X297845Y227935D01*
X297553Y227852D01*
X297261D01*
X296970Y227935D01*
X296720Y228060D01*
X296511Y228227D01*
G01X295161Y228144D02*
X294870Y227935D01*
X294536Y227852D01*
X294203Y227935D01*
X293911Y228185D01*
X293703Y228560D01*
X293620Y228935D01*
Y229394D01*
X293703Y229769D01*
X293911Y230102D01*
X294161Y230269D01*
X294453Y230352D01*
X294786Y230269D01*
X295036Y230102D01*
X295203Y229852D01*
X295286Y229519D01*
X295203Y229227D01*
X294995Y228935D01*
X294745Y228769D01*
X294453Y228727D01*
X294120Y228810D01*
X293870Y229019D01*
X293620Y229394D01*
G01X292145Y229935D02*
X291895Y230185D01*
X291603Y230310D01*
X291270Y230352D01*
X290853Y230269D01*
X290561Y230060D01*
X290478Y229810D01*
X290520Y229560D01*
X290686Y229352D01*
X291520Y228935D01*
X291895Y228644D01*
X292145Y228227D01*
X292228Y227852D01*
X290478D01*
G01X287753D02*
Y230352D01*
X289295Y228560D01*
X287211D01*
G01X312500Y53467D02*
X315000D01*
Y54467D01*
X314875Y54800D01*
X314583Y55050D01*
X314250Y55133D01*
X313917Y55050D01*
X313667Y54842D01*
X313542Y54467D01*
Y53467D01*
G01X314792Y58317D02*
X314917Y58067D01*
X315000Y57775D01*
Y57442D01*
X314875Y57067D01*
X314667Y56775D01*
X314417Y56567D01*
X314000Y56400D01*
X313625Y56358D01*
X313250Y56442D01*
X313000Y56567D01*
X312750Y56817D01*
X312583Y57108D01*
X312500Y57400D01*
Y57692D01*
X312583Y57983D01*
X312708Y58233D01*
X312875Y58442D01*
G01X314583Y59708D02*
X314833Y59958D01*
X314958Y60250D01*
X315000Y60583D01*
X314917Y61000D01*
X314708Y61292D01*
X314458Y61375D01*
X314208Y61333D01*
X314000Y61167D01*
X313583Y60333D01*
X313292Y59958D01*
X312875Y59708D01*
X312500Y59625D01*
Y61375D01*
G01Y63600D02*
X315000D01*
X314500Y63100D01*
G01X312500D02*
Y64100D01*
G01X313000Y65783D02*
X312708Y66033D01*
X312542Y66367D01*
X312500Y66742D01*
X312542Y67075D01*
X312750Y67408D01*
X313000Y67617D01*
X313250Y67658D01*
X313542Y67575D01*
X313750Y67283D01*
X313833Y66992D01*
Y66617D01*
G01Y66992D02*
X313958Y67242D01*
X314167Y67450D01*
X314417Y67533D01*
X314667Y67450D01*
X314875Y67242D01*
X315000Y66867D01*
X314958Y66492D01*
X314792Y66117D01*
G01X310500Y94500D02*
Y81500D01*
G01X318575Y106333D02*
X318242Y106125D01*
X317867Y106000D01*
X317533D01*
X317200Y106125D01*
X316950Y106333D01*
X316825Y106625D01*
X316908Y106917D01*
X317117Y107167D01*
X317492Y107333D01*
X317992Y107417D01*
X318283Y107583D01*
X318408Y107875D01*
X318325Y108167D01*
X318117Y108375D01*
X317825Y108500D01*
X317533D01*
X317242Y108417D01*
X316992Y108208D01*
G01X315433Y106000D02*
Y108500D01*
X314392D01*
X314058Y108375D01*
X313850Y108208D01*
X313767Y107875D01*
X313850Y107542D01*
X314100Y107333D01*
X314392Y107208D01*
X315433D01*
G01X314392D02*
X313767Y106000D01*
G01X312208Y106292D02*
X311917Y106083D01*
X311583Y106000D01*
X311250Y106083D01*
X310958Y106333D01*
X310750Y106708D01*
X310667Y107083D01*
Y107542D01*
X310750Y107917D01*
X310958Y108250D01*
X311208Y108417D01*
X311500Y108500D01*
X311833Y108417D01*
X312083Y108250D01*
X312250Y108000D01*
X312333Y107667D01*
X312250Y107375D01*
X312042Y107083D01*
X311792Y106917D01*
X311500Y106875D01*
X311167Y106958D01*
X310917Y107167D01*
X310667Y107542D01*
G01X309317Y106500D02*
X309067Y106208D01*
X308733Y106042D01*
X308358Y106000D01*
X308025Y106042D01*
X307692Y106250D01*
X307483Y106500D01*
X307442Y106750D01*
X307525Y107042D01*
X307817Y107250D01*
X308108Y107333D01*
X308483D01*
G01X308108D02*
X307858Y107458D01*
X307650Y107667D01*
X307567Y107917D01*
X307650Y108167D01*
X307858Y108375D01*
X308233Y108500D01*
X308608Y108458D01*
X308983Y108292D01*
G01X305300Y108500D02*
X305633Y108417D01*
X305883Y108208D01*
X306050Y107958D01*
X306175Y107625D01*
X306217Y107250D01*
X306175Y106875D01*
X306050Y106542D01*
X305883Y106292D01*
X305633Y106083D01*
X305300Y106000D01*
X304967Y106083D01*
X304717Y106292D01*
X304550Y106542D01*
X304425Y106875D01*
X304383Y107250D01*
X304425Y107625D01*
X304550Y107958D01*
X304717Y108208D01*
X304967Y108417D01*
X305300Y108500D01*
G01X311200Y100500D02*
Y96500D01*
X303800D01*
G01X311000Y94700D02*
X315000D01*
Y87300D01*
G01X310154Y187033D02*
X309821Y186825D01*
X309446Y186700D01*
X309112D01*
X308779Y186825D01*
X308529Y187033D01*
X308404Y187325D01*
X308487Y187617D01*
X308696Y187867D01*
X309071Y188033D01*
X309571Y188117D01*
X309862Y188283D01*
X309987Y188575D01*
X309904Y188867D01*
X309696Y189075D01*
X309404Y189200D01*
X309112D01*
X308821Y189117D01*
X308571Y188908D01*
G01X306179Y189200D02*
Y186700D01*
G01X307137Y189200D02*
X305221D01*
G01X303912Y186700D02*
Y189200D01*
X302912D01*
X302579Y189075D01*
X302329Y188783D01*
X302246Y188450D01*
X302329Y188117D01*
X302537Y187867D01*
X302912Y187742D01*
X303912D01*
G01X300896Y187200D02*
X300646Y186908D01*
X300312Y186742D01*
X299937Y186700D01*
X299604Y186742D01*
X299271Y186950D01*
X299062Y187200D01*
X299021Y187450D01*
X299104Y187742D01*
X299396Y187950D01*
X299687Y188033D01*
X300062D01*
G01X299687D02*
X299437Y188158D01*
X299229Y188367D01*
X299146Y188617D01*
X299229Y188867D01*
X299437Y189075D01*
X299812Y189200D01*
X300187Y189158D01*
X300562Y188992D01*
G01X322004Y173833D02*
X321671Y173625D01*
X321296Y173500D01*
X320962D01*
X320629Y173625D01*
X320379Y173833D01*
X320254Y174125D01*
X320337Y174417D01*
X320546Y174667D01*
X320921Y174833D01*
X321421Y174917D01*
X321712Y175083D01*
X321837Y175375D01*
X321754Y175667D01*
X321546Y175875D01*
X321254Y176000D01*
X320962D01*
X320671Y175917D01*
X320421Y175708D01*
G01X318029Y176000D02*
Y173500D01*
G01X318987Y176000D02*
X317071D01*
G01X315762Y173500D02*
Y176000D01*
X314762D01*
X314429Y175875D01*
X314179Y175583D01*
X314096Y175250D01*
X314179Y174917D01*
X314387Y174667D01*
X314762Y174542D01*
X315762D01*
G01X311329Y173500D02*
Y176000D01*
X312871Y174208D01*
X310787D01*
G01X309437Y173792D02*
X309146Y173583D01*
X308812Y173500D01*
X308479Y173583D01*
X308187Y173833D01*
X307979Y174208D01*
X307896Y174583D01*
Y175042D01*
X307979Y175417D01*
X308187Y175750D01*
X308437Y175917D01*
X308729Y176000D01*
X309062Y175917D01*
X309312Y175750D01*
X309479Y175500D01*
X309562Y175167D01*
X309479Y174875D01*
X309271Y174583D01*
X309021Y174417D01*
X308729Y174375D01*
X308396Y174458D01*
X308146Y174667D01*
X307896Y175042D01*
G01X311954Y182833D02*
X311621Y182625D01*
X311246Y182500D01*
X310912D01*
X310579Y182625D01*
X310329Y182833D01*
X310204Y183125D01*
X310287Y183417D01*
X310496Y183667D01*
X310871Y183833D01*
X311371Y183917D01*
X311662Y184083D01*
X311787Y184375D01*
X311704Y184667D01*
X311496Y184875D01*
X311204Y185000D01*
X310912D01*
X310621Y184917D01*
X310371Y184708D01*
G01X307979Y185000D02*
Y182500D01*
G01X308937Y185000D02*
X307021D01*
G01X305712Y182500D02*
Y185000D01*
X304712D01*
X304379Y184875D01*
X304129Y184583D01*
X304046Y184250D01*
X304129Y183917D01*
X304337Y183667D01*
X304712Y183542D01*
X305712D01*
G01X302696Y182875D02*
X302446Y182667D01*
X302154Y182542D01*
X301779Y182500D01*
X301404Y182583D01*
X301112Y182750D01*
X300904Y183042D01*
X300862Y183375D01*
X300946Y183708D01*
X301154Y183917D01*
X301446Y184083D01*
X301737Y184125D01*
X302029Y184083D01*
X302404Y183917D01*
X302279Y185000D01*
X301154D01*
G01X312504Y178333D02*
X312171Y178125D01*
X311796Y178000D01*
X311462D01*
X311129Y178125D01*
X310879Y178333D01*
X310754Y178625D01*
X310837Y178917D01*
X311046Y179167D01*
X311421Y179333D01*
X311921Y179417D01*
X312212Y179583D01*
X312337Y179875D01*
X312254Y180167D01*
X312046Y180375D01*
X311754Y180500D01*
X311462D01*
X311171Y180417D01*
X310921Y180208D01*
G01X309362Y178000D02*
Y180500D01*
X308321D01*
X307987Y180375D01*
X307779Y180208D01*
X307696Y179875D01*
X307779Y179542D01*
X308029Y179333D01*
X308321Y179208D01*
X309362D01*
G01X308321D02*
X307696Y178000D01*
G01X306221Y179042D02*
X305929Y179333D01*
X305679Y179500D01*
X305346Y179583D01*
X305054Y179500D01*
X304846Y179333D01*
X304679Y179083D01*
X304637Y178792D01*
X304679Y178542D01*
X304846Y178292D01*
X305096Y178083D01*
X305387Y178000D01*
X305721Y178083D01*
X306012Y178333D01*
X306179Y178708D01*
X306221Y179125D01*
X306137Y179667D01*
X306012Y179958D01*
X305804Y180250D01*
X305512Y180458D01*
X305221Y180500D01*
X304929Y180417D01*
X304721Y180208D01*
G01X302329Y180500D02*
X302662Y180417D01*
X302912Y180208D01*
X303079Y179958D01*
X303204Y179625D01*
X303246Y179250D01*
X303204Y178875D01*
X303079Y178542D01*
X302912Y178292D01*
X302662Y178083D01*
X302329Y178000D01*
X301996Y178083D01*
X301746Y178292D01*
X301579Y178542D01*
X301454Y178875D01*
X301412Y179250D01*
X301454Y179625D01*
X301579Y179958D01*
X301746Y180208D01*
X301996Y180417D01*
X302329Y180500D01*
G01X300146Y178375D02*
X299896Y178167D01*
X299604Y178042D01*
X299229Y178000D01*
X298854Y178083D01*
X298562Y178250D01*
X298354Y178542D01*
X298312Y178875D01*
X298396Y179208D01*
X298604Y179417D01*
X298896Y179583D01*
X299187Y179625D01*
X299479Y179583D01*
X299854Y179417D01*
X299729Y180500D01*
X298604D01*
G01X312504Y200333D02*
X312171Y200125D01*
X311796Y200000D01*
X311462D01*
X311129Y200125D01*
X310879Y200333D01*
X310754Y200625D01*
X310837Y200917D01*
X311046Y201167D01*
X311421Y201333D01*
X311921Y201417D01*
X312212Y201583D01*
X312337Y201875D01*
X312254Y202167D01*
X312046Y202375D01*
X311754Y202500D01*
X311462D01*
X311171Y202417D01*
X310921Y202208D01*
G01X308529Y202500D02*
Y200000D01*
G01X309487Y202500D02*
X307571D01*
G01X306262Y200000D02*
Y202500D01*
X305262D01*
X304929Y202375D01*
X304679Y202083D01*
X304596Y201750D01*
X304679Y201417D01*
X304887Y201167D01*
X305262Y201042D01*
X306262D01*
G01X302329Y200000D02*
Y202500D01*
X302829Y202000D01*
G01Y200000D02*
X301829D01*
G01X300021Y202083D02*
X299771Y202333D01*
X299479Y202458D01*
X299146Y202500D01*
X298729Y202417D01*
X298437Y202208D01*
X298354Y201958D01*
X298396Y201708D01*
X298562Y201500D01*
X299396Y201083D01*
X299771Y200792D01*
X300021Y200375D01*
X300104Y200000D01*
X298354D01*
G01X314004Y196333D02*
X313671Y196125D01*
X313296Y196000D01*
X312962D01*
X312629Y196125D01*
X312379Y196333D01*
X312254Y196625D01*
X312337Y196917D01*
X312546Y197167D01*
X312921Y197333D01*
X313421Y197417D01*
X313712Y197583D01*
X313837Y197875D01*
X313754Y198167D01*
X313546Y198375D01*
X313254Y198500D01*
X312962D01*
X312671Y198417D01*
X312421Y198208D01*
G01X310029Y198500D02*
Y196000D01*
G01X310987Y198500D02*
X309071D01*
G01X307762Y196000D02*
Y198500D01*
X306762D01*
X306429Y198375D01*
X306179Y198083D01*
X306096Y197750D01*
X306179Y197417D01*
X306387Y197167D01*
X306762Y197042D01*
X307762D01*
G01X303829Y196000D02*
Y198500D01*
X304329Y198000D01*
G01Y196000D02*
X303329D01*
G01X300229D02*
Y198500D01*
X301771Y196708D01*
X299687D01*
G01X312615Y191833D02*
X312282Y191625D01*
X311907Y191500D01*
X311573D01*
X311240Y191625D01*
X310990Y191833D01*
X310865Y192125D01*
X310948Y192417D01*
X311157Y192667D01*
X311532Y192833D01*
X312032Y192917D01*
X312323Y193083D01*
X312448Y193375D01*
X312365Y193667D01*
X312157Y193875D01*
X311865Y194000D01*
X311573D01*
X311282Y193917D01*
X311032Y193708D01*
G01X308640Y194000D02*
Y191500D01*
G01X309598Y194000D02*
X307682D01*
G01X306373Y191500D02*
Y194000D01*
X305373D01*
X305040Y193875D01*
X304790Y193583D01*
X304707Y193250D01*
X304790Y192917D01*
X304998Y192667D01*
X305373Y192542D01*
X306373D01*
G01X302440Y191500D02*
Y194000D01*
X302940Y193500D01*
G01Y191500D02*
X301940D01*
G01X300132Y192542D02*
X299840Y192833D01*
X299590Y193000D01*
X299257Y193083D01*
X298965Y193000D01*
X298757Y192833D01*
X298590Y192583D01*
X298548Y192292D01*
X298590Y192042D01*
X298757Y191792D01*
X299007Y191583D01*
X299298Y191500D01*
X299632Y191583D01*
X299923Y191833D01*
X300090Y192208D01*
X300132Y192625D01*
X300048Y193167D01*
X299923Y193458D01*
X299715Y193750D01*
X299423Y193958D01*
X299132Y194000D01*
X298840Y193917D01*
X298632Y193708D01*
G01X299333Y246025D02*
X299125Y246358D01*
X299000Y246733D01*
Y247067D01*
X299125Y247400D01*
X299333Y247650D01*
X299625Y247775D01*
X299917Y247692D01*
X300167Y247483D01*
X300333Y247108D01*
X300417Y246608D01*
X300583Y246317D01*
X300875Y246192D01*
X301167Y246275D01*
X301375Y246483D01*
X301500Y246775D01*
Y247067D01*
X301417Y247358D01*
X301208Y247608D01*
G01X301500Y249167D02*
X299000D01*
Y250833D01*
G01Y253600D02*
X301500D01*
X299708Y252058D01*
Y254142D01*
G01X304453Y240152D02*
X311453D01*
Y253552D01*
X304453D01*
Y240152D01*
G01X313762Y253925D02*
X313554Y254258D01*
X313429Y254633D01*
Y254967D01*
X313554Y255300D01*
X313762Y255550D01*
X314054Y255675D01*
X314346Y255592D01*
X314596Y255383D01*
X314762Y255008D01*
X314846Y254508D01*
X315012Y254217D01*
X315304Y254092D01*
X315596Y254175D01*
X315804Y254383D01*
X315929Y254675D01*
Y254967D01*
X315846Y255258D01*
X315637Y255508D01*
G01X313429Y257067D02*
X315929D01*
Y258108D01*
X315804Y258442D01*
X315637Y258650D01*
X315304Y258733D01*
X314971Y258650D01*
X314762Y258400D01*
X314637Y258108D01*
Y257067D01*
G01Y258108D02*
X313429Y258733D01*
G01Y260917D02*
X313971Y261000D01*
X314429Y261125D01*
X314846Y261292D01*
X315304Y261500D01*
X315929Y261833D01*
Y260167D01*
G01X313429Y264100D02*
X315929D01*
X315429Y263600D01*
G01X313429D02*
Y264600D01*
G01Y267200D02*
X315929D01*
X315429Y266700D01*
G01X313429D02*
Y267700D01*
G01X312453Y250552D02*
X316453D01*
Y243152D01*
G01X310833Y298925D02*
X310625Y299258D01*
X310500Y299633D01*
Y299967D01*
X310625Y300300D01*
X310833Y300550D01*
X311125Y300675D01*
X311417Y300592D01*
X311667Y300383D01*
X311833Y300008D01*
X311917Y299508D01*
X312083Y299217D01*
X312375Y299092D01*
X312667Y299175D01*
X312875Y299383D01*
X313000Y299675D01*
Y299967D01*
X312917Y300258D01*
X312708Y300508D01*
G01X310500Y302067D02*
X313000D01*
Y303108D01*
X312875Y303442D01*
X312708Y303650D01*
X312375Y303733D01*
X312042Y303650D01*
X311833Y303400D01*
X311708Y303108D01*
Y302067D01*
G01Y303108D02*
X310500Y303733D01*
G01Y306000D02*
X310542Y306292D01*
X310667Y306625D01*
X310875Y306833D01*
X311167Y306917D01*
X311458Y306833D01*
X311708Y306583D01*
X311833Y306208D01*
Y305792D01*
X311917Y305542D01*
X312125Y305333D01*
X312417Y305250D01*
X312708Y305375D01*
X312917Y305667D01*
X313000Y306000D01*
X312917Y306333D01*
X312708Y306625D01*
X312417Y306750D01*
X312125Y306667D01*
X311917Y306458D01*
X311833Y306208D01*
Y305792D01*
X311708Y305417D01*
X311458Y305167D01*
X311167Y305083D01*
X310875Y305167D01*
X310667Y305375D01*
X310542Y305708D01*
X310500Y306000D01*
G01X310875Y308183D02*
X310667Y308433D01*
X310542Y308725D01*
X310500Y309100D01*
X310583Y309475D01*
X310750Y309767D01*
X311042Y309975D01*
X311375Y310017D01*
X311708Y309933D01*
X311917Y309725D01*
X312083Y309433D01*
X312125Y309142D01*
X312083Y308850D01*
X311917Y308475D01*
X313000Y308600D01*
Y309725D01*
G01X310500Y312200D02*
X313000D01*
X312500Y311700D01*
G01X310500D02*
Y312700D01*
G01X314000Y287300D02*
X310000D01*
Y294700D01*
G01X306000Y299467D02*
X308500D01*
Y300467D01*
X308375Y300800D01*
X308083Y301050D01*
X307750Y301133D01*
X307417Y301050D01*
X307167Y300842D01*
X307042Y300467D01*
Y299467D01*
G01X308292Y304317D02*
X308417Y304067D01*
X308500Y303775D01*
Y303442D01*
X308375Y303067D01*
X308167Y302775D01*
X307917Y302567D01*
X307500Y302400D01*
X307125Y302358D01*
X306750Y302442D01*
X306500Y302567D01*
X306250Y302817D01*
X306083Y303108D01*
X306000Y303400D01*
Y303692D01*
X306083Y303983D01*
X306208Y304233D01*
X306375Y304442D01*
G01X308083Y305708D02*
X308333Y305958D01*
X308458Y306250D01*
X308500Y306583D01*
X308417Y307000D01*
X308208Y307292D01*
X307958Y307375D01*
X307708Y307333D01*
X307500Y307167D01*
X307083Y306333D01*
X306792Y305958D01*
X306375Y305708D01*
X306000Y305625D01*
Y307375D01*
G01X308083Y308808D02*
X308333Y309058D01*
X308458Y309350D01*
X308500Y309683D01*
X308417Y310100D01*
X308208Y310392D01*
X307958Y310475D01*
X307708Y310433D01*
X307500Y310267D01*
X307083Y309433D01*
X306792Y309058D01*
X306375Y308808D01*
X306000Y308725D01*
Y310475D01*
G01X306500Y311783D02*
X306208Y312033D01*
X306042Y312367D01*
X306000Y312742D01*
X306042Y313075D01*
X306250Y313408D01*
X306500Y313617D01*
X306750Y313658D01*
X307042Y313575D01*
X307250Y313283D01*
X307333Y312992D01*
Y312617D01*
G01Y312992D02*
X307458Y313242D01*
X307667Y313450D01*
X307917Y313533D01*
X308167Y313450D01*
X308375Y313242D01*
X308500Y312867D01*
X308458Y312492D01*
X308292Y312117D01*
G01X325000Y48467D02*
X327500D01*
Y49467D01*
X327375Y49800D01*
X327083Y50050D01*
X326750Y50133D01*
X326417Y50050D01*
X326167Y49842D01*
X326042Y49467D01*
Y48467D01*
G01X327292Y53317D02*
X327417Y53067D01*
X327500Y52775D01*
Y52442D01*
X327375Y52067D01*
X327167Y51775D01*
X326917Y51567D01*
X326500Y51400D01*
X326125Y51358D01*
X325750Y51442D01*
X325500Y51567D01*
X325250Y51817D01*
X325083Y52108D01*
X325000Y52400D01*
Y52692D01*
X325083Y52983D01*
X325208Y53233D01*
X325375Y53442D01*
G01X327083Y54708D02*
X327333Y54958D01*
X327458Y55250D01*
X327500Y55583D01*
X327417Y56000D01*
X327208Y56292D01*
X326958Y56375D01*
X326708Y56333D01*
X326500Y56167D01*
X326083Y55333D01*
X325792Y54958D01*
X325375Y54708D01*
X325000Y54625D01*
Y56375D01*
G01Y58600D02*
X327500D01*
X327000Y58100D01*
G01X325000D02*
Y59100D01*
G01X326042Y60908D02*
X326333Y61200D01*
X326500Y61450D01*
X326583Y61783D01*
X326500Y62075D01*
X326333Y62283D01*
X326083Y62450D01*
X325792Y62492D01*
X325542Y62450D01*
X325292Y62283D01*
X325083Y62033D01*
X325000Y61742D01*
X325083Y61408D01*
X325333Y61117D01*
X325708Y60950D01*
X326125Y60908D01*
X326667Y60992D01*
X326958Y61117D01*
X327250Y61325D01*
X327458Y61617D01*
X327500Y61908D01*
X327417Y62200D01*
X327208Y62408D01*
G01X318000Y53467D02*
X320500D01*
Y54467D01*
X320375Y54800D01*
X320083Y55050D01*
X319750Y55133D01*
X319417Y55050D01*
X319167Y54842D01*
X319042Y54467D01*
Y53467D01*
G01X320292Y58317D02*
X320417Y58067D01*
X320500Y57775D01*
Y57442D01*
X320375Y57067D01*
X320167Y56775D01*
X319917Y56567D01*
X319500Y56400D01*
X319125Y56358D01*
X318750Y56442D01*
X318500Y56567D01*
X318250Y56817D01*
X318083Y57108D01*
X318000Y57400D01*
Y57692D01*
X318083Y57983D01*
X318208Y58233D01*
X318375Y58442D01*
G01X320083Y59708D02*
X320333Y59958D01*
X320458Y60250D01*
X320500Y60583D01*
X320417Y61000D01*
X320208Y61292D01*
X319958Y61375D01*
X319708Y61333D01*
X319500Y61167D01*
X319083Y60333D01*
X318792Y59958D01*
X318375Y59708D01*
X318000Y59625D01*
Y61375D01*
G01Y63600D02*
X320500D01*
X320000Y63100D01*
G01X318000D02*
Y64100D01*
G01X320083Y65908D02*
X320333Y66158D01*
X320458Y66450D01*
X320500Y66783D01*
X320417Y67200D01*
X320208Y67492D01*
X319958Y67575D01*
X319708Y67533D01*
X319500Y67367D01*
X319083Y66533D01*
X318792Y66158D01*
X318375Y65908D01*
X318000Y65825D01*
Y67575D01*
G01X323500Y79800D02*
X319500D01*
Y87200D01*
G01X328000Y79800D02*
X324000D01*
Y87200D01*
G01X319000Y79800D02*
X315000D01*
Y87200D01*
G01X328000Y89700D02*
X332000D01*
Y82300D01*
G01X327833Y108965D02*
X327625Y109298D01*
X327500Y109673D01*
Y110007D01*
X327625Y110340D01*
X327833Y110590D01*
X328125Y110715D01*
X328417Y110632D01*
X328667Y110423D01*
X328833Y110048D01*
X328917Y109548D01*
X329083Y109257D01*
X329375Y109132D01*
X329667Y109215D01*
X329875Y109423D01*
X330000Y109715D01*
Y110007D01*
X329917Y110298D01*
X329708Y110548D01*
G01X327500Y112107D02*
X330000D01*
Y113148D01*
X329875Y113482D01*
X329708Y113690D01*
X329375Y113773D01*
X329042Y113690D01*
X328833Y113440D01*
X328708Y113148D01*
Y112107D01*
G01Y113148D02*
X327500Y113773D01*
G01X327875Y115123D02*
X327667Y115373D01*
X327542Y115665D01*
X327500Y116040D01*
X327583Y116415D01*
X327750Y116707D01*
X328042Y116915D01*
X328375Y116957D01*
X328708Y116873D01*
X328917Y116665D01*
X329083Y116373D01*
X329125Y116082D01*
X329083Y115790D01*
X328917Y115415D01*
X330000Y115540D01*
Y116665D01*
G01X327500Y119140D02*
X327542Y119432D01*
X327667Y119765D01*
X327875Y119973D01*
X328167Y120057D01*
X328458Y119973D01*
X328708Y119723D01*
X328833Y119348D01*
Y118932D01*
X328917Y118682D01*
X329125Y118473D01*
X329417Y118390D01*
X329708Y118515D01*
X329917Y118807D01*
X330000Y119140D01*
X329917Y119473D01*
X329708Y119765D01*
X329417Y119890D01*
X329125Y119807D01*
X328917Y119598D01*
X328833Y119348D01*
Y118932D01*
X328708Y118557D01*
X328458Y118307D01*
X328167Y118223D01*
X327875Y118307D01*
X327667Y118515D01*
X327542Y118848D01*
X327500Y119140D01*
G01X327875Y121323D02*
X327667Y121573D01*
X327542Y121865D01*
X327500Y122240D01*
X327583Y122615D01*
X327750Y122907D01*
X328042Y123115D01*
X328375Y123157D01*
X328708Y123073D01*
X328917Y122865D01*
X329083Y122573D01*
X329125Y122282D01*
X329083Y121990D01*
X328917Y121615D01*
X330000Y121740D01*
Y122865D01*
G01X333504Y148333D02*
X333171Y148125D01*
X332796Y148000D01*
X332462D01*
X332129Y148125D01*
X331879Y148333D01*
X331754Y148625D01*
X331837Y148917D01*
X332046Y149167D01*
X332421Y149333D01*
X332921Y149417D01*
X333212Y149583D01*
X333337Y149875D01*
X333254Y150167D01*
X333046Y150375D01*
X332754Y150500D01*
X332462D01*
X332171Y150417D01*
X331921Y150208D01*
G01X328612Y150292D02*
X328862Y150417D01*
X329154Y150500D01*
X329487D01*
X329862Y150375D01*
X330154Y150167D01*
X330362Y149917D01*
X330529Y149500D01*
X330571Y149125D01*
X330487Y148750D01*
X330362Y148500D01*
X330112Y148250D01*
X329821Y148083D01*
X329529Y148000D01*
X329237D01*
X328946Y148083D01*
X328696Y148208D01*
X328487Y148375D01*
G01X327137Y148292D02*
X326846Y148083D01*
X326512Y148000D01*
X326179Y148083D01*
X325887Y148333D01*
X325679Y148708D01*
X325596Y149083D01*
Y149542D01*
X325679Y149917D01*
X325887Y150250D01*
X326137Y150417D01*
X326429Y150500D01*
X326762Y150417D01*
X327012Y150250D01*
X327179Y150000D01*
X327262Y149667D01*
X327179Y149375D01*
X326971Y149083D01*
X326721Y148917D01*
X326429Y148875D01*
X326096Y148958D01*
X325846Y149167D01*
X325596Y149542D01*
G01X324246Y148500D02*
X323996Y148208D01*
X323662Y148042D01*
X323287Y148000D01*
X322954Y148042D01*
X322621Y148250D01*
X322412Y148500D01*
X322371Y148750D01*
X322454Y149042D01*
X322746Y149250D01*
X323037Y149333D01*
X323412D01*
G01X323037D02*
X322787Y149458D01*
X322579Y149667D01*
X322496Y149917D01*
X322579Y150167D01*
X322787Y150375D01*
X323162Y150500D01*
X323537Y150458D01*
X323912Y150292D01*
G01X320312Y148000D02*
X320229Y148542D01*
X320104Y149000D01*
X319937Y149417D01*
X319729Y149875D01*
X319396Y150500D01*
X321062D01*
G01X338004Y154333D02*
X337671Y154125D01*
X337296Y154000D01*
X336962D01*
X336629Y154125D01*
X336379Y154333D01*
X336254Y154625D01*
X336337Y154917D01*
X336546Y155167D01*
X336921Y155333D01*
X337421Y155417D01*
X337712Y155583D01*
X337837Y155875D01*
X337754Y156167D01*
X337546Y156375D01*
X337254Y156500D01*
X336962D01*
X336671Y156417D01*
X336421Y156208D01*
G01X333112Y156292D02*
X333362Y156417D01*
X333654Y156500D01*
X333987D01*
X334362Y156375D01*
X334654Y156167D01*
X334862Y155917D01*
X335029Y155500D01*
X335071Y155125D01*
X334987Y154750D01*
X334862Y154500D01*
X334612Y154250D01*
X334321Y154083D01*
X334029Y154000D01*
X333737D01*
X333446Y154083D01*
X333196Y154208D01*
X332987Y154375D01*
G01X331637Y154292D02*
X331346Y154083D01*
X331012Y154000D01*
X330679Y154083D01*
X330387Y154333D01*
X330179Y154708D01*
X330096Y155083D01*
Y155542D01*
X330179Y155917D01*
X330387Y156250D01*
X330637Y156417D01*
X330929Y156500D01*
X331262Y156417D01*
X331512Y156250D01*
X331679Y156000D01*
X331762Y155667D01*
X331679Y155375D01*
X331471Y155083D01*
X331221Y154917D01*
X330929Y154875D01*
X330596Y154958D01*
X330346Y155167D01*
X330096Y155542D01*
G01X328746Y154500D02*
X328496Y154208D01*
X328162Y154042D01*
X327787Y154000D01*
X327454Y154042D01*
X327121Y154250D01*
X326912Y154500D01*
X326871Y154750D01*
X326954Y155042D01*
X327246Y155250D01*
X327537Y155333D01*
X327912D01*
G01X327537D02*
X327287Y155458D01*
X327079Y155667D01*
X326996Y155917D01*
X327079Y156167D01*
X327287Y156375D01*
X327662Y156500D01*
X328037Y156458D01*
X328412Y156292D01*
G01X325437Y154292D02*
X325146Y154083D01*
X324812Y154000D01*
X324479Y154083D01*
X324187Y154333D01*
X323979Y154708D01*
X323896Y155083D01*
Y155542D01*
X323979Y155917D01*
X324187Y156250D01*
X324437Y156417D01*
X324729Y156500D01*
X325062Y156417D01*
X325312Y156250D01*
X325479Y156000D01*
X325562Y155667D01*
X325479Y155375D01*
X325271Y155083D01*
X325021Y154917D01*
X324729Y154875D01*
X324396Y154958D01*
X324146Y155167D01*
X323896Y155542D01*
G01X338004Y161833D02*
X337671Y161625D01*
X337296Y161500D01*
X336962D01*
X336629Y161625D01*
X336379Y161833D01*
X336254Y162125D01*
X336337Y162417D01*
X336546Y162667D01*
X336921Y162833D01*
X337421Y162917D01*
X337712Y163083D01*
X337837Y163375D01*
X337754Y163667D01*
X337546Y163875D01*
X337254Y164000D01*
X336962D01*
X336671Y163917D01*
X336421Y163708D01*
G01X333112Y163792D02*
X333362Y163917D01*
X333654Y164000D01*
X333987D01*
X334362Y163875D01*
X334654Y163667D01*
X334862Y163417D01*
X335029Y163000D01*
X335071Y162625D01*
X334987Y162250D01*
X334862Y162000D01*
X334612Y161750D01*
X334321Y161583D01*
X334029Y161500D01*
X333737D01*
X333446Y161583D01*
X333196Y161708D01*
X332987Y161875D01*
G01X331637Y161792D02*
X331346Y161583D01*
X331012Y161500D01*
X330679Y161583D01*
X330387Y161833D01*
X330179Y162208D01*
X330096Y162583D01*
Y163042D01*
X330179Y163417D01*
X330387Y163750D01*
X330637Y163917D01*
X330929Y164000D01*
X331262Y163917D01*
X331512Y163750D01*
X331679Y163500D01*
X331762Y163167D01*
X331679Y162875D01*
X331471Y162583D01*
X331221Y162417D01*
X330929Y162375D01*
X330596Y162458D01*
X330346Y162667D01*
X330096Y163042D01*
G01X327329Y161500D02*
Y164000D01*
X328871Y162208D01*
X326787D01*
G01X324729Y164000D02*
X325062Y163917D01*
X325312Y163708D01*
X325479Y163458D01*
X325604Y163125D01*
X325646Y162750D01*
X325604Y162375D01*
X325479Y162042D01*
X325312Y161792D01*
X325062Y161583D01*
X324729Y161500D01*
X324396Y161583D01*
X324146Y161792D01*
X323979Y162042D01*
X323854Y162375D01*
X323812Y162750D01*
X323854Y163125D01*
X323979Y163458D01*
X324146Y163708D01*
X324396Y163917D01*
X324729Y164000D01*
G01X329155Y182633D02*
X328822Y182425D01*
X328447Y182300D01*
X328113D01*
X327780Y182425D01*
X327530Y182633D01*
X327405Y182925D01*
X327488Y183217D01*
X327697Y183467D01*
X328072Y183633D01*
X328572Y183717D01*
X328863Y183883D01*
X328988Y184175D01*
X328905Y184467D01*
X328697Y184675D01*
X328405Y184800D01*
X328113D01*
X327822Y184717D01*
X327572Y184508D01*
G01X325180Y184800D02*
Y182300D01*
G01X326138Y184800D02*
X324222D01*
G01X322913Y182300D02*
Y184800D01*
X321913D01*
X321580Y184675D01*
X321330Y184383D01*
X321247Y184050D01*
X321330Y183717D01*
X321538Y183467D01*
X321913Y183342D01*
X322913D01*
G01X319772Y184383D02*
X319522Y184633D01*
X319230Y184758D01*
X318897Y184800D01*
X318480Y184717D01*
X318188Y184508D01*
X318105Y184258D01*
X318147Y184008D01*
X318313Y183800D01*
X319147Y183383D01*
X319522Y183092D01*
X319772Y182675D01*
X319855Y182300D01*
X318105D01*
G01X315880D02*
Y184800D01*
X316380Y184300D01*
G01Y182300D02*
X315380D01*
G01X327965Y187633D02*
X327632Y187425D01*
X327257Y187300D01*
X326923D01*
X326590Y187425D01*
X326340Y187633D01*
X326215Y187925D01*
X326298Y188217D01*
X326507Y188467D01*
X326882Y188633D01*
X327382Y188717D01*
X327673Y188883D01*
X327798Y189175D01*
X327715Y189467D01*
X327507Y189675D01*
X327215Y189800D01*
X326923D01*
X326632Y189717D01*
X326382Y189508D01*
G01X323990Y189800D02*
Y187300D01*
G01X324948Y189800D02*
X323032D01*
G01X321723Y187300D02*
Y189800D01*
X320723D01*
X320390Y189675D01*
X320140Y189383D01*
X320057Y189050D01*
X320140Y188717D01*
X320348Y188467D01*
X320723Y188342D01*
X321723D01*
G01X318498Y187592D02*
X318207Y187383D01*
X317873Y187300D01*
X317540Y187383D01*
X317248Y187633D01*
X317040Y188008D01*
X316957Y188383D01*
Y188842D01*
X317040Y189217D01*
X317248Y189550D01*
X317498Y189717D01*
X317790Y189800D01*
X318123Y189717D01*
X318373Y189550D01*
X318540Y189300D01*
X318623Y188967D01*
X318540Y188675D01*
X318332Y188383D01*
X318082Y188217D01*
X317790Y188175D01*
X317457Y188258D01*
X317207Y188467D01*
X316957Y188842D01*
G01X329004Y178333D02*
X328671Y178125D01*
X328296Y178000D01*
X327962D01*
X327629Y178125D01*
X327379Y178333D01*
X327254Y178625D01*
X327337Y178917D01*
X327546Y179167D01*
X327921Y179333D01*
X328421Y179417D01*
X328712Y179583D01*
X328837Y179875D01*
X328754Y180167D01*
X328546Y180375D01*
X328254Y180500D01*
X327962D01*
X327671Y180417D01*
X327421Y180208D01*
G01X325862Y178000D02*
Y180500D01*
X324821D01*
X324487Y180375D01*
X324279Y180208D01*
X324196Y179875D01*
X324279Y179542D01*
X324529Y179333D01*
X324821Y179208D01*
X325862D01*
G01X324821D02*
X324196Y178000D01*
G01X322721Y179042D02*
X322429Y179333D01*
X322179Y179500D01*
X321846Y179583D01*
X321554Y179500D01*
X321346Y179333D01*
X321179Y179083D01*
X321137Y178792D01*
X321179Y178542D01*
X321346Y178292D01*
X321596Y178083D01*
X321887Y178000D01*
X322221Y178083D01*
X322512Y178333D01*
X322679Y178708D01*
X322721Y179125D01*
X322637Y179667D01*
X322512Y179958D01*
X322304Y180250D01*
X322012Y180458D01*
X321721Y180500D01*
X321429Y180417D01*
X321221Y180208D01*
G01X319746Y178375D02*
X319496Y178167D01*
X319204Y178042D01*
X318829Y178000D01*
X318454Y178083D01*
X318162Y178250D01*
X317954Y178542D01*
X317912Y178875D01*
X317996Y179208D01*
X318204Y179417D01*
X318496Y179583D01*
X318787Y179625D01*
X319079Y179583D01*
X319454Y179417D01*
X319329Y180500D01*
X318204D01*
G01X315729D02*
X316062Y180417D01*
X316312Y180208D01*
X316479Y179958D01*
X316604Y179625D01*
X316646Y179250D01*
X316604Y178875D01*
X316479Y178542D01*
X316312Y178292D01*
X316062Y178083D01*
X315729Y178000D01*
X315396Y178083D01*
X315146Y178292D01*
X314979Y178542D01*
X314854Y178875D01*
X314812Y179250D01*
X314854Y179625D01*
X314979Y179958D01*
X315146Y180208D01*
X315396Y180417D01*
X315729Y180500D01*
G01X328504Y200333D02*
X328171Y200125D01*
X327796Y200000D01*
X327462D01*
X327129Y200125D01*
X326879Y200333D01*
X326754Y200625D01*
X326837Y200917D01*
X327046Y201167D01*
X327421Y201333D01*
X327921Y201417D01*
X328212Y201583D01*
X328337Y201875D01*
X328254Y202167D01*
X328046Y202375D01*
X327754Y202500D01*
X327462D01*
X327171Y202417D01*
X326921Y202208D01*
G01X324529Y202500D02*
Y200000D01*
G01X325487Y202500D02*
X323571D01*
G01X322262Y200000D02*
Y202500D01*
X321262D01*
X320929Y202375D01*
X320679Y202083D01*
X320596Y201750D01*
X320679Y201417D01*
X320887Y201167D01*
X321262Y201042D01*
X322262D01*
G01X318329Y200000D02*
Y202500D01*
X318829Y202000D01*
G01Y200000D02*
X317829D01*
G01X315229D02*
X314937Y200042D01*
X314604Y200167D01*
X314396Y200375D01*
X314312Y200667D01*
X314396Y200958D01*
X314646Y201208D01*
X315021Y201333D01*
X315437D01*
X315687Y201417D01*
X315896Y201625D01*
X315979Y201917D01*
X315854Y202208D01*
X315562Y202417D01*
X315229Y202500D01*
X314896Y202417D01*
X314604Y202208D01*
X314479Y201917D01*
X314562Y201625D01*
X314771Y201417D01*
X315021Y201333D01*
X315437D01*
X315812Y201208D01*
X316062Y200958D01*
X316146Y200667D01*
X316062Y200375D01*
X315854Y200167D01*
X315521Y200042D01*
X315229Y200000D01*
G01X326954Y196333D02*
X326621Y196125D01*
X326246Y196000D01*
X325912D01*
X325579Y196125D01*
X325329Y196333D01*
X325204Y196625D01*
X325287Y196917D01*
X325496Y197167D01*
X325871Y197333D01*
X326371Y197417D01*
X326662Y197583D01*
X326787Y197875D01*
X326704Y198167D01*
X326496Y198375D01*
X326204Y198500D01*
X325912D01*
X325621Y198417D01*
X325371Y198208D01*
G01X322979Y198500D02*
Y196000D01*
G01X323937Y198500D02*
X322021D01*
G01X320712Y196000D02*
Y198500D01*
X319712D01*
X319379Y198375D01*
X319129Y198083D01*
X319046Y197750D01*
X319129Y197417D01*
X319337Y197167D01*
X319712Y197042D01*
X320712D01*
G01X316862Y196000D02*
X316779Y196542D01*
X316654Y197000D01*
X316487Y197417D01*
X316279Y197875D01*
X315946Y198500D01*
X317612D01*
G01X391500Y212000D02*
Y218000D01*
X389000D01*
Y247500D01*
X370500D01*
Y261500D01*
X385000D01*
Y300000D01*
X348500D01*
Y282500D01*
X328000D01*
Y269500D01*
X333500D01*
Y261500D01*
X370500D01*
X374000Y258000D01*
X367000D01*
X370500Y261500D01*
G01X325500Y281800D02*
Y295200D01*
G01X315500Y281800D02*
X325500D01*
G01X315500Y295200D02*
Y281800D01*
G01X325983Y302500D02*
Y305000D01*
X324983D01*
X324650Y304875D01*
X324400Y304583D01*
X324317Y304250D01*
X324400Y303917D01*
X324608Y303667D01*
X324983Y303542D01*
X325983D01*
G01X322967Y305000D02*
Y303208D01*
X322800Y302833D01*
X322467Y302583D01*
X322050Y302500D01*
X321633Y302583D01*
X321300Y302833D01*
X321133Y303208D01*
Y305000D01*
G01X319658Y302792D02*
X319367Y302583D01*
X319033Y302500D01*
X318700Y302583D01*
X318408Y302833D01*
X318200Y303208D01*
X318117Y303583D01*
Y304042D01*
X318200Y304417D01*
X318408Y304750D01*
X318658Y304917D01*
X318950Y305000D01*
X319283Y304917D01*
X319533Y304750D01*
X319700Y304500D01*
X319783Y304167D01*
X319700Y303875D01*
X319492Y303583D01*
X319242Y303417D01*
X318950Y303375D01*
X318617Y303458D01*
X318367Y303667D01*
X318117Y304042D01*
G01X316558Y302792D02*
X316267Y302583D01*
X315933Y302500D01*
X315600Y302583D01*
X315308Y302833D01*
X315100Y303208D01*
X315017Y303583D01*
Y304042D01*
X315100Y304417D01*
X315308Y304750D01*
X315558Y304917D01*
X315850Y305000D01*
X316183Y304917D01*
X316433Y304750D01*
X316600Y304500D01*
X316683Y304167D01*
X316600Y303875D01*
X316392Y303583D01*
X316142Y303417D01*
X315850Y303375D01*
X315517Y303458D01*
X315267Y303667D01*
X315017Y304042D01*
G01X325500Y295200D02*
X315500D01*
G01X328833Y298925D02*
X328625Y299258D01*
X328500Y299633D01*
Y299967D01*
X328625Y300300D01*
X328833Y300550D01*
X329125Y300675D01*
X329417Y300592D01*
X329667Y300383D01*
X329833Y300008D01*
X329917Y299508D01*
X330083Y299217D01*
X330375Y299092D01*
X330667Y299175D01*
X330875Y299383D01*
X331000Y299675D01*
Y299967D01*
X330917Y300258D01*
X330708Y300508D01*
G01X328500Y302067D02*
X331000D01*
Y303108D01*
X330875Y303442D01*
X330708Y303650D01*
X330375Y303733D01*
X330042Y303650D01*
X329833Y303400D01*
X329708Y303108D01*
Y302067D01*
G01Y303108D02*
X328500Y303733D01*
G01X328792Y305292D02*
X328583Y305583D01*
X328500Y305917D01*
X328583Y306250D01*
X328833Y306542D01*
X329208Y306750D01*
X329583Y306833D01*
X330042D01*
X330417Y306750D01*
X330750Y306542D01*
X330917Y306292D01*
X331000Y306000D01*
X330917Y305667D01*
X330750Y305417D01*
X330500Y305250D01*
X330167Y305167D01*
X329875Y305250D01*
X329583Y305458D01*
X329417Y305708D01*
X329375Y306000D01*
X329458Y306333D01*
X329667Y306583D01*
X330042Y306833D01*
G01X330583Y308308D02*
X330833Y308558D01*
X330958Y308850D01*
X331000Y309183D01*
X330917Y309600D01*
X330708Y309892D01*
X330458Y309975D01*
X330208Y309933D01*
X330000Y309767D01*
X329583Y308933D01*
X329292Y308558D01*
X328875Y308308D01*
X328500Y308225D01*
Y309975D01*
G01X328792Y311492D02*
X328583Y311783D01*
X328500Y312117D01*
X328583Y312450D01*
X328833Y312742D01*
X329208Y312950D01*
X329583Y313033D01*
X330042D01*
X330417Y312950D01*
X330750Y312742D01*
X330917Y312492D01*
X331000Y312200D01*
X330917Y311867D01*
X330750Y311617D01*
X330500Y311450D01*
X330167Y311367D01*
X329875Y311450D01*
X329583Y311658D01*
X329417Y311908D01*
X329375Y312200D01*
X329458Y312533D01*
X329667Y312783D01*
X330042Y313033D01*
G01X331500Y288800D02*
X327500D01*
Y296200D01*
G01X322000Y364500D02*
X318000D01*
Y320500D01*
X381500D01*
Y356000D01*
X384500Y359000D01*
Y353000D01*
X381500Y356000D01*
G01X338125Y327333D02*
X337792Y327125D01*
X337417Y327000D01*
X337083D01*
X336750Y327125D01*
X336500Y327333D01*
X336375Y327625D01*
X336458Y327917D01*
X336667Y328167D01*
X337042Y328333D01*
X337542Y328417D01*
X337833Y328583D01*
X337958Y328875D01*
X337875Y329167D01*
X337667Y329375D01*
X337375Y329500D01*
X337083D01*
X336792Y329417D01*
X336542Y329208D01*
G01X333233Y329292D02*
X333483Y329417D01*
X333775Y329500D01*
X334108D01*
X334483Y329375D01*
X334775Y329167D01*
X334983Y328917D01*
X335150Y328500D01*
X335192Y328125D01*
X335108Y327750D01*
X334983Y327500D01*
X334733Y327250D01*
X334442Y327083D01*
X334150Y327000D01*
X333858D01*
X333567Y327083D01*
X333317Y327208D01*
X333108Y327375D01*
G01X331050Y327000D02*
Y329500D01*
X331550Y329000D01*
G01Y327000D02*
X330550D01*
G01X328742Y329083D02*
X328492Y329333D01*
X328200Y329458D01*
X327867Y329500D01*
X327450Y329417D01*
X327158Y329208D01*
X327075Y328958D01*
X327117Y328708D01*
X327283Y328500D01*
X328117Y328083D01*
X328492Y327792D01*
X328742Y327375D01*
X328825Y327000D01*
X327075D01*
G01X325767Y327375D02*
X325517Y327167D01*
X325225Y327042D01*
X324850Y327000D01*
X324475Y327083D01*
X324183Y327250D01*
X323975Y327542D01*
X323933Y327875D01*
X324017Y328208D01*
X324225Y328417D01*
X324517Y328583D01*
X324808Y328625D01*
X325100Y328583D01*
X325475Y328417D01*
X325350Y329500D01*
X324225D01*
G01X321750D02*
X322083Y329417D01*
X322333Y329208D01*
X322500Y328958D01*
X322625Y328625D01*
X322667Y328250D01*
X322625Y327875D01*
X322500Y327542D01*
X322333Y327292D01*
X322083Y327083D01*
X321750Y327000D01*
X321417Y327083D01*
X321167Y327292D01*
X321000Y327542D01*
X320875Y327875D01*
X320833Y328250D01*
X320875Y328625D01*
X321000Y328958D01*
X321167Y329208D01*
X321417Y329417D01*
X321750Y329500D01*
G01X320833Y345375D02*
X320625Y345708D01*
X320500Y346083D01*
Y346417D01*
X320625Y346750D01*
X320833Y347000D01*
X321125Y347125D01*
X321417Y347042D01*
X321667Y346833D01*
X321833Y346458D01*
X321917Y345958D01*
X322083Y345667D01*
X322375Y345542D01*
X322667Y345625D01*
X322875Y345833D01*
X323000Y346125D01*
Y346417D01*
X322917Y346708D01*
X322708Y346958D01*
G01X322792Y350267D02*
X322917Y350017D01*
X323000Y349725D01*
Y349392D01*
X322875Y349017D01*
X322667Y348725D01*
X322417Y348517D01*
X322000Y348350D01*
X321625Y348308D01*
X321250Y348392D01*
X321000Y348517D01*
X320750Y348767D01*
X320583Y349058D01*
X320500Y349350D01*
Y349642D01*
X320583Y349933D01*
X320708Y350183D01*
X320875Y350392D01*
G01X320500Y352450D02*
X323000D01*
X322500Y351950D01*
G01X320500D02*
Y352950D01*
G01X322583Y354758D02*
X322833Y355008D01*
X322958Y355300D01*
X323000Y355633D01*
X322917Y356050D01*
X322708Y356342D01*
X322458Y356425D01*
X322208Y356383D01*
X322000Y356217D01*
X321583Y355383D01*
X321292Y355008D01*
X320875Y354758D01*
X320500Y354675D01*
Y356425D01*
G01X320875Y357733D02*
X320667Y357983D01*
X320542Y358275D01*
X320500Y358650D01*
X320583Y359025D01*
X320750Y359317D01*
X321042Y359525D01*
X321375Y359567D01*
X321708Y359483D01*
X321917Y359275D01*
X322083Y358983D01*
X322125Y358692D01*
X322083Y358400D01*
X321917Y358025D01*
X323000Y358150D01*
Y359275D01*
G01X320500Y361750D02*
X323000D01*
X322500Y361250D01*
G01X320500D02*
Y362250D01*
G01X342125Y339333D02*
X341792Y339125D01*
X341417Y339000D01*
X341083D01*
X340750Y339125D01*
X340500Y339333D01*
X340375Y339625D01*
X340458Y339917D01*
X340667Y340167D01*
X341042Y340333D01*
X341542Y340417D01*
X341833Y340583D01*
X341958Y340875D01*
X341875Y341167D01*
X341667Y341375D01*
X341375Y341500D01*
X341083D01*
X340792Y341417D01*
X340542Y341208D01*
G01X338150Y341500D02*
Y339000D01*
G01X339108Y341500D02*
X337192D01*
G01X335883Y339000D02*
Y341500D01*
X334883D01*
X334550Y341375D01*
X334300Y341083D01*
X334217Y340750D01*
X334300Y340417D01*
X334508Y340167D01*
X334883Y340042D01*
X335883D01*
G01X331950Y339000D02*
Y341500D01*
X332450Y341000D01*
G01Y339000D02*
X331450D01*
G01X329642Y340042D02*
X329350Y340333D01*
X329100Y340500D01*
X328767Y340583D01*
X328475Y340500D01*
X328267Y340333D01*
X328100Y340083D01*
X328058Y339792D01*
X328100Y339542D01*
X328267Y339292D01*
X328517Y339083D01*
X328808Y339000D01*
X329142Y339083D01*
X329433Y339333D01*
X329600Y339708D01*
X329642Y340125D01*
X329558Y340667D01*
X329433Y340958D01*
X329225Y341250D01*
X328933Y341458D01*
X328642Y341500D01*
X328350Y341417D01*
X328142Y341208D01*
G01X326542Y341083D02*
X326292Y341333D01*
X326000Y341458D01*
X325667Y341500D01*
X325250Y341417D01*
X324958Y341208D01*
X324875Y340958D01*
X324917Y340708D01*
X325083Y340500D01*
X325917Y340083D01*
X326292Y339792D01*
X326542Y339375D01*
X326625Y339000D01*
X324875D01*
G01X344625Y354333D02*
X344292Y354125D01*
X343917Y354000D01*
X343583D01*
X343250Y354125D01*
X343000Y354333D01*
X342875Y354625D01*
X342958Y354917D01*
X343167Y355167D01*
X343542Y355333D01*
X344042Y355417D01*
X344333Y355583D01*
X344458Y355875D01*
X344375Y356167D01*
X344167Y356375D01*
X343875Y356500D01*
X343583D01*
X343292Y356417D01*
X343042Y356208D01*
G01X339733Y356292D02*
X339983Y356417D01*
X340275Y356500D01*
X340608D01*
X340983Y356375D01*
X341275Y356167D01*
X341483Y355917D01*
X341650Y355500D01*
X341692Y355125D01*
X341608Y354750D01*
X341483Y354500D01*
X341233Y354250D01*
X340942Y354083D01*
X340650Y354000D01*
X340358D01*
X340067Y354083D01*
X339817Y354208D01*
X339608Y354375D01*
G01X337550Y354000D02*
Y356500D01*
X338050Y356000D01*
G01Y354000D02*
X337050D01*
G01X335242Y356083D02*
X334992Y356333D01*
X334700Y356458D01*
X334367Y356500D01*
X333950Y356417D01*
X333658Y356208D01*
X333575Y355958D01*
X333617Y355708D01*
X333783Y355500D01*
X334617Y355083D01*
X334992Y354792D01*
X335242Y354375D01*
X335325Y354000D01*
X333575D01*
G01X332267Y354375D02*
X332017Y354167D01*
X331725Y354042D01*
X331350Y354000D01*
X330975Y354083D01*
X330683Y354250D01*
X330475Y354542D01*
X330433Y354875D01*
X330517Y355208D01*
X330725Y355417D01*
X331017Y355583D01*
X331308Y355625D01*
X331600Y355583D01*
X331975Y355417D01*
X331850Y356500D01*
X330725D01*
G01X328958Y354292D02*
X328667Y354083D01*
X328333Y354000D01*
X328000Y354083D01*
X327708Y354333D01*
X327500Y354708D01*
X327417Y355083D01*
Y355542D01*
X327500Y355917D01*
X327708Y356250D01*
X327958Y356417D01*
X328250Y356500D01*
X328583Y356417D01*
X328833Y356250D01*
X329000Y356000D01*
X329083Y355667D01*
X329000Y355375D01*
X328792Y355083D01*
X328542Y354917D01*
X328250Y354875D01*
X327917Y354958D01*
X327667Y355167D01*
X327417Y355542D01*
G01X344780Y358533D02*
X344447Y358325D01*
X344072Y358200D01*
X343738D01*
X343405Y358325D01*
X343155Y358533D01*
X343030Y358825D01*
X343113Y359117D01*
X343322Y359367D01*
X343697Y359533D01*
X344197Y359617D01*
X344488Y359783D01*
X344613Y360075D01*
X344530Y360367D01*
X344322Y360575D01*
X344030Y360700D01*
X343738D01*
X343447Y360617D01*
X343197Y360408D01*
G01X339888Y360492D02*
X340138Y360617D01*
X340430Y360700D01*
X340763D01*
X341138Y360575D01*
X341430Y360367D01*
X341638Y360117D01*
X341805Y359700D01*
X341847Y359325D01*
X341763Y358950D01*
X341638Y358700D01*
X341388Y358450D01*
X341097Y358283D01*
X340805Y358200D01*
X340513D01*
X340222Y358283D01*
X339972Y358408D01*
X339763Y358575D01*
G01X337705Y358200D02*
Y360700D01*
X338205Y360200D01*
G01Y358200D02*
X337205D01*
G01X335397Y360283D02*
X335147Y360533D01*
X334855Y360658D01*
X334522Y360700D01*
X334105Y360617D01*
X333813Y360408D01*
X333730Y360158D01*
X333772Y359908D01*
X333938Y359700D01*
X334772Y359283D01*
X335147Y358992D01*
X335397Y358575D01*
X335480Y358200D01*
X333730D01*
G01X331005D02*
Y360700D01*
X332547Y358908D01*
X330463D01*
G01X329113Y358492D02*
X328822Y358283D01*
X328488Y358200D01*
X328155Y358283D01*
X327863Y358533D01*
X327655Y358908D01*
X327572Y359283D01*
Y359742D01*
X327655Y360117D01*
X327863Y360450D01*
X328113Y360617D01*
X328405Y360700D01*
X328738Y360617D01*
X328988Y360450D01*
X329155Y360200D01*
X329238Y359867D01*
X329155Y359575D01*
X328947Y359283D01*
X328697Y359117D01*
X328405Y359075D01*
X328072Y359158D01*
X327822Y359367D01*
X327572Y359742D01*
G01X331500Y48467D02*
X334000D01*
Y49467D01*
X333875Y49800D01*
X333583Y50050D01*
X333250Y50133D01*
X332917Y50050D01*
X332667Y49842D01*
X332542Y49467D01*
Y48467D01*
G01X333792Y53317D02*
X333917Y53067D01*
X334000Y52775D01*
Y52442D01*
X333875Y52067D01*
X333667Y51775D01*
X333417Y51567D01*
X333000Y51400D01*
X332625Y51358D01*
X332250Y51442D01*
X332000Y51567D01*
X331750Y51817D01*
X331583Y52108D01*
X331500Y52400D01*
Y52692D01*
X331583Y52983D01*
X331708Y53233D01*
X331875Y53442D01*
G01X333583Y54708D02*
X333833Y54958D01*
X333958Y55250D01*
X334000Y55583D01*
X333917Y56000D01*
X333708Y56292D01*
X333458Y56375D01*
X333208Y56333D01*
X333000Y56167D01*
X332583Y55333D01*
X332292Y54958D01*
X331875Y54708D01*
X331500Y54625D01*
Y56375D01*
G01Y58600D02*
X334000D01*
X333500Y58100D01*
G01X331500D02*
Y59100D01*
G01X331875Y60783D02*
X331667Y61033D01*
X331542Y61325D01*
X331500Y61700D01*
X331583Y62075D01*
X331750Y62367D01*
X332042Y62575D01*
X332375Y62617D01*
X332708Y62533D01*
X332917Y62325D01*
X333083Y62033D01*
X333125Y61742D01*
X333083Y61450D01*
X332917Y61075D01*
X334000Y61200D01*
Y62325D01*
G01X346000Y60467D02*
X348500D01*
Y61467D01*
X348375Y61800D01*
X348083Y62050D01*
X347750Y62133D01*
X347417Y62050D01*
X347167Y61842D01*
X347042Y61467D01*
Y60467D01*
G01X346000Y63567D02*
X348500D01*
Y64608D01*
X348375Y64942D01*
X348208Y65150D01*
X347875Y65233D01*
X347542Y65150D01*
X347333Y64900D01*
X347208Y64608D01*
Y63567D01*
G01Y64608D02*
X346000Y65233D01*
G01Y67500D02*
X348500D01*
X348000Y67000D01*
G01X346000D02*
Y68000D01*
G01Y70600D02*
X346042Y70892D01*
X346167Y71225D01*
X346375Y71433D01*
X346667Y71517D01*
X346958Y71433D01*
X347208Y71183D01*
X347333Y70808D01*
Y70392D01*
X347417Y70142D01*
X347625Y69933D01*
X347917Y69850D01*
X348208Y69975D01*
X348417Y70267D01*
X348500Y70600D01*
X348417Y70933D01*
X348208Y71225D01*
X347917Y71350D01*
X347625Y71267D01*
X347417Y71058D01*
X347333Y70808D01*
Y70392D01*
X347208Y70017D01*
X346958Y69767D01*
X346667Y69683D01*
X346375Y69767D01*
X346167Y69975D01*
X346042Y70308D01*
X346000Y70600D01*
G01Y74200D02*
X348500D01*
X346708Y72658D01*
Y74742D01*
G01X341500Y60467D02*
X344000D01*
Y61467D01*
X343875Y61800D01*
X343583Y62050D01*
X343250Y62133D01*
X342917Y62050D01*
X342667Y61842D01*
X342542Y61467D01*
Y60467D01*
G01X341500Y63567D02*
X344000D01*
Y64608D01*
X343875Y64942D01*
X343708Y65150D01*
X343375Y65233D01*
X343042Y65150D01*
X342833Y64900D01*
X342708Y64608D01*
Y63567D01*
G01Y64608D02*
X341500Y65233D01*
G01Y67500D02*
X344000D01*
X343500Y67000D01*
G01X341500D02*
Y68000D01*
G01Y70600D02*
X341542Y70892D01*
X341667Y71225D01*
X341875Y71433D01*
X342167Y71517D01*
X342458Y71433D01*
X342708Y71183D01*
X342833Y70808D01*
Y70392D01*
X342917Y70142D01*
X343125Y69933D01*
X343417Y69850D01*
X343708Y69975D01*
X343917Y70267D01*
X344000Y70600D01*
X343917Y70933D01*
X343708Y71225D01*
X343417Y71350D01*
X343125Y71267D01*
X342917Y71058D01*
X342833Y70808D01*
Y70392D01*
X342708Y70017D01*
X342458Y69767D01*
X342167Y69683D01*
X341875Y69767D01*
X341667Y69975D01*
X341542Y70308D01*
X341500Y70600D01*
G01X341875Y72783D02*
X341667Y73033D01*
X341542Y73325D01*
X341500Y73700D01*
X341583Y74075D01*
X341750Y74367D01*
X342042Y74575D01*
X342375Y74617D01*
X342708Y74533D01*
X342917Y74325D01*
X343083Y74033D01*
X343125Y73742D01*
X343083Y73450D01*
X342917Y73075D01*
X344000Y73200D01*
Y74325D01*
G01X343000Y110840D02*
X339000D01*
Y118240D01*
G01X332833Y108965D02*
X332625Y109298D01*
X332500Y109673D01*
Y110007D01*
X332625Y110340D01*
X332833Y110590D01*
X333125Y110715D01*
X333417Y110632D01*
X333667Y110423D01*
X333833Y110048D01*
X333917Y109548D01*
X334083Y109257D01*
X334375Y109132D01*
X334667Y109215D01*
X334875Y109423D01*
X335000Y109715D01*
Y110007D01*
X334917Y110298D01*
X334708Y110548D01*
G01X334792Y113857D02*
X334917Y113607D01*
X335000Y113315D01*
Y112982D01*
X334875Y112607D01*
X334667Y112315D01*
X334417Y112107D01*
X334000Y111940D01*
X333625Y111898D01*
X333250Y111982D01*
X333000Y112107D01*
X332750Y112357D01*
X332583Y112648D01*
X332500Y112940D01*
Y113232D01*
X332583Y113523D01*
X332708Y113773D01*
X332875Y113982D01*
G01X332500Y116040D02*
X332542Y116332D01*
X332667Y116665D01*
X332875Y116873D01*
X333167Y116957D01*
X333458Y116873D01*
X333708Y116623D01*
X333833Y116248D01*
Y115832D01*
X333917Y115582D01*
X334125Y115373D01*
X334417Y115290D01*
X334708Y115415D01*
X334917Y115707D01*
X335000Y116040D01*
X334917Y116373D01*
X334708Y116665D01*
X334417Y116790D01*
X334125Y116707D01*
X333917Y116498D01*
X333833Y116248D01*
Y115832D01*
X333708Y115457D01*
X333458Y115207D01*
X333167Y115123D01*
X332875Y115207D01*
X332667Y115415D01*
X332542Y115748D01*
X332500Y116040D01*
G01Y119057D02*
X333042Y119140D01*
X333500Y119265D01*
X333917Y119432D01*
X334375Y119640D01*
X335000Y119973D01*
Y118307D01*
G01X332500Y122157D02*
X333042Y122240D01*
X333500Y122365D01*
X333917Y122532D01*
X334375Y122740D01*
X335000Y123073D01*
Y121407D01*
G01X349504Y134333D02*
X349171Y134125D01*
X348796Y134000D01*
X348462D01*
X348129Y134125D01*
X347879Y134333D01*
X347754Y134625D01*
X347837Y134917D01*
X348046Y135167D01*
X348421Y135333D01*
X348921Y135417D01*
X349212Y135583D01*
X349337Y135875D01*
X349254Y136167D01*
X349046Y136375D01*
X348754Y136500D01*
X348462D01*
X348171Y136417D01*
X347921Y136208D01*
G01X344612Y136292D02*
X344862Y136417D01*
X345154Y136500D01*
X345487D01*
X345862Y136375D01*
X346154Y136167D01*
X346362Y135917D01*
X346529Y135500D01*
X346571Y135125D01*
X346487Y134750D01*
X346362Y134500D01*
X346112Y134250D01*
X345821Y134083D01*
X345529Y134000D01*
X345237D01*
X344946Y134083D01*
X344696Y134208D01*
X344487Y134375D01*
G01X343137Y134292D02*
X342846Y134083D01*
X342512Y134000D01*
X342179Y134083D01*
X341887Y134333D01*
X341679Y134708D01*
X341596Y135083D01*
Y135542D01*
X341679Y135917D01*
X341887Y136250D01*
X342137Y136417D01*
X342429Y136500D01*
X342762Y136417D01*
X343012Y136250D01*
X343179Y136000D01*
X343262Y135667D01*
X343179Y135375D01*
X342971Y135083D01*
X342721Y134917D01*
X342429Y134875D01*
X342096Y134958D01*
X341846Y135167D01*
X341596Y135542D01*
G01X340246Y134375D02*
X339996Y134167D01*
X339704Y134042D01*
X339329Y134000D01*
X338954Y134083D01*
X338662Y134250D01*
X338454Y134542D01*
X338412Y134875D01*
X338496Y135208D01*
X338704Y135417D01*
X338996Y135583D01*
X339287Y135625D01*
X339579Y135583D01*
X339954Y135417D01*
X339829Y136500D01*
X338704D01*
G01X336229Y134000D02*
X335937Y134042D01*
X335604Y134167D01*
X335396Y134375D01*
X335312Y134667D01*
X335396Y134958D01*
X335646Y135208D01*
X336021Y135333D01*
X336437D01*
X336687Y135417D01*
X336896Y135625D01*
X336979Y135917D01*
X336854Y136208D01*
X336562Y136417D01*
X336229Y136500D01*
X335896Y136417D01*
X335604Y136208D01*
X335479Y135917D01*
X335562Y135625D01*
X335771Y135417D01*
X336021Y135333D01*
X336437D01*
X336812Y135208D01*
X337062Y134958D01*
X337146Y134667D01*
X337062Y134375D01*
X336854Y134167D01*
X336521Y134042D01*
X336229Y134000D01*
G01X349504Y129833D02*
X349171Y129625D01*
X348796Y129500D01*
X348462D01*
X348129Y129625D01*
X347879Y129833D01*
X347754Y130125D01*
X347837Y130417D01*
X348046Y130667D01*
X348421Y130833D01*
X348921Y130917D01*
X349212Y131083D01*
X349337Y131375D01*
X349254Y131667D01*
X349046Y131875D01*
X348754Y132000D01*
X348462D01*
X348171Y131917D01*
X347921Y131708D01*
G01X344612Y131792D02*
X344862Y131917D01*
X345154Y132000D01*
X345487D01*
X345862Y131875D01*
X346154Y131667D01*
X346362Y131417D01*
X346529Y131000D01*
X346571Y130625D01*
X346487Y130250D01*
X346362Y130000D01*
X346112Y129750D01*
X345821Y129583D01*
X345529Y129500D01*
X345237D01*
X344946Y129583D01*
X344696Y129708D01*
X344487Y129875D01*
G01X343137Y129792D02*
X342846Y129583D01*
X342512Y129500D01*
X342179Y129583D01*
X341887Y129833D01*
X341679Y130208D01*
X341596Y130583D01*
Y131042D01*
X341679Y131417D01*
X341887Y131750D01*
X342137Y131917D01*
X342429Y132000D01*
X342762Y131917D01*
X343012Y131750D01*
X343179Y131500D01*
X343262Y131167D01*
X343179Y130875D01*
X342971Y130583D01*
X342721Y130417D01*
X342429Y130375D01*
X342096Y130458D01*
X341846Y130667D01*
X341596Y131042D01*
G01X340246Y129875D02*
X339996Y129667D01*
X339704Y129542D01*
X339329Y129500D01*
X338954Y129583D01*
X338662Y129750D01*
X338454Y130042D01*
X338412Y130375D01*
X338496Y130708D01*
X338704Y130917D01*
X338996Y131083D01*
X339287Y131125D01*
X339579Y131083D01*
X339954Y130917D01*
X339829Y132000D01*
X338704D01*
G01X336937Y129792D02*
X336646Y129583D01*
X336312Y129500D01*
X335979Y129583D01*
X335687Y129833D01*
X335479Y130208D01*
X335396Y130583D01*
Y131042D01*
X335479Y131417D01*
X335687Y131750D01*
X335937Y131917D01*
X336229Y132000D01*
X336562Y131917D01*
X336812Y131750D01*
X336979Y131500D01*
X337062Y131167D01*
X336979Y130875D01*
X336771Y130583D01*
X336521Y130417D01*
X336229Y130375D01*
X335896Y130458D01*
X335646Y130667D01*
X335396Y131042D01*
G01X349504Y138833D02*
X349171Y138625D01*
X348796Y138500D01*
X348462D01*
X348129Y138625D01*
X347879Y138833D01*
X347754Y139125D01*
X347837Y139417D01*
X348046Y139667D01*
X348421Y139833D01*
X348921Y139917D01*
X349212Y140083D01*
X349337Y140375D01*
X349254Y140667D01*
X349046Y140875D01*
X348754Y141000D01*
X348462D01*
X348171Y140917D01*
X347921Y140708D01*
G01X344612Y140792D02*
X344862Y140917D01*
X345154Y141000D01*
X345487D01*
X345862Y140875D01*
X346154Y140667D01*
X346362Y140417D01*
X346529Y140000D01*
X346571Y139625D01*
X346487Y139250D01*
X346362Y139000D01*
X346112Y138750D01*
X345821Y138583D01*
X345529Y138500D01*
X345237D01*
X344946Y138583D01*
X344696Y138708D01*
X344487Y138875D01*
G01X343137Y138792D02*
X342846Y138583D01*
X342512Y138500D01*
X342179Y138583D01*
X341887Y138833D01*
X341679Y139208D01*
X341596Y139583D01*
Y140042D01*
X341679Y140417D01*
X341887Y140750D01*
X342137Y140917D01*
X342429Y141000D01*
X342762Y140917D01*
X343012Y140750D01*
X343179Y140500D01*
X343262Y140167D01*
X343179Y139875D01*
X342971Y139583D01*
X342721Y139417D01*
X342429Y139375D01*
X342096Y139458D01*
X341846Y139667D01*
X341596Y140042D01*
G01X340246Y139000D02*
X339996Y138708D01*
X339662Y138542D01*
X339287Y138500D01*
X338954Y138542D01*
X338621Y138750D01*
X338412Y139000D01*
X338371Y139250D01*
X338454Y139542D01*
X338746Y139750D01*
X339037Y139833D01*
X339412D01*
G01X339037D02*
X338787Y139958D01*
X338579Y140167D01*
X338496Y140417D01*
X338579Y140667D01*
X338787Y140875D01*
X339162Y141000D01*
X339537Y140958D01*
X339912Y140792D01*
G01X336229Y138500D02*
X335937Y138542D01*
X335604Y138667D01*
X335396Y138875D01*
X335312Y139167D01*
X335396Y139458D01*
X335646Y139708D01*
X336021Y139833D01*
X336437D01*
X336687Y139917D01*
X336896Y140125D01*
X336979Y140417D01*
X336854Y140708D01*
X336562Y140917D01*
X336229Y141000D01*
X335896Y140917D01*
X335604Y140708D01*
X335479Y140417D01*
X335562Y140125D01*
X335771Y139917D01*
X336021Y139833D01*
X336437D01*
X336812Y139708D01*
X337062Y139458D01*
X337146Y139167D01*
X337062Y138875D01*
X336854Y138667D01*
X336521Y138542D01*
X336229Y138500D01*
G01X349504Y148333D02*
X349171Y148125D01*
X348796Y148000D01*
X348462D01*
X348129Y148125D01*
X347879Y148333D01*
X347754Y148625D01*
X347837Y148917D01*
X348046Y149167D01*
X348421Y149333D01*
X348921Y149417D01*
X349212Y149583D01*
X349337Y149875D01*
X349254Y150167D01*
X349046Y150375D01*
X348754Y150500D01*
X348462D01*
X348171Y150417D01*
X347921Y150208D01*
G01X344612Y150292D02*
X344862Y150417D01*
X345154Y150500D01*
X345487D01*
X345862Y150375D01*
X346154Y150167D01*
X346362Y149917D01*
X346529Y149500D01*
X346571Y149125D01*
X346487Y148750D01*
X346362Y148500D01*
X346112Y148250D01*
X345821Y148083D01*
X345529Y148000D01*
X345237D01*
X344946Y148083D01*
X344696Y148208D01*
X344487Y148375D01*
G01X343137Y148292D02*
X342846Y148083D01*
X342512Y148000D01*
X342179Y148083D01*
X341887Y148333D01*
X341679Y148708D01*
X341596Y149083D01*
Y149542D01*
X341679Y149917D01*
X341887Y150250D01*
X342137Y150417D01*
X342429Y150500D01*
X342762Y150417D01*
X343012Y150250D01*
X343179Y150000D01*
X343262Y149667D01*
X343179Y149375D01*
X342971Y149083D01*
X342721Y148917D01*
X342429Y148875D01*
X342096Y148958D01*
X341846Y149167D01*
X341596Y149542D01*
G01X340121Y149042D02*
X339829Y149333D01*
X339579Y149500D01*
X339246Y149583D01*
X338954Y149500D01*
X338746Y149333D01*
X338579Y149083D01*
X338537Y148792D01*
X338579Y148542D01*
X338746Y148292D01*
X338996Y148083D01*
X339287Y148000D01*
X339621Y148083D01*
X339912Y148333D01*
X340079Y148708D01*
X340121Y149125D01*
X340037Y149667D01*
X339912Y149958D01*
X339704Y150250D01*
X339412Y150458D01*
X339121Y150500D01*
X338829Y150417D01*
X338621Y150208D01*
G01X336229Y148000D02*
Y150500D01*
X336729Y150000D01*
G01Y148000D02*
X335729D01*
G01X349504Y143833D02*
X349171Y143625D01*
X348796Y143500D01*
X348462D01*
X348129Y143625D01*
X347879Y143833D01*
X347754Y144125D01*
X347837Y144417D01*
X348046Y144667D01*
X348421Y144833D01*
X348921Y144917D01*
X349212Y145083D01*
X349337Y145375D01*
X349254Y145667D01*
X349046Y145875D01*
X348754Y146000D01*
X348462D01*
X348171Y145917D01*
X347921Y145708D01*
G01X344612Y145792D02*
X344862Y145917D01*
X345154Y146000D01*
X345487D01*
X345862Y145875D01*
X346154Y145667D01*
X346362Y145417D01*
X346529Y145000D01*
X346571Y144625D01*
X346487Y144250D01*
X346362Y144000D01*
X346112Y143750D01*
X345821Y143583D01*
X345529Y143500D01*
X345237D01*
X344946Y143583D01*
X344696Y143708D01*
X344487Y143875D01*
G01X343137Y143792D02*
X342846Y143583D01*
X342512Y143500D01*
X342179Y143583D01*
X341887Y143833D01*
X341679Y144208D01*
X341596Y144583D01*
Y145042D01*
X341679Y145417D01*
X341887Y145750D01*
X342137Y145917D01*
X342429Y146000D01*
X342762Y145917D01*
X343012Y145750D01*
X343179Y145500D01*
X343262Y145167D01*
X343179Y144875D01*
X342971Y144583D01*
X342721Y144417D01*
X342429Y144375D01*
X342096Y144458D01*
X341846Y144667D01*
X341596Y145042D01*
G01X340121Y144542D02*
X339829Y144833D01*
X339579Y145000D01*
X339246Y145083D01*
X338954Y145000D01*
X338746Y144833D01*
X338579Y144583D01*
X338537Y144292D01*
X338579Y144042D01*
X338746Y143792D01*
X338996Y143583D01*
X339287Y143500D01*
X339621Y143583D01*
X339912Y143833D01*
X340079Y144208D01*
X340121Y144625D01*
X340037Y145167D01*
X339912Y145458D01*
X339704Y145750D01*
X339412Y145958D01*
X339121Y146000D01*
X338829Y145917D01*
X338621Y145708D01*
G01X336229Y146000D02*
X336562Y145917D01*
X336812Y145708D01*
X336979Y145458D01*
X337104Y145125D01*
X337146Y144750D01*
X337104Y144375D01*
X336979Y144042D01*
X336812Y143792D01*
X336562Y143583D01*
X336229Y143500D01*
X335896Y143583D01*
X335646Y143792D01*
X335479Y144042D01*
X335354Y144375D01*
X335312Y144750D01*
X335354Y145125D01*
X335479Y145458D01*
X335646Y145708D01*
X335896Y145917D01*
X336229Y146000D01*
G01X346333Y153425D02*
X346125Y153758D01*
X346000Y154133D01*
Y154467D01*
X346125Y154800D01*
X346333Y155050D01*
X346625Y155175D01*
X346917Y155092D01*
X347167Y154883D01*
X347333Y154508D01*
X347417Y154008D01*
X347583Y153717D01*
X347875Y153592D01*
X348167Y153675D01*
X348375Y153883D01*
X348500Y154175D01*
Y154467D01*
X348417Y154758D01*
X348208Y155008D01*
G01X348292Y158317D02*
X348417Y158067D01*
X348500Y157775D01*
Y157442D01*
X348375Y157067D01*
X348167Y156775D01*
X347917Y156567D01*
X347500Y156400D01*
X347125Y156358D01*
X346750Y156442D01*
X346500Y156567D01*
X346250Y156817D01*
X346083Y157108D01*
X346000Y157400D01*
Y157692D01*
X346083Y157983D01*
X346208Y158233D01*
X346375Y158442D01*
G01X346292Y159792D02*
X346083Y160083D01*
X346000Y160417D01*
X346083Y160750D01*
X346333Y161042D01*
X346708Y161250D01*
X347083Y161333D01*
X347542D01*
X347917Y161250D01*
X348250Y161042D01*
X348417Y160792D01*
X348500Y160500D01*
X348417Y160167D01*
X348250Y159917D01*
X348000Y159750D01*
X347667Y159667D01*
X347375Y159750D01*
X347083Y159958D01*
X346917Y160208D01*
X346875Y160500D01*
X346958Y160833D01*
X347167Y161083D01*
X347542Y161333D01*
G01X346375Y162683D02*
X346167Y162933D01*
X346042Y163225D01*
X346000Y163600D01*
X346083Y163975D01*
X346250Y164267D01*
X346542Y164475D01*
X346875Y164517D01*
X347208Y164433D01*
X347417Y164225D01*
X347583Y163933D01*
X347625Y163642D01*
X347583Y163350D01*
X347417Y162975D01*
X348500Y163100D01*
Y164225D01*
G01X346375Y165783D02*
X346167Y166033D01*
X346042Y166325D01*
X346000Y166700D01*
X346083Y167075D01*
X346250Y167367D01*
X346542Y167575D01*
X346875Y167617D01*
X347208Y167533D01*
X347417Y167325D01*
X347583Y167033D01*
X347625Y166742D01*
X347583Y166450D01*
X347417Y166075D01*
X348500Y166200D01*
Y167325D01*
G01X341333Y153425D02*
X341125Y153758D01*
X341000Y154133D01*
Y154467D01*
X341125Y154800D01*
X341333Y155050D01*
X341625Y155175D01*
X341917Y155092D01*
X342167Y154883D01*
X342333Y154508D01*
X342417Y154008D01*
X342583Y153717D01*
X342875Y153592D01*
X343167Y153675D01*
X343375Y153883D01*
X343500Y154175D01*
Y154467D01*
X343417Y154758D01*
X343208Y155008D01*
G01X343292Y158317D02*
X343417Y158067D01*
X343500Y157775D01*
Y157442D01*
X343375Y157067D01*
X343167Y156775D01*
X342917Y156567D01*
X342500Y156400D01*
X342125Y156358D01*
X341750Y156442D01*
X341500Y156567D01*
X341250Y156817D01*
X341083Y157108D01*
X341000Y157400D01*
Y157692D01*
X341083Y157983D01*
X341208Y158233D01*
X341375Y158442D01*
G01X341292Y159792D02*
X341083Y160083D01*
X341000Y160417D01*
X341083Y160750D01*
X341333Y161042D01*
X341708Y161250D01*
X342083Y161333D01*
X342542D01*
X342917Y161250D01*
X343250Y161042D01*
X343417Y160792D01*
X343500Y160500D01*
X343417Y160167D01*
X343250Y159917D01*
X343000Y159750D01*
X342667Y159667D01*
X342375Y159750D01*
X342083Y159958D01*
X341917Y160208D01*
X341875Y160500D01*
X341958Y160833D01*
X342167Y161083D01*
X342542Y161333D01*
G01X341375Y162683D02*
X341167Y162933D01*
X341042Y163225D01*
X341000Y163600D01*
X341083Y163975D01*
X341250Y164267D01*
X341542Y164475D01*
X341875Y164517D01*
X342208Y164433D01*
X342417Y164225D01*
X342583Y163933D01*
X342625Y163642D01*
X342583Y163350D01*
X342417Y162975D01*
X343500Y163100D01*
Y164225D01*
G01X341000Y167200D02*
X343500D01*
X341708Y165658D01*
Y167742D01*
G01X351780Y181800D02*
Y177800D01*
X344380D01*
G01X335229Y187000D02*
Y191000D01*
X342629D01*
G01X331262Y173875D02*
X331054Y174208D01*
X330929Y174583D01*
Y174917D01*
X331054Y175250D01*
X331262Y175500D01*
X331554Y175625D01*
X331846Y175542D01*
X332096Y175333D01*
X332262Y174958D01*
X332346Y174458D01*
X332512Y174167D01*
X332804Y174042D01*
X333096Y174125D01*
X333304Y174333D01*
X333429Y174625D01*
Y174917D01*
X333346Y175208D01*
X333137Y175458D01*
G01X333221Y178767D02*
X333346Y178517D01*
X333429Y178225D01*
Y177892D01*
X333304Y177517D01*
X333096Y177225D01*
X332846Y177017D01*
X332429Y176850D01*
X332054Y176808D01*
X331679Y176892D01*
X331429Y177017D01*
X331179Y177267D01*
X331012Y177558D01*
X330929Y177850D01*
Y178142D01*
X331012Y178433D01*
X331137Y178683D01*
X331304Y178892D01*
G01X330929Y180950D02*
X333429D01*
X332929Y180450D01*
G01X330929D02*
Y181450D01*
G01X333429Y184050D02*
X333346Y183717D01*
X333137Y183467D01*
X332887Y183300D01*
X332554Y183175D01*
X332179Y183133D01*
X331804Y183175D01*
X331471Y183300D01*
X331221Y183467D01*
X331012Y183717D01*
X330929Y184050D01*
X331012Y184383D01*
X331221Y184633D01*
X331471Y184800D01*
X331804Y184925D01*
X332179Y184967D01*
X332554Y184925D01*
X332887Y184800D01*
X333137Y184633D01*
X333346Y184383D01*
X333429Y184050D01*
G01X331971Y186358D02*
X332262Y186650D01*
X332429Y186900D01*
X332512Y187233D01*
X332429Y187525D01*
X332262Y187733D01*
X332012Y187900D01*
X331721Y187942D01*
X331471Y187900D01*
X331221Y187733D01*
X331012Y187483D01*
X330929Y187192D01*
X331012Y186858D01*
X331262Y186567D01*
X331637Y186400D01*
X332054Y186358D01*
X332596Y186442D01*
X332887Y186567D01*
X333179Y186775D01*
X333387Y187067D01*
X333429Y187358D01*
X333346Y187650D01*
X333137Y187858D01*
G01X331971Y189458D02*
X332262Y189750D01*
X332429Y190000D01*
X332512Y190333D01*
X332429Y190625D01*
X332262Y190833D01*
X332012Y191000D01*
X331721Y191042D01*
X331471Y191000D01*
X331221Y190833D01*
X331012Y190583D01*
X330929Y190292D01*
X331012Y189958D01*
X331262Y189667D01*
X331637Y189500D01*
X332054Y189458D01*
X332596Y189542D01*
X332887Y189667D01*
X333179Y189875D01*
X333387Y190167D01*
X333429Y190458D01*
X333346Y190750D01*
X333137Y190958D01*
G01X335340Y191000D02*
Y195000D01*
X342740D01*
G01X331262Y193425D02*
X331054Y193758D01*
X330929Y194133D01*
Y194467D01*
X331054Y194800D01*
X331262Y195050D01*
X331554Y195175D01*
X331846Y195092D01*
X332096Y194883D01*
X332262Y194508D01*
X332346Y194008D01*
X332512Y193717D01*
X332804Y193592D01*
X333096Y193675D01*
X333304Y193883D01*
X333429Y194175D01*
Y194467D01*
X333346Y194758D01*
X333137Y195008D01*
G01X330929Y196567D02*
X333429D01*
Y197608D01*
X333304Y197942D01*
X333137Y198150D01*
X332804Y198233D01*
X332471Y198150D01*
X332262Y197900D01*
X332137Y197608D01*
Y196567D01*
G01Y197608D02*
X330929Y198233D01*
G01X331971Y199708D02*
X332262Y200000D01*
X332429Y200250D01*
X332512Y200583D01*
X332429Y200875D01*
X332262Y201083D01*
X332012Y201250D01*
X331721Y201292D01*
X331471Y201250D01*
X331221Y201083D01*
X331012Y200833D01*
X330929Y200542D01*
X331012Y200208D01*
X331262Y199917D01*
X331637Y199750D01*
X332054Y199708D01*
X332596Y199792D01*
X332887Y199917D01*
X333179Y200125D01*
X333387Y200417D01*
X333429Y200708D01*
X333346Y201000D01*
X333137Y201208D01*
G01X333012Y202808D02*
X333262Y203058D01*
X333387Y203350D01*
X333429Y203683D01*
X333346Y204100D01*
X333137Y204392D01*
X332887Y204475D01*
X332637Y204433D01*
X332429Y204267D01*
X332012Y203433D01*
X331721Y203058D01*
X331304Y202808D01*
X330929Y202725D01*
Y204475D01*
G01X331221Y205992D02*
X331012Y206283D01*
X330929Y206617D01*
X331012Y206950D01*
X331262Y207242D01*
X331637Y207450D01*
X332012Y207533D01*
X332471D01*
X332846Y207450D01*
X333179Y207242D01*
X333346Y206992D01*
X333429Y206700D01*
X333346Y206367D01*
X333179Y206117D01*
X332929Y205950D01*
X332596Y205867D01*
X332304Y205950D01*
X332012Y206158D01*
X331846Y206408D01*
X331804Y206700D01*
X331887Y207033D01*
X332096Y207283D01*
X332471Y207533D01*
G01X335340Y195500D02*
Y199500D01*
X342740D01*
G01X342040Y212700D02*
X346040D01*
Y205300D01*
G01X339762Y223925D02*
X339554Y224258D01*
X339429Y224633D01*
Y224967D01*
X339554Y225300D01*
X339762Y225550D01*
X340054Y225675D01*
X340346Y225592D01*
X340596Y225383D01*
X340762Y225008D01*
X340846Y224508D01*
X341012Y224217D01*
X341304Y224092D01*
X341596Y224175D01*
X341804Y224383D01*
X341929Y224675D01*
Y224967D01*
X341846Y225258D01*
X341637Y225508D01*
G01X339429Y227067D02*
X341929D01*
Y228108D01*
X341804Y228442D01*
X341637Y228650D01*
X341304Y228733D01*
X340971Y228650D01*
X340762Y228400D01*
X340637Y228108D01*
Y227067D01*
G01Y228108D02*
X339429Y228733D01*
G01X340471Y230208D02*
X340762Y230500D01*
X340929Y230750D01*
X341012Y231083D01*
X340929Y231375D01*
X340762Y231583D01*
X340512Y231750D01*
X340221Y231792D01*
X339971Y231750D01*
X339721Y231583D01*
X339512Y231333D01*
X339429Y231042D01*
X339512Y230708D01*
X339762Y230417D01*
X340137Y230250D01*
X340554Y230208D01*
X341096Y230292D01*
X341387Y230417D01*
X341679Y230625D01*
X341887Y230917D01*
X341929Y231208D01*
X341846Y231500D01*
X341637Y231708D01*
G01X339929Y233183D02*
X339637Y233433D01*
X339471Y233767D01*
X339429Y234142D01*
X339471Y234475D01*
X339679Y234808D01*
X339929Y235017D01*
X340179Y235058D01*
X340471Y234975D01*
X340679Y234683D01*
X340762Y234392D01*
Y234017D01*
G01Y234392D02*
X340887Y234642D01*
X341096Y234850D01*
X341346Y234933D01*
X341596Y234850D01*
X341804Y234642D01*
X341929Y234267D01*
X341887Y233892D01*
X341721Y233517D01*
G01X341929Y237200D02*
X341846Y236867D01*
X341637Y236617D01*
X341387Y236450D01*
X341054Y236325D01*
X340679Y236283D01*
X340304Y236325D01*
X339971Y236450D01*
X339721Y236617D01*
X339512Y236867D01*
X339429Y237200D01*
X339512Y237533D01*
X339721Y237783D01*
X339971Y237950D01*
X340304Y238075D01*
X340679Y238117D01*
X341054Y238075D01*
X341387Y237950D01*
X341637Y237783D01*
X341846Y237533D01*
X341929Y237200D01*
G01X344873Y223925D02*
X344665Y224258D01*
X344540Y224633D01*
Y224967D01*
X344665Y225300D01*
X344873Y225550D01*
X345165Y225675D01*
X345457Y225592D01*
X345707Y225383D01*
X345873Y225008D01*
X345957Y224508D01*
X346123Y224217D01*
X346415Y224092D01*
X346707Y224175D01*
X346915Y224383D01*
X347040Y224675D01*
Y224967D01*
X346957Y225258D01*
X346748Y225508D01*
G01X344540Y227067D02*
X347040D01*
Y228108D01*
X346915Y228442D01*
X346748Y228650D01*
X346415Y228733D01*
X346082Y228650D01*
X345873Y228400D01*
X345748Y228108D01*
Y227067D01*
G01Y228108D02*
X344540Y228733D01*
G01X345582Y230208D02*
X345873Y230500D01*
X346040Y230750D01*
X346123Y231083D01*
X346040Y231375D01*
X345873Y231583D01*
X345623Y231750D01*
X345332Y231792D01*
X345082Y231750D01*
X344832Y231583D01*
X344623Y231333D01*
X344540Y231042D01*
X344623Y230708D01*
X344873Y230417D01*
X345248Y230250D01*
X345665Y230208D01*
X346207Y230292D01*
X346498Y230417D01*
X346790Y230625D01*
X346998Y230917D01*
X347040Y231208D01*
X346957Y231500D01*
X346748Y231708D01*
G01X345040Y233183D02*
X344748Y233433D01*
X344582Y233767D01*
X344540Y234142D01*
X344582Y234475D01*
X344790Y234808D01*
X345040Y235017D01*
X345290Y235058D01*
X345582Y234975D01*
X345790Y234683D01*
X345873Y234392D01*
Y234017D01*
G01Y234392D02*
X345998Y234642D01*
X346207Y234850D01*
X346457Y234933D01*
X346707Y234850D01*
X346915Y234642D01*
X347040Y234267D01*
X346998Y233892D01*
X346832Y233517D01*
G01X344540Y237200D02*
X347040D01*
X346540Y236700D01*
G01X344540D02*
Y237700D01*
G01X344762Y241875D02*
X344554Y242208D01*
X344429Y242583D01*
Y242917D01*
X344554Y243250D01*
X344762Y243500D01*
X345054Y243625D01*
X345346Y243542D01*
X345596Y243333D01*
X345762Y242958D01*
X345846Y242458D01*
X346012Y242167D01*
X346304Y242042D01*
X346596Y242125D01*
X346804Y242333D01*
X346929Y242625D01*
Y242917D01*
X346846Y243208D01*
X346637Y243458D01*
G01X346721Y246767D02*
X346846Y246517D01*
X346929Y246225D01*
Y245892D01*
X346804Y245517D01*
X346596Y245225D01*
X346346Y245017D01*
X345929Y244850D01*
X345554Y244808D01*
X345179Y244892D01*
X344929Y245017D01*
X344679Y245267D01*
X344512Y245558D01*
X344429Y245850D01*
Y246142D01*
X344512Y246433D01*
X344637Y246683D01*
X344804Y246892D01*
G01X344429Y248950D02*
X346929D01*
X346429Y248450D01*
G01X344429D02*
Y249450D01*
G01X346929Y252050D02*
X346846Y251717D01*
X346637Y251467D01*
X346387Y251300D01*
X346054Y251175D01*
X345679Y251133D01*
X345304Y251175D01*
X344971Y251300D01*
X344721Y251467D01*
X344512Y251717D01*
X344429Y252050D01*
X344512Y252383D01*
X344721Y252633D01*
X344971Y252800D01*
X345304Y252925D01*
X345679Y252967D01*
X346054Y252925D01*
X346387Y252800D01*
X346637Y252633D01*
X346846Y252383D01*
X346929Y252050D01*
G01X344429Y255150D02*
X346929D01*
X346429Y254650D01*
G01X344429D02*
Y255650D01*
G01Y258750D02*
X346929D01*
X345137Y257208D01*
Y259292D01*
G01X353185Y266243D02*
X352852Y266035D01*
X352477Y265910D01*
X352143D01*
X351810Y266035D01*
X351560Y266243D01*
X351435Y266535D01*
X351518Y266827D01*
X351727Y267077D01*
X352102Y267243D01*
X352602Y267327D01*
X352893Y267493D01*
X353018Y267785D01*
X352935Y268077D01*
X352727Y268285D01*
X352435Y268410D01*
X352143D01*
X351852Y268327D01*
X351602Y268118D01*
G01X350043Y265910D02*
Y268410D01*
X349002D01*
X348668Y268285D01*
X348460Y268118D01*
X348377Y267785D01*
X348460Y267452D01*
X348710Y267243D01*
X349002Y267118D01*
X350043D01*
G01X349002D02*
X348377Y265910D01*
G01X346902Y266952D02*
X346610Y267243D01*
X346360Y267410D01*
X346027Y267493D01*
X345735Y267410D01*
X345527Y267243D01*
X345360Y266993D01*
X345318Y266702D01*
X345360Y266452D01*
X345527Y266202D01*
X345777Y265993D01*
X346068Y265910D01*
X346402Y265993D01*
X346693Y266243D01*
X346860Y266618D01*
X346902Y267035D01*
X346818Y267577D01*
X346693Y267868D01*
X346485Y268160D01*
X346193Y268368D01*
X345902Y268410D01*
X345610Y268327D01*
X345402Y268118D01*
G01X343802Y266952D02*
X343510Y267243D01*
X343260Y267410D01*
X342927Y267493D01*
X342635Y267410D01*
X342427Y267243D01*
X342260Y266993D01*
X342218Y266702D01*
X342260Y266452D01*
X342427Y266202D01*
X342677Y265993D01*
X342968Y265910D01*
X343302Y265993D01*
X343593Y266243D01*
X343760Y266618D01*
X343802Y267035D01*
X343718Y267577D01*
X343593Y267868D01*
X343385Y268160D01*
X343093Y268368D01*
X342802Y268410D01*
X342510Y268327D01*
X342302Y268118D01*
G01X339993Y265910D02*
X339910Y266452D01*
X339785Y266910D01*
X339618Y267327D01*
X339410Y267785D01*
X339077Y268410D01*
X340743D01*
G01X332500Y285000D02*
Y298000D01*
G01X346500Y285000D02*
X332500D01*
G01X348125Y272333D02*
X347792Y272125D01*
X347417Y272000D01*
X347083D01*
X346750Y272125D01*
X346500Y272333D01*
X346375Y272625D01*
X346458Y272917D01*
X346667Y273167D01*
X347042Y273333D01*
X347542Y273417D01*
X347833Y273583D01*
X347958Y273875D01*
X347875Y274167D01*
X347667Y274375D01*
X347375Y274500D01*
X347083D01*
X346792Y274417D01*
X346542Y274208D01*
G01X343233Y274292D02*
X343483Y274417D01*
X343775Y274500D01*
X344108D01*
X344483Y274375D01*
X344775Y274167D01*
X344983Y273917D01*
X345150Y273500D01*
X345192Y273125D01*
X345108Y272750D01*
X344983Y272500D01*
X344733Y272250D01*
X344442Y272083D01*
X344150Y272000D01*
X343858D01*
X343567Y272083D01*
X343317Y272208D01*
X343108Y272375D01*
G01X341050Y272000D02*
Y274500D01*
X341550Y274000D01*
G01Y272000D02*
X340550D01*
G01X337950Y274500D02*
X338283Y274417D01*
X338533Y274208D01*
X338700Y273958D01*
X338825Y273625D01*
X338867Y273250D01*
X338825Y272875D01*
X338700Y272542D01*
X338533Y272292D01*
X338283Y272083D01*
X337950Y272000D01*
X337617Y272083D01*
X337367Y272292D01*
X337200Y272542D01*
X337075Y272875D01*
X337033Y273250D01*
X337075Y273625D01*
X337200Y273958D01*
X337367Y274208D01*
X337617Y274417D01*
X337950Y274500D01*
G01X334850Y272000D02*
Y274500D01*
X335350Y274000D01*
G01Y272000D02*
X334350D01*
G01X332667Y272500D02*
X332417Y272208D01*
X332083Y272042D01*
X331708Y272000D01*
X331375Y272042D01*
X331042Y272250D01*
X330833Y272500D01*
X330792Y272750D01*
X330875Y273042D01*
X331167Y273250D01*
X331458Y273333D01*
X331833D01*
G01X331458D02*
X331208Y273458D01*
X331000Y273667D01*
X330917Y273917D01*
X331000Y274167D01*
X331208Y274375D01*
X331583Y274500D01*
X331958Y274458D01*
X332333Y274292D01*
G01X348054Y277333D02*
X347721Y277125D01*
X347346Y277000D01*
X347012D01*
X346679Y277125D01*
X346429Y277333D01*
X346304Y277625D01*
X346387Y277917D01*
X346596Y278167D01*
X346971Y278333D01*
X347471Y278417D01*
X347762Y278583D01*
X347887Y278875D01*
X347804Y279167D01*
X347596Y279375D01*
X347304Y279500D01*
X347012D01*
X346721Y279417D01*
X346471Y279208D01*
G01X343162Y279292D02*
X343412Y279417D01*
X343704Y279500D01*
X344037D01*
X344412Y279375D01*
X344704Y279167D01*
X344912Y278917D01*
X345079Y278500D01*
X345121Y278125D01*
X345037Y277750D01*
X344912Y277500D01*
X344662Y277250D01*
X344371Y277083D01*
X344079Y277000D01*
X343787D01*
X343496Y277083D01*
X343246Y277208D01*
X343037Y277375D01*
G01X340979Y277000D02*
Y279500D01*
X341479Y279000D01*
G01Y277000D02*
X340479D01*
G01X337879Y279500D02*
X338212Y279417D01*
X338462Y279208D01*
X338629Y278958D01*
X338754Y278625D01*
X338796Y278250D01*
X338754Y277875D01*
X338629Y277542D01*
X338462Y277292D01*
X338212Y277083D01*
X337879Y277000D01*
X337546Y277083D01*
X337296Y277292D01*
X337129Y277542D01*
X337004Y277875D01*
X336962Y278250D01*
X337004Y278625D01*
X337129Y278958D01*
X337296Y279208D01*
X337546Y279417D01*
X337879Y279500D01*
G01X334779Y277000D02*
Y279500D01*
X335279Y279000D01*
G01Y277000D02*
X334279D01*
G01X332596Y277375D02*
X332346Y277167D01*
X332054Y277042D01*
X331679Y277000D01*
X331304Y277083D01*
X331012Y277250D01*
X330804Y277542D01*
X330762Y277875D01*
X330846Y278208D01*
X331054Y278417D01*
X331346Y278583D01*
X331637Y278625D01*
X331929Y278583D01*
X332304Y278417D01*
X332179Y279500D01*
X331054D01*
G01X345025Y300833D02*
X344692Y300625D01*
X344317Y300500D01*
X343983D01*
X343650Y300625D01*
X343400Y300833D01*
X343275Y301125D01*
X343358Y301417D01*
X343567Y301667D01*
X343942Y301833D01*
X344442Y301917D01*
X344733Y302083D01*
X344858Y302375D01*
X344775Y302667D01*
X344567Y302875D01*
X344275Y303000D01*
X343983D01*
X343692Y302917D01*
X343442Y302708D01*
G01X341050Y300500D02*
X341383Y300542D01*
X341675Y300708D01*
X341925Y300958D01*
X342092Y301250D01*
X342175Y301583D01*
Y301917D01*
X342092Y302250D01*
X341925Y302542D01*
X341675Y302792D01*
X341383Y302958D01*
X341050Y303000D01*
X340717Y302958D01*
X340425Y302792D01*
X340175Y302542D01*
X340008Y302250D01*
X339925Y301917D01*
Y301583D01*
X340008Y301250D01*
X340175Y300958D01*
X340425Y300708D01*
X340717Y300542D01*
X341050Y300500D01*
G01X340717Y301167D02*
X340217Y300500D01*
G01X337950D02*
Y303000D01*
X338450Y302500D01*
G01Y300500D02*
X337450D01*
G01X334850D02*
Y303000D01*
X335350Y302500D01*
G01Y300500D02*
X334350D01*
G01X332500Y298000D02*
X346500D01*
G01X357625Y331833D02*
X357292Y331625D01*
X356917Y331500D01*
X356583D01*
X356250Y331625D01*
X356000Y331833D01*
X355875Y332125D01*
X355958Y332417D01*
X356167Y332667D01*
X356542Y332833D01*
X357042Y332917D01*
X357333Y333083D01*
X357458Y333375D01*
X357375Y333667D01*
X357167Y333875D01*
X356875Y334000D01*
X356583D01*
X356292Y333917D01*
X356042Y333708D01*
G01X352733Y333792D02*
X352983Y333917D01*
X353275Y334000D01*
X353608D01*
X353983Y333875D01*
X354275Y333667D01*
X354483Y333417D01*
X354650Y333000D01*
X354692Y332625D01*
X354608Y332250D01*
X354483Y332000D01*
X354233Y331750D01*
X353942Y331583D01*
X353650Y331500D01*
X353358D01*
X353067Y331583D01*
X352817Y331708D01*
X352608Y331875D01*
G01X350550Y331500D02*
Y334000D01*
X351050Y333500D01*
G01Y331500D02*
X350050D01*
G01X348242Y333583D02*
X347992Y333833D01*
X347700Y333958D01*
X347367Y334000D01*
X346950Y333917D01*
X346658Y333708D01*
X346575Y333458D01*
X346617Y333208D01*
X346783Y333000D01*
X347617Y332583D01*
X347992Y332292D01*
X348242Y331875D01*
X348325Y331500D01*
X346575D01*
G01X345267Y331875D02*
X345017Y331667D01*
X344725Y331542D01*
X344350Y331500D01*
X343975Y331583D01*
X343683Y331750D01*
X343475Y332042D01*
X343433Y332375D01*
X343517Y332708D01*
X343725Y332917D01*
X344017Y333083D01*
X344308Y333125D01*
X344600Y333083D01*
X344975Y332917D01*
X344850Y334000D01*
X343725D01*
G01X342167Y332000D02*
X341917Y331708D01*
X341583Y331542D01*
X341208Y331500D01*
X340875Y331542D01*
X340542Y331750D01*
X340333Y332000D01*
X340292Y332250D01*
X340375Y332542D01*
X340667Y332750D01*
X340958Y332833D01*
X341333D01*
G01X340958D02*
X340708Y332958D01*
X340500Y333167D01*
X340417Y333417D01*
X340500Y333667D01*
X340708Y333875D01*
X341083Y334000D01*
X341458Y333958D01*
X341833Y333792D01*
G01X357625Y327333D02*
X357292Y327125D01*
X356917Y327000D01*
X356583D01*
X356250Y327125D01*
X356000Y327333D01*
X355875Y327625D01*
X355958Y327917D01*
X356167Y328167D01*
X356542Y328333D01*
X357042Y328417D01*
X357333Y328583D01*
X357458Y328875D01*
X357375Y329167D01*
X357167Y329375D01*
X356875Y329500D01*
X356583D01*
X356292Y329417D01*
X356042Y329208D01*
G01X352733Y329292D02*
X352983Y329417D01*
X353275Y329500D01*
X353608D01*
X353983Y329375D01*
X354275Y329167D01*
X354483Y328917D01*
X354650Y328500D01*
X354692Y328125D01*
X354608Y327750D01*
X354483Y327500D01*
X354233Y327250D01*
X353942Y327083D01*
X353650Y327000D01*
X353358D01*
X353067Y327083D01*
X352817Y327208D01*
X352608Y327375D01*
G01X350550Y327000D02*
Y329500D01*
X351050Y329000D01*
G01Y327000D02*
X350050D01*
G01X348242Y329083D02*
X347992Y329333D01*
X347700Y329458D01*
X347367Y329500D01*
X346950Y329417D01*
X346658Y329208D01*
X346575Y328958D01*
X346617Y328708D01*
X346783Y328500D01*
X347617Y328083D01*
X347992Y327792D01*
X348242Y327375D01*
X348325Y327000D01*
X346575D01*
G01X345267Y327375D02*
X345017Y327167D01*
X344725Y327042D01*
X344350Y327000D01*
X343975Y327083D01*
X343683Y327250D01*
X343475Y327542D01*
X343433Y327875D01*
X343517Y328208D01*
X343725Y328417D01*
X344017Y328583D01*
X344308Y328625D01*
X344600Y328583D01*
X344975Y328417D01*
X344850Y329500D01*
X343725D01*
G01X342042Y329083D02*
X341792Y329333D01*
X341500Y329458D01*
X341167Y329500D01*
X340750Y329417D01*
X340458Y329208D01*
X340375Y328958D01*
X340417Y328708D01*
X340583Y328500D01*
X341417Y328083D01*
X341792Y327792D01*
X342042Y327375D01*
X342125Y327000D01*
X340375D01*
G01X347333Y345875D02*
X347125Y346208D01*
X347000Y346583D01*
Y346917D01*
X347125Y347250D01*
X347333Y347500D01*
X347625Y347625D01*
X347917Y347542D01*
X348167Y347333D01*
X348333Y346958D01*
X348417Y346458D01*
X348583Y346167D01*
X348875Y346042D01*
X349167Y346125D01*
X349375Y346333D01*
X349500Y346625D01*
Y346917D01*
X349417Y347208D01*
X349208Y347458D01*
G01X349292Y350767D02*
X349417Y350517D01*
X349500Y350225D01*
Y349892D01*
X349375Y349517D01*
X349167Y349225D01*
X348917Y349017D01*
X348500Y348850D01*
X348125Y348808D01*
X347750Y348892D01*
X347500Y349017D01*
X347250Y349267D01*
X347083Y349558D01*
X347000Y349850D01*
Y350142D01*
X347083Y350433D01*
X347208Y350683D01*
X347375Y350892D01*
G01X347000Y352950D02*
X349500D01*
X349000Y352450D01*
G01X347000D02*
Y353450D01*
G01X349083Y355258D02*
X349333Y355508D01*
X349458Y355800D01*
X349500Y356133D01*
X349417Y356550D01*
X349208Y356842D01*
X348958Y356925D01*
X348708Y356883D01*
X348500Y356717D01*
X348083Y355883D01*
X347792Y355508D01*
X347375Y355258D01*
X347000Y355175D01*
Y356925D01*
G01Y359150D02*
X349500D01*
X349000Y358650D01*
G01X347000D02*
Y359650D01*
G01Y362250D02*
X347042Y362542D01*
X347167Y362875D01*
X347375Y363083D01*
X347667Y363167D01*
X347958Y363083D01*
X348208Y362833D01*
X348333Y362458D01*
Y362042D01*
X348417Y361792D01*
X348625Y361583D01*
X348917Y361500D01*
X349208Y361625D01*
X349417Y361917D01*
X349500Y362250D01*
X349417Y362583D01*
X349208Y362875D01*
X348917Y363000D01*
X348625Y362917D01*
X348417Y362708D01*
X348333Y362458D01*
Y362042D01*
X348208Y361667D01*
X347958Y361417D01*
X347667Y361333D01*
X347375Y361417D01*
X347167Y361625D01*
X347042Y361958D01*
X347000Y362250D01*
G01X428000Y356000D02*
X381500D01*
Y362500D01*
X360500D01*
Y364500D01*
X342000D01*
G01X347075Y388833D02*
X346742Y388625D01*
X346367Y388500D01*
X346033D01*
X345700Y388625D01*
X345450Y388833D01*
X345325Y389125D01*
X345408Y389417D01*
X345617Y389667D01*
X345992Y389833D01*
X346492Y389917D01*
X346783Y390083D01*
X346908Y390375D01*
X346825Y390667D01*
X346617Y390875D01*
X346325Y391000D01*
X346033D01*
X345742Y390917D01*
X345492Y390708D01*
G01X343933Y388500D02*
Y391000D01*
X342892D01*
X342558Y390875D01*
X342350Y390708D01*
X342267Y390375D01*
X342350Y390042D01*
X342600Y389833D01*
X342892Y389708D01*
X343933D01*
G01X342892D02*
X342267Y388500D01*
G01X340000D02*
X339708Y388542D01*
X339375Y388667D01*
X339167Y388875D01*
X339083Y389167D01*
X339167Y389458D01*
X339417Y389708D01*
X339792Y389833D01*
X340208D01*
X340458Y389917D01*
X340667Y390125D01*
X340750Y390417D01*
X340625Y390708D01*
X340333Y390917D01*
X340000Y391000D01*
X339667Y390917D01*
X339375Y390708D01*
X339250Y390417D01*
X339333Y390125D01*
X339542Y389917D01*
X339792Y389833D01*
X340208D01*
X340583Y389708D01*
X340833Y389458D01*
X340917Y389167D01*
X340833Y388875D01*
X340625Y388667D01*
X340292Y388542D01*
X340000Y388500D01*
G01X337692Y390583D02*
X337442Y390833D01*
X337150Y390958D01*
X336817Y391000D01*
X336400Y390917D01*
X336108Y390708D01*
X336025Y390458D01*
X336067Y390208D01*
X336233Y390000D01*
X337067Y389583D01*
X337442Y389292D01*
X337692Y388875D01*
X337775Y388500D01*
X336025D01*
G01X334717Y388875D02*
X334467Y388667D01*
X334175Y388542D01*
X333800Y388500D01*
X333425Y388583D01*
X333133Y388750D01*
X332925Y389042D01*
X332883Y389375D01*
X332967Y389708D01*
X333175Y389917D01*
X333467Y390083D01*
X333758Y390125D01*
X334050Y390083D01*
X334425Y389917D01*
X334300Y391000D01*
X333175D01*
G01X341300Y394000D02*
Y398000D01*
X348700D01*
G01X357823Y402757D02*
X357490Y402549D01*
X357115Y402424D01*
X356781D01*
X356448Y402549D01*
X356198Y402757D01*
X356073Y403049D01*
X356156Y403341D01*
X356365Y403591D01*
X356740Y403757D01*
X357240Y403841D01*
X357531Y404007D01*
X357656Y404299D01*
X357573Y404591D01*
X357365Y404799D01*
X357073Y404924D01*
X356781D01*
X356490Y404841D01*
X356240Y404632D01*
G01X354681Y402424D02*
Y404924D01*
X353640D01*
X353306Y404799D01*
X353098Y404632D01*
X353015Y404299D01*
X353098Y403966D01*
X353348Y403757D01*
X353640Y403632D01*
X354681D01*
G01X353640D02*
X353015Y402424D01*
G01X350748D02*
X350456Y402466D01*
X350123Y402591D01*
X349915Y402799D01*
X349831Y403091D01*
X349915Y403382D01*
X350165Y403632D01*
X350540Y403757D01*
X350956D01*
X351206Y403841D01*
X351415Y404049D01*
X351498Y404341D01*
X351373Y404632D01*
X351081Y404841D01*
X350748Y404924D01*
X350415Y404841D01*
X350123Y404632D01*
X349998Y404341D01*
X350081Y404049D01*
X350290Y403841D01*
X350540Y403757D01*
X350956D01*
X351331Y403632D01*
X351581Y403382D01*
X351665Y403091D01*
X351581Y402799D01*
X351373Y402591D01*
X351040Y402466D01*
X350748Y402424D01*
G01X348440Y404507D02*
X348190Y404757D01*
X347898Y404882D01*
X347565Y404924D01*
X347148Y404841D01*
X346856Y404632D01*
X346773Y404382D01*
X346815Y404132D01*
X346981Y403924D01*
X347815Y403507D01*
X348190Y403216D01*
X348440Y402799D01*
X348523Y402424D01*
X346773D01*
G01X345340Y404507D02*
X345090Y404757D01*
X344798Y404882D01*
X344465Y404924D01*
X344048Y404841D01*
X343756Y404632D01*
X343673Y404382D01*
X343715Y404132D01*
X343881Y403924D01*
X344715Y403507D01*
X345090Y403216D01*
X345340Y402799D01*
X345423Y402424D01*
X343673D01*
G01X352500Y22967D02*
X355000D01*
Y23967D01*
X354875Y24300D01*
X354583Y24550D01*
X354250Y24633D01*
X353917Y24550D01*
X353667Y24342D01*
X353542Y23967D01*
Y22967D01*
G01X352500Y26067D02*
X355000D01*
Y27108D01*
X354875Y27442D01*
X354708Y27650D01*
X354375Y27733D01*
X354042Y27650D01*
X353833Y27400D01*
X353708Y27108D01*
Y26067D01*
G01Y27108D02*
X352500Y27733D01*
G01Y30000D02*
X355000D01*
X354500Y29500D01*
G01X352500D02*
Y30500D01*
G01Y33017D02*
X353042Y33100D01*
X353500Y33225D01*
X353917Y33392D01*
X354375Y33600D01*
X355000Y33933D01*
Y32267D01*
G01X352792Y35492D02*
X352583Y35783D01*
X352500Y36117D01*
X352583Y36450D01*
X352833Y36742D01*
X353208Y36950D01*
X353583Y37033D01*
X354042D01*
X354417Y36950D01*
X354750Y36742D01*
X354917Y36492D01*
X355000Y36200D01*
X354917Y35867D01*
X354750Y35617D01*
X354500Y35450D01*
X354167Y35367D01*
X353875Y35450D01*
X353583Y35658D01*
X353417Y35908D01*
X353375Y36200D01*
X353458Y36533D01*
X353667Y36783D01*
X354042Y37033D01*
G01X355500Y9800D02*
X351500D01*
Y17200D01*
G01X348333Y21375D02*
X348125Y21708D01*
X348000Y22083D01*
Y22417D01*
X348125Y22750D01*
X348333Y23000D01*
X348625Y23125D01*
X348917Y23042D01*
X349167Y22833D01*
X349333Y22458D01*
X349417Y21958D01*
X349583Y21667D01*
X349875Y21542D01*
X350167Y21625D01*
X350375Y21833D01*
X350500Y22125D01*
Y22417D01*
X350417Y22708D01*
X350208Y22958D01*
G01X350292Y26267D02*
X350417Y26017D01*
X350500Y25725D01*
Y25392D01*
X350375Y25017D01*
X350167Y24725D01*
X349917Y24517D01*
X349500Y24350D01*
X349125Y24308D01*
X348750Y24392D01*
X348500Y24517D01*
X348250Y24767D01*
X348083Y25058D01*
X348000Y25350D01*
Y25642D01*
X348083Y25933D01*
X348208Y26183D01*
X348375Y26392D01*
G01X348000Y28450D02*
X350500D01*
X350000Y27950D01*
G01X348000D02*
Y28950D01*
G01X350500Y31550D02*
X350417Y31217D01*
X350208Y30967D01*
X349958Y30800D01*
X349625Y30675D01*
X349250Y30633D01*
X348875Y30675D01*
X348542Y30800D01*
X348292Y30967D01*
X348083Y31217D01*
X348000Y31550D01*
X348083Y31883D01*
X348292Y32133D01*
X348542Y32300D01*
X348875Y32425D01*
X349250Y32467D01*
X349625Y32425D01*
X349958Y32300D01*
X350208Y32133D01*
X350417Y31883D01*
X350500Y31550D01*
G01X348500Y33733D02*
X348208Y33983D01*
X348042Y34317D01*
X348000Y34692D01*
X348042Y35025D01*
X348250Y35358D01*
X348500Y35567D01*
X348750Y35608D01*
X349042Y35525D01*
X349250Y35233D01*
X349333Y34942D01*
Y34567D01*
G01Y34942D02*
X349458Y35192D01*
X349667Y35400D01*
X349917Y35483D01*
X350167Y35400D01*
X350375Y35192D01*
X350500Y34817D01*
X350458Y34442D01*
X350292Y34067D01*
G01X348292Y37042D02*
X348083Y37333D01*
X348000Y37667D01*
X348083Y38000D01*
X348333Y38292D01*
X348708Y38500D01*
X349083Y38583D01*
X349542D01*
X349917Y38500D01*
X350250Y38292D01*
X350417Y38042D01*
X350500Y37750D01*
X350417Y37417D01*
X350250Y37167D01*
X350000Y37000D01*
X349667Y36917D01*
X349375Y37000D01*
X349083Y37208D01*
X348917Y37458D01*
X348875Y37750D01*
X348958Y38083D01*
X349167Y38333D01*
X349542Y38583D01*
G01X361833Y21375D02*
X361625Y21708D01*
X361500Y22083D01*
Y22417D01*
X361625Y22750D01*
X361833Y23000D01*
X362125Y23125D01*
X362417Y23042D01*
X362667Y22833D01*
X362833Y22458D01*
X362917Y21958D01*
X363083Y21667D01*
X363375Y21542D01*
X363667Y21625D01*
X363875Y21833D01*
X364000Y22125D01*
Y22417D01*
X363917Y22708D01*
X363708Y22958D01*
G01X363792Y26267D02*
X363917Y26017D01*
X364000Y25725D01*
Y25392D01*
X363875Y25017D01*
X363667Y24725D01*
X363417Y24517D01*
X363000Y24350D01*
X362625Y24308D01*
X362250Y24392D01*
X362000Y24517D01*
X361750Y24767D01*
X361583Y25058D01*
X361500Y25350D01*
Y25642D01*
X361583Y25933D01*
X361708Y26183D01*
X361875Y26392D01*
G01X361500Y28450D02*
X364000D01*
X363500Y27950D01*
G01X361500D02*
Y28950D01*
G01X364000Y31550D02*
X363917Y31217D01*
X363708Y30967D01*
X363458Y30800D01*
X363125Y30675D01*
X362750Y30633D01*
X362375Y30675D01*
X362042Y30800D01*
X361792Y30967D01*
X361583Y31217D01*
X361500Y31550D01*
X361583Y31883D01*
X361792Y32133D01*
X362042Y32300D01*
X362375Y32425D01*
X362750Y32467D01*
X363125Y32425D01*
X363458Y32300D01*
X363708Y32133D01*
X363917Y31883D01*
X364000Y31550D01*
G01X361875Y33733D02*
X361667Y33983D01*
X361542Y34275D01*
X361500Y34650D01*
X361583Y35025D01*
X361750Y35317D01*
X362042Y35525D01*
X362375Y35567D01*
X362708Y35483D01*
X362917Y35275D01*
X363083Y34983D01*
X363125Y34692D01*
X363083Y34400D01*
X362917Y34025D01*
X364000Y34150D01*
Y35275D01*
G01Y37750D02*
X363917Y37417D01*
X363708Y37167D01*
X363458Y37000D01*
X363125Y36875D01*
X362750Y36833D01*
X362375Y36875D01*
X362042Y37000D01*
X361792Y37167D01*
X361583Y37417D01*
X361500Y37750D01*
X361583Y38083D01*
X361792Y38333D01*
X362042Y38500D01*
X362375Y38625D01*
X362750Y38667D01*
X363125Y38625D01*
X363458Y38500D01*
X363708Y38333D01*
X363917Y38083D01*
X364000Y37750D01*
G01X357333Y21375D02*
X357125Y21708D01*
X357000Y22083D01*
Y22417D01*
X357125Y22750D01*
X357333Y23000D01*
X357625Y23125D01*
X357917Y23042D01*
X358167Y22833D01*
X358333Y22458D01*
X358417Y21958D01*
X358583Y21667D01*
X358875Y21542D01*
X359167Y21625D01*
X359375Y21833D01*
X359500Y22125D01*
Y22417D01*
X359417Y22708D01*
X359208Y22958D01*
G01X359292Y26267D02*
X359417Y26017D01*
X359500Y25725D01*
Y25392D01*
X359375Y25017D01*
X359167Y24725D01*
X358917Y24517D01*
X358500Y24350D01*
X358125Y24308D01*
X357750Y24392D01*
X357500Y24517D01*
X357250Y24767D01*
X357083Y25058D01*
X357000Y25350D01*
Y25642D01*
X357083Y25933D01*
X357208Y26183D01*
X357375Y26392D01*
G01X357000Y28450D02*
X359500D01*
X359000Y27950D01*
G01X357000D02*
Y28950D01*
G01X359500Y31550D02*
X359417Y31217D01*
X359208Y30967D01*
X358958Y30800D01*
X358625Y30675D01*
X358250Y30633D01*
X357875Y30675D01*
X357542Y30800D01*
X357292Y30967D01*
X357083Y31217D01*
X357000Y31550D01*
X357083Y31883D01*
X357292Y32133D01*
X357542Y32300D01*
X357875Y32425D01*
X358250Y32467D01*
X358625Y32425D01*
X358958Y32300D01*
X359208Y32133D01*
X359417Y31883D01*
X359500Y31550D01*
G01X357375Y33733D02*
X357167Y33983D01*
X357042Y34275D01*
X357000Y34650D01*
X357083Y35025D01*
X357250Y35317D01*
X357542Y35525D01*
X357875Y35567D01*
X358208Y35483D01*
X358417Y35275D01*
X358583Y34983D01*
X358625Y34692D01*
X358583Y34400D01*
X358417Y34025D01*
X359500Y34150D01*
Y35275D01*
G01X357000Y37750D02*
X359500D01*
X359000Y37250D01*
G01X357000D02*
Y38250D01*
G01X350500Y60467D02*
X353000D01*
Y61467D01*
X352875Y61800D01*
X352583Y62050D01*
X352250Y62133D01*
X351917Y62050D01*
X351667Y61842D01*
X351542Y61467D01*
Y60467D01*
G01X350500Y63567D02*
X353000D01*
Y64608D01*
X352875Y64942D01*
X352708Y65150D01*
X352375Y65233D01*
X352042Y65150D01*
X351833Y64900D01*
X351708Y64608D01*
Y63567D01*
G01Y64608D02*
X350500Y65233D01*
G01Y67500D02*
X353000D01*
X352500Y67000D01*
G01X350500D02*
Y68000D01*
G01Y70600D02*
X350542Y70892D01*
X350667Y71225D01*
X350875Y71433D01*
X351167Y71517D01*
X351458Y71433D01*
X351708Y71183D01*
X351833Y70808D01*
Y70392D01*
X351917Y70142D01*
X352125Y69933D01*
X352417Y69850D01*
X352708Y69975D01*
X352917Y70267D01*
X353000Y70600D01*
X352917Y70933D01*
X352708Y71225D01*
X352417Y71350D01*
X352125Y71267D01*
X351917Y71058D01*
X351833Y70808D01*
Y70392D01*
X351708Y70017D01*
X351458Y69767D01*
X351167Y69683D01*
X350875Y69767D01*
X350667Y69975D01*
X350542Y70308D01*
X350500Y70600D01*
G01X351542Y72908D02*
X351833Y73200D01*
X352000Y73450D01*
X352083Y73783D01*
X352000Y74075D01*
X351833Y74283D01*
X351583Y74450D01*
X351292Y74492D01*
X351042Y74450D01*
X350792Y74283D01*
X350583Y74033D01*
X350500Y73742D01*
X350583Y73408D01*
X350833Y73117D01*
X351208Y72950D01*
X351625Y72908D01*
X352167Y72992D01*
X352458Y73117D01*
X352750Y73325D01*
X352958Y73617D01*
X353000Y73908D01*
X352917Y74200D01*
X352708Y74408D01*
G01X355000Y60467D02*
X357500D01*
Y61467D01*
X357375Y61800D01*
X357083Y62050D01*
X356750Y62133D01*
X356417Y62050D01*
X356167Y61842D01*
X356042Y61467D01*
Y60467D01*
G01X355000Y63567D02*
X357500D01*
Y64608D01*
X357375Y64942D01*
X357208Y65150D01*
X356875Y65233D01*
X356542Y65150D01*
X356333Y64900D01*
X356208Y64608D01*
Y63567D01*
G01Y64608D02*
X355000Y65233D01*
G01Y67500D02*
X357500D01*
X357000Y67000D01*
G01X355000D02*
Y68000D01*
G01Y70600D02*
X355042Y70892D01*
X355167Y71225D01*
X355375Y71433D01*
X355667Y71517D01*
X355958Y71433D01*
X356208Y71183D01*
X356333Y70808D01*
Y70392D01*
X356417Y70142D01*
X356625Y69933D01*
X356917Y69850D01*
X357208Y69975D01*
X357417Y70267D01*
X357500Y70600D01*
X357417Y70933D01*
X357208Y71225D01*
X356917Y71350D01*
X356625Y71267D01*
X356417Y71058D01*
X356333Y70808D01*
Y70392D01*
X356208Y70017D01*
X355958Y69767D01*
X355667Y69683D01*
X355375Y69767D01*
X355167Y69975D01*
X355042Y70308D01*
X355000Y70600D01*
G01Y73617D02*
X355542Y73700D01*
X356000Y73825D01*
X356417Y73992D01*
X356875Y74200D01*
X357500Y74533D01*
Y72867D01*
G01X360000Y60467D02*
X362500D01*
Y61467D01*
X362375Y61800D01*
X362083Y62050D01*
X361750Y62133D01*
X361417Y62050D01*
X361167Y61842D01*
X361042Y61467D01*
Y60467D01*
G01X362292Y65317D02*
X362417Y65067D01*
X362500Y64775D01*
Y64442D01*
X362375Y64067D01*
X362167Y63775D01*
X361917Y63567D01*
X361500Y63400D01*
X361125Y63358D01*
X360750Y63442D01*
X360500Y63567D01*
X360250Y63817D01*
X360083Y64108D01*
X360000Y64400D01*
Y64692D01*
X360083Y64983D01*
X360208Y65233D01*
X360375Y65442D01*
G01X362083Y66708D02*
X362333Y66958D01*
X362458Y67250D01*
X362500Y67583D01*
X362417Y68000D01*
X362208Y68292D01*
X361958Y68375D01*
X361708Y68333D01*
X361500Y68167D01*
X361083Y67333D01*
X360792Y66958D01*
X360375Y66708D01*
X360000Y66625D01*
Y68375D01*
G01X362083Y69808D02*
X362333Y70058D01*
X362458Y70350D01*
X362500Y70683D01*
X362417Y71100D01*
X362208Y71392D01*
X361958Y71475D01*
X361708Y71433D01*
X361500Y71267D01*
X361083Y70433D01*
X360792Y70058D01*
X360375Y69808D01*
X360000Y69725D01*
Y71475D01*
G01X362083Y72908D02*
X362333Y73158D01*
X362458Y73450D01*
X362500Y73783D01*
X362417Y74200D01*
X362208Y74492D01*
X361958Y74575D01*
X361708Y74533D01*
X361500Y74367D01*
X361083Y73533D01*
X360792Y73158D01*
X360375Y72908D01*
X360000Y72825D01*
Y74575D01*
G01X354262Y105925D02*
X354054Y106258D01*
X353929Y106633D01*
Y106967D01*
X354054Y107300D01*
X354262Y107550D01*
X354554Y107675D01*
X354846Y107592D01*
X355096Y107383D01*
X355262Y107008D01*
X355346Y106508D01*
X355512Y106217D01*
X355804Y106092D01*
X356096Y106175D01*
X356304Y106383D01*
X356429Y106675D01*
Y106967D01*
X356346Y107258D01*
X356137Y107508D01*
G01X356221Y110817D02*
X356346Y110567D01*
X356429Y110275D01*
Y109942D01*
X356304Y109567D01*
X356096Y109275D01*
X355846Y109067D01*
X355429Y108900D01*
X355054Y108858D01*
X354679Y108942D01*
X354429Y109067D01*
X354179Y109317D01*
X354012Y109608D01*
X353929Y109900D01*
Y110192D01*
X354012Y110483D01*
X354137Y110733D01*
X354304Y110942D01*
G01X353929Y113000D02*
X353971Y113292D01*
X354096Y113625D01*
X354304Y113833D01*
X354596Y113917D01*
X354887Y113833D01*
X355137Y113583D01*
X355262Y113208D01*
Y112792D01*
X355346Y112542D01*
X355554Y112333D01*
X355846Y112250D01*
X356137Y112375D01*
X356346Y112667D01*
X356429Y113000D01*
X356346Y113333D01*
X356137Y113625D01*
X355846Y113750D01*
X355554Y113667D01*
X355346Y113458D01*
X355262Y113208D01*
Y112792D01*
X355137Y112417D01*
X354887Y112167D01*
X354596Y112083D01*
X354304Y112167D01*
X354096Y112375D01*
X353971Y112708D01*
X353929Y113000D01*
G01X354971Y115308D02*
X355262Y115600D01*
X355429Y115850D01*
X355512Y116183D01*
X355429Y116475D01*
X355262Y116683D01*
X355012Y116850D01*
X354721Y116892D01*
X354471Y116850D01*
X354221Y116683D01*
X354012Y116433D01*
X353929Y116142D01*
X354012Y115808D01*
X354262Y115517D01*
X354637Y115350D01*
X355054Y115308D01*
X355596Y115392D01*
X355887Y115517D01*
X356179Y115725D01*
X356387Y116017D01*
X356429Y116308D01*
X356346Y116600D01*
X356137Y116808D01*
G01X353929Y119200D02*
X356429D01*
X355929Y118700D01*
G01X353929D02*
Y119700D01*
G01X358373Y105925D02*
X358165Y106258D01*
X358040Y106633D01*
Y106967D01*
X358165Y107300D01*
X358373Y107550D01*
X358665Y107675D01*
X358957Y107592D01*
X359207Y107383D01*
X359373Y107008D01*
X359457Y106508D01*
X359623Y106217D01*
X359915Y106092D01*
X360207Y106175D01*
X360415Y106383D01*
X360540Y106675D01*
Y106967D01*
X360457Y107258D01*
X360248Y107508D01*
G01X360332Y110817D02*
X360457Y110567D01*
X360540Y110275D01*
Y109942D01*
X360415Y109567D01*
X360207Y109275D01*
X359957Y109067D01*
X359540Y108900D01*
X359165Y108858D01*
X358790Y108942D01*
X358540Y109067D01*
X358290Y109317D01*
X358123Y109608D01*
X358040Y109900D01*
Y110192D01*
X358123Y110483D01*
X358248Y110733D01*
X358415Y110942D01*
G01X358040Y113000D02*
X358082Y113292D01*
X358207Y113625D01*
X358415Y113833D01*
X358707Y113917D01*
X358998Y113833D01*
X359248Y113583D01*
X359373Y113208D01*
Y112792D01*
X359457Y112542D01*
X359665Y112333D01*
X359957Y112250D01*
X360248Y112375D01*
X360457Y112667D01*
X360540Y113000D01*
X360457Y113333D01*
X360248Y113625D01*
X359957Y113750D01*
X359665Y113667D01*
X359457Y113458D01*
X359373Y113208D01*
Y112792D01*
X359248Y112417D01*
X358998Y112167D01*
X358707Y112083D01*
X358415Y112167D01*
X358207Y112375D01*
X358082Y112708D01*
X358040Y113000D01*
G01X359082Y115308D02*
X359373Y115600D01*
X359540Y115850D01*
X359623Y116183D01*
X359540Y116475D01*
X359373Y116683D01*
X359123Y116850D01*
X358832Y116892D01*
X358582Y116850D01*
X358332Y116683D01*
X358123Y116433D01*
X358040Y116142D01*
X358123Y115808D01*
X358373Y115517D01*
X358748Y115350D01*
X359165Y115308D01*
X359707Y115392D01*
X359998Y115517D01*
X360290Y115725D01*
X360498Y116017D01*
X360540Y116308D01*
X360457Y116600D01*
X360248Y116808D01*
G01X360123Y118408D02*
X360373Y118658D01*
X360498Y118950D01*
X360540Y119283D01*
X360457Y119700D01*
X360248Y119992D01*
X359998Y120075D01*
X359748Y120033D01*
X359540Y119867D01*
X359123Y119033D01*
X358832Y118658D01*
X358415Y118408D01*
X358040Y118325D01*
Y120075D01*
G01X362373Y105925D02*
X362165Y106258D01*
X362040Y106633D01*
Y106967D01*
X362165Y107300D01*
X362373Y107550D01*
X362665Y107675D01*
X362957Y107592D01*
X363207Y107383D01*
X363373Y107008D01*
X363457Y106508D01*
X363623Y106217D01*
X363915Y106092D01*
X364207Y106175D01*
X364415Y106383D01*
X364540Y106675D01*
Y106967D01*
X364457Y107258D01*
X364248Y107508D01*
G01X364332Y110817D02*
X364457Y110567D01*
X364540Y110275D01*
Y109942D01*
X364415Y109567D01*
X364207Y109275D01*
X363957Y109067D01*
X363540Y108900D01*
X363165Y108858D01*
X362790Y108942D01*
X362540Y109067D01*
X362290Y109317D01*
X362123Y109608D01*
X362040Y109900D01*
Y110192D01*
X362123Y110483D01*
X362248Y110733D01*
X362415Y110942D01*
G01X362040Y113000D02*
X362082Y113292D01*
X362207Y113625D01*
X362415Y113833D01*
X362707Y113917D01*
X362998Y113833D01*
X363248Y113583D01*
X363373Y113208D01*
Y112792D01*
X363457Y112542D01*
X363665Y112333D01*
X363957Y112250D01*
X364248Y112375D01*
X364457Y112667D01*
X364540Y113000D01*
X364457Y113333D01*
X364248Y113625D01*
X363957Y113750D01*
X363665Y113667D01*
X363457Y113458D01*
X363373Y113208D01*
Y112792D01*
X363248Y112417D01*
X362998Y112167D01*
X362707Y112083D01*
X362415Y112167D01*
X362207Y112375D01*
X362082Y112708D01*
X362040Y113000D01*
G01X363082Y115308D02*
X363373Y115600D01*
X363540Y115850D01*
X363623Y116183D01*
X363540Y116475D01*
X363373Y116683D01*
X363123Y116850D01*
X362832Y116892D01*
X362582Y116850D01*
X362332Y116683D01*
X362123Y116433D01*
X362040Y116142D01*
X362123Y115808D01*
X362373Y115517D01*
X362748Y115350D01*
X363165Y115308D01*
X363707Y115392D01*
X363998Y115517D01*
X364290Y115725D01*
X364498Y116017D01*
X364540Y116308D01*
X364457Y116600D01*
X364248Y116808D01*
G01X362540Y118283D02*
X362248Y118533D01*
X362082Y118867D01*
X362040Y119242D01*
X362082Y119575D01*
X362290Y119908D01*
X362540Y120117D01*
X362790Y120158D01*
X363082Y120075D01*
X363290Y119783D01*
X363373Y119492D01*
Y119117D01*
G01Y119492D02*
X363498Y119742D01*
X363707Y119950D01*
X363957Y120033D01*
X364207Y119950D01*
X364415Y119742D01*
X364540Y119367D01*
X364498Y118992D01*
X364332Y118617D01*
G01X352262Y123425D02*
X352054Y123758D01*
X351929Y124133D01*
Y124467D01*
X352054Y124800D01*
X352262Y125050D01*
X352554Y125175D01*
X352846Y125092D01*
X353096Y124883D01*
X353262Y124508D01*
X353346Y124008D01*
X353512Y123717D01*
X353804Y123592D01*
X354096Y123675D01*
X354304Y123883D01*
X354429Y124175D01*
Y124467D01*
X354346Y124758D01*
X354137Y125008D01*
G01X354221Y128317D02*
X354346Y128067D01*
X354429Y127775D01*
Y127442D01*
X354304Y127067D01*
X354096Y126775D01*
X353846Y126567D01*
X353429Y126400D01*
X353054Y126358D01*
X352679Y126442D01*
X352429Y126567D01*
X352179Y126817D01*
X352012Y127108D01*
X351929Y127400D01*
Y127692D01*
X352012Y127983D01*
X352137Y128233D01*
X352304Y128442D01*
G01X352221Y129792D02*
X352012Y130083D01*
X351929Y130417D01*
X352012Y130750D01*
X352262Y131042D01*
X352637Y131250D01*
X353012Y131333D01*
X353471D01*
X353846Y131250D01*
X354179Y131042D01*
X354346Y130792D01*
X354429Y130500D01*
X354346Y130167D01*
X354179Y129917D01*
X353929Y129750D01*
X353596Y129667D01*
X353304Y129750D01*
X353012Y129958D01*
X352846Y130208D01*
X352804Y130500D01*
X352887Y130833D01*
X353096Y131083D01*
X353471Y131333D01*
G01X352304Y132683D02*
X352096Y132933D01*
X351971Y133225D01*
X351929Y133600D01*
X352012Y133975D01*
X352179Y134267D01*
X352471Y134475D01*
X352804Y134517D01*
X353137Y134433D01*
X353346Y134225D01*
X353512Y133933D01*
X353554Y133642D01*
X353512Y133350D01*
X353346Y132975D01*
X354429Y133100D01*
Y134225D01*
G01X352429Y135783D02*
X352137Y136033D01*
X351971Y136367D01*
X351929Y136742D01*
X351971Y137075D01*
X352179Y137408D01*
X352429Y137617D01*
X352679Y137658D01*
X352971Y137575D01*
X353179Y137283D01*
X353262Y136992D01*
Y136617D01*
G01Y136992D02*
X353387Y137242D01*
X353596Y137450D01*
X353846Y137533D01*
X354096Y137450D01*
X354304Y137242D01*
X354429Y136867D01*
X354387Y136492D01*
X354221Y136117D01*
G01X375504Y158333D02*
X375171Y158125D01*
X374796Y158000D01*
X374462D01*
X374129Y158125D01*
X373879Y158333D01*
X373754Y158625D01*
X373837Y158917D01*
X374046Y159167D01*
X374421Y159333D01*
X374921Y159417D01*
X375212Y159583D01*
X375337Y159875D01*
X375254Y160167D01*
X375046Y160375D01*
X374754Y160500D01*
X374462D01*
X374171Y160417D01*
X373921Y160208D01*
G01X370612Y160292D02*
X370862Y160417D01*
X371154Y160500D01*
X371487D01*
X371862Y160375D01*
X372154Y160167D01*
X372362Y159917D01*
X372529Y159500D01*
X372571Y159125D01*
X372487Y158750D01*
X372362Y158500D01*
X372112Y158250D01*
X371821Y158083D01*
X371529Y158000D01*
X371237D01*
X370946Y158083D01*
X370696Y158208D01*
X370487Y158375D01*
G01X369137Y158292D02*
X368846Y158083D01*
X368512Y158000D01*
X368179Y158083D01*
X367887Y158333D01*
X367679Y158708D01*
X367596Y159083D01*
Y159542D01*
X367679Y159917D01*
X367887Y160250D01*
X368137Y160417D01*
X368429Y160500D01*
X368762Y160417D01*
X369012Y160250D01*
X369179Y160000D01*
X369262Y159667D01*
X369179Y159375D01*
X368971Y159083D01*
X368721Y158917D01*
X368429Y158875D01*
X368096Y158958D01*
X367846Y159167D01*
X367596Y159542D01*
G01X366121Y159042D02*
X365829Y159333D01*
X365579Y159500D01*
X365246Y159583D01*
X364954Y159500D01*
X364746Y159333D01*
X364579Y159083D01*
X364537Y158792D01*
X364579Y158542D01*
X364746Y158292D01*
X364996Y158083D01*
X365287Y158000D01*
X365621Y158083D01*
X365912Y158333D01*
X366079Y158708D01*
X366121Y159125D01*
X366037Y159667D01*
X365912Y159958D01*
X365704Y160250D01*
X365412Y160458D01*
X365121Y160500D01*
X364829Y160417D01*
X364621Y160208D01*
G01X363021Y159042D02*
X362729Y159333D01*
X362479Y159500D01*
X362146Y159583D01*
X361854Y159500D01*
X361646Y159333D01*
X361479Y159083D01*
X361437Y158792D01*
X361479Y158542D01*
X361646Y158292D01*
X361896Y158083D01*
X362187Y158000D01*
X362521Y158083D01*
X362812Y158333D01*
X362979Y158708D01*
X363021Y159125D01*
X362937Y159667D01*
X362812Y159958D01*
X362604Y160250D01*
X362312Y160458D01*
X362021Y160500D01*
X361729Y160417D01*
X361521Y160208D01*
G01X371575Y168833D02*
X371242Y168625D01*
X370867Y168500D01*
X370533D01*
X370200Y168625D01*
X369950Y168833D01*
X369825Y169125D01*
X369908Y169417D01*
X370117Y169667D01*
X370492Y169833D01*
X370992Y169917D01*
X371283Y170083D01*
X371408Y170375D01*
X371325Y170667D01*
X371117Y170875D01*
X370825Y171000D01*
X370533D01*
X370242Y170917D01*
X369992Y170708D01*
G01X366683Y170792D02*
X366933Y170917D01*
X367225Y171000D01*
X367558D01*
X367933Y170875D01*
X368225Y170667D01*
X368433Y170417D01*
X368600Y170000D01*
X368642Y169625D01*
X368558Y169250D01*
X368433Y169000D01*
X368183Y168750D01*
X367892Y168583D01*
X367600Y168500D01*
X367308D01*
X367017Y168583D01*
X366767Y168708D01*
X366558Y168875D01*
G01X365208Y168792D02*
X364917Y168583D01*
X364583Y168500D01*
X364250Y168583D01*
X363958Y168833D01*
X363750Y169208D01*
X363667Y169583D01*
Y170042D01*
X363750Y170417D01*
X363958Y170750D01*
X364208Y170917D01*
X364500Y171000D01*
X364833Y170917D01*
X365083Y170750D01*
X365250Y170500D01*
X365333Y170167D01*
X365250Y169875D01*
X365042Y169583D01*
X364792Y169417D01*
X364500Y169375D01*
X364167Y169458D01*
X363917Y169667D01*
X363667Y170042D01*
G01X362192Y169542D02*
X361900Y169833D01*
X361650Y170000D01*
X361317Y170083D01*
X361025Y170000D01*
X360817Y169833D01*
X360650Y169583D01*
X360608Y169292D01*
X360650Y169042D01*
X360817Y168792D01*
X361067Y168583D01*
X361358Y168500D01*
X361692Y168583D01*
X361983Y168833D01*
X362150Y169208D01*
X362192Y169625D01*
X362108Y170167D01*
X361983Y170458D01*
X361775Y170750D01*
X361483Y170958D01*
X361192Y171000D01*
X360900Y170917D01*
X360692Y170708D01*
G01X359217Y169000D02*
X358967Y168708D01*
X358633Y168542D01*
X358258Y168500D01*
X357925Y168542D01*
X357592Y168750D01*
X357383Y169000D01*
X357342Y169250D01*
X357425Y169542D01*
X357717Y169750D01*
X358008Y169833D01*
X358383D01*
G01X358008D02*
X357758Y169958D01*
X357550Y170167D01*
X357467Y170417D01*
X357550Y170667D01*
X357758Y170875D01*
X358133Y171000D01*
X358508Y170958D01*
X358883Y170792D01*
G01X376004Y163833D02*
X375671Y163625D01*
X375296Y163500D01*
X374962D01*
X374629Y163625D01*
X374379Y163833D01*
X374254Y164125D01*
X374337Y164417D01*
X374546Y164667D01*
X374921Y164833D01*
X375421Y164917D01*
X375712Y165083D01*
X375837Y165375D01*
X375754Y165667D01*
X375546Y165875D01*
X375254Y166000D01*
X374962D01*
X374671Y165917D01*
X374421Y165708D01*
G01X371112Y165792D02*
X371362Y165917D01*
X371654Y166000D01*
X371987D01*
X372362Y165875D01*
X372654Y165667D01*
X372862Y165417D01*
X373029Y165000D01*
X373071Y164625D01*
X372987Y164250D01*
X372862Y164000D01*
X372612Y163750D01*
X372321Y163583D01*
X372029Y163500D01*
X371737D01*
X371446Y163583D01*
X371196Y163708D01*
X370987Y163875D01*
G01X369637Y163792D02*
X369346Y163583D01*
X369012Y163500D01*
X368679Y163583D01*
X368387Y163833D01*
X368179Y164208D01*
X368096Y164583D01*
Y165042D01*
X368179Y165417D01*
X368387Y165750D01*
X368637Y165917D01*
X368929Y166000D01*
X369262Y165917D01*
X369512Y165750D01*
X369679Y165500D01*
X369762Y165167D01*
X369679Y164875D01*
X369471Y164583D01*
X369221Y164417D01*
X368929Y164375D01*
X368596Y164458D01*
X368346Y164667D01*
X368096Y165042D01*
G01X366621Y164542D02*
X366329Y164833D01*
X366079Y165000D01*
X365746Y165083D01*
X365454Y165000D01*
X365246Y164833D01*
X365079Y164583D01*
X365037Y164292D01*
X365079Y164042D01*
X365246Y163792D01*
X365496Y163583D01*
X365787Y163500D01*
X366121Y163583D01*
X366412Y163833D01*
X366579Y164208D01*
X366621Y164625D01*
X366537Y165167D01*
X366412Y165458D01*
X366204Y165750D01*
X365912Y165958D01*
X365621Y166000D01*
X365329Y165917D01*
X365121Y165708D01*
G01X363521Y165583D02*
X363271Y165833D01*
X362979Y165958D01*
X362646Y166000D01*
X362229Y165917D01*
X361937Y165708D01*
X361854Y165458D01*
X361896Y165208D01*
X362062Y165000D01*
X362896Y164583D01*
X363271Y164292D01*
X363521Y163875D01*
X363604Y163500D01*
X361854D01*
G01X356810Y177910D02*
Y181910D01*
X364210D01*
G01X367129Y201389D02*
Y197389D01*
X359729D01*
G01X355040Y212700D02*
X359040D01*
Y205300D01*
G01X346540Y212700D02*
X350540D01*
Y205300D01*
G01X351040Y212700D02*
X355040D01*
Y205300D01*
G01X353373Y223925D02*
X353165Y224258D01*
X353040Y224633D01*
Y224967D01*
X353165Y225300D01*
X353373Y225550D01*
X353665Y225675D01*
X353957Y225592D01*
X354207Y225383D01*
X354373Y225008D01*
X354457Y224508D01*
X354623Y224217D01*
X354915Y224092D01*
X355207Y224175D01*
X355415Y224383D01*
X355540Y224675D01*
Y224967D01*
X355457Y225258D01*
X355248Y225508D01*
G01X353040Y227067D02*
X355540D01*
Y228108D01*
X355415Y228442D01*
X355248Y228650D01*
X354915Y228733D01*
X354582Y228650D01*
X354373Y228400D01*
X354248Y228108D01*
Y227067D01*
G01Y228108D02*
X353040Y228733D01*
G01X354082Y230208D02*
X354373Y230500D01*
X354540Y230750D01*
X354623Y231083D01*
X354540Y231375D01*
X354373Y231583D01*
X354123Y231750D01*
X353832Y231792D01*
X353582Y231750D01*
X353332Y231583D01*
X353123Y231333D01*
X353040Y231042D01*
X353123Y230708D01*
X353373Y230417D01*
X353748Y230250D01*
X354165Y230208D01*
X354707Y230292D01*
X354998Y230417D01*
X355290Y230625D01*
X355498Y230917D01*
X355540Y231208D01*
X355457Y231500D01*
X355248Y231708D01*
G01X355123Y233308D02*
X355373Y233558D01*
X355498Y233850D01*
X355540Y234183D01*
X355457Y234600D01*
X355248Y234892D01*
X354998Y234975D01*
X354748Y234933D01*
X354540Y234767D01*
X354123Y233933D01*
X353832Y233558D01*
X353415Y233308D01*
X353040Y233225D01*
Y234975D01*
G01Y237200D02*
X353082Y237492D01*
X353207Y237825D01*
X353415Y238033D01*
X353707Y238117D01*
X353998Y238033D01*
X354248Y237783D01*
X354373Y237408D01*
Y236992D01*
X354457Y236742D01*
X354665Y236533D01*
X354957Y236450D01*
X355248Y236575D01*
X355457Y236867D01*
X355540Y237200D01*
X355457Y237533D01*
X355248Y237825D01*
X354957Y237950D01*
X354665Y237867D01*
X354457Y237658D01*
X354373Y237408D01*
Y236992D01*
X354248Y236617D01*
X353998Y236367D01*
X353707Y236283D01*
X353415Y236367D01*
X353207Y236575D01*
X353082Y236908D01*
X353040Y237200D01*
G01X349373Y223925D02*
X349165Y224258D01*
X349040Y224633D01*
Y224967D01*
X349165Y225300D01*
X349373Y225550D01*
X349665Y225675D01*
X349957Y225592D01*
X350207Y225383D01*
X350373Y225008D01*
X350457Y224508D01*
X350623Y224217D01*
X350915Y224092D01*
X351207Y224175D01*
X351415Y224383D01*
X351540Y224675D01*
Y224967D01*
X351457Y225258D01*
X351248Y225508D01*
G01X349040Y227067D02*
X351540D01*
Y228108D01*
X351415Y228442D01*
X351248Y228650D01*
X350915Y228733D01*
X350582Y228650D01*
X350373Y228400D01*
X350248Y228108D01*
Y227067D01*
G01Y228108D02*
X349040Y228733D01*
G01X350082Y230208D02*
X350373Y230500D01*
X350540Y230750D01*
X350623Y231083D01*
X350540Y231375D01*
X350373Y231583D01*
X350123Y231750D01*
X349832Y231792D01*
X349582Y231750D01*
X349332Y231583D01*
X349123Y231333D01*
X349040Y231042D01*
X349123Y230708D01*
X349373Y230417D01*
X349748Y230250D01*
X350165Y230208D01*
X350707Y230292D01*
X350998Y230417D01*
X351290Y230625D01*
X351498Y230917D01*
X351540Y231208D01*
X351457Y231500D01*
X351248Y231708D01*
G01X349540Y233183D02*
X349248Y233433D01*
X349082Y233767D01*
X349040Y234142D01*
X349082Y234475D01*
X349290Y234808D01*
X349540Y235017D01*
X349790Y235058D01*
X350082Y234975D01*
X350290Y234683D01*
X350373Y234392D01*
Y234017D01*
G01Y234392D02*
X350498Y234642D01*
X350707Y234850D01*
X350957Y234933D01*
X351207Y234850D01*
X351415Y234642D01*
X351540Y234267D01*
X351498Y233892D01*
X351332Y233517D01*
G01X349540Y236283D02*
X349248Y236533D01*
X349082Y236867D01*
X349040Y237242D01*
X349082Y237575D01*
X349290Y237908D01*
X349540Y238117D01*
X349790Y238158D01*
X350082Y238075D01*
X350290Y237783D01*
X350373Y237492D01*
Y237117D01*
G01Y237492D02*
X350498Y237742D01*
X350707Y237950D01*
X350957Y238033D01*
X351207Y237950D01*
X351415Y237742D01*
X351540Y237367D01*
X351498Y236992D01*
X351332Y236617D01*
G01X357762Y222375D02*
X357554Y222708D01*
X357429Y223083D01*
Y223417D01*
X357554Y223750D01*
X357762Y224000D01*
X358054Y224125D01*
X358346Y224042D01*
X358596Y223833D01*
X358762Y223458D01*
X358846Y222958D01*
X359012Y222667D01*
X359304Y222542D01*
X359596Y222625D01*
X359804Y222833D01*
X359929Y223125D01*
Y223417D01*
X359846Y223708D01*
X359637Y223958D01*
G01X359721Y227267D02*
X359846Y227017D01*
X359929Y226725D01*
Y226392D01*
X359804Y226017D01*
X359596Y225725D01*
X359346Y225517D01*
X358929Y225350D01*
X358554Y225308D01*
X358179Y225392D01*
X357929Y225517D01*
X357679Y225767D01*
X357512Y226058D01*
X357429Y226350D01*
Y226642D01*
X357512Y226933D01*
X357637Y227183D01*
X357804Y227392D01*
G01X357429Y229450D02*
X359929D01*
X359429Y228950D01*
G01X357429D02*
Y229950D01*
G01X359929Y232550D02*
X359846Y232217D01*
X359637Y231967D01*
X359387Y231800D01*
X359054Y231675D01*
X358679Y231633D01*
X358304Y231675D01*
X357971Y231800D01*
X357721Y231967D01*
X357512Y232217D01*
X357429Y232550D01*
X357512Y232883D01*
X357721Y233133D01*
X357971Y233300D01*
X358304Y233425D01*
X358679Y233467D01*
X359054Y233425D01*
X359387Y233300D01*
X359637Y233133D01*
X359846Y232883D01*
X359929Y232550D01*
G01X357429Y235650D02*
X359929D01*
X359429Y235150D01*
G01X357429D02*
Y236150D01*
G01X358471Y237958D02*
X358762Y238250D01*
X358929Y238500D01*
X359012Y238833D01*
X358929Y239125D01*
X358762Y239333D01*
X358512Y239500D01*
X358221Y239542D01*
X357971Y239500D01*
X357721Y239333D01*
X357512Y239083D01*
X357429Y238792D01*
X357512Y238458D01*
X357762Y238167D01*
X358137Y238000D01*
X358554Y237958D01*
X359096Y238042D01*
X359387Y238167D01*
X359679Y238375D01*
X359887Y238667D01*
X359929Y238958D01*
X359846Y239250D01*
X359637Y239458D01*
G01X353762Y241925D02*
X353554Y242258D01*
X353429Y242633D01*
Y242967D01*
X353554Y243300D01*
X353762Y243550D01*
X354054Y243675D01*
X354346Y243592D01*
X354596Y243383D01*
X354762Y243008D01*
X354846Y242508D01*
X355012Y242217D01*
X355304Y242092D01*
X355596Y242175D01*
X355804Y242383D01*
X355929Y242675D01*
Y242967D01*
X355846Y243258D01*
X355637Y243508D01*
G01X355721Y246817D02*
X355846Y246567D01*
X355929Y246275D01*
Y245942D01*
X355804Y245567D01*
X355596Y245275D01*
X355346Y245067D01*
X354929Y244900D01*
X354554Y244858D01*
X354179Y244942D01*
X353929Y245067D01*
X353679Y245317D01*
X353512Y245608D01*
X353429Y245900D01*
Y246192D01*
X353512Y246483D01*
X353637Y246733D01*
X353804Y246942D01*
G01X353721Y248292D02*
X353512Y248583D01*
X353429Y248917D01*
X353512Y249250D01*
X353762Y249542D01*
X354137Y249750D01*
X354512Y249833D01*
X354971D01*
X355346Y249750D01*
X355679Y249542D01*
X355846Y249292D01*
X355929Y249000D01*
X355846Y248667D01*
X355679Y248417D01*
X355429Y248250D01*
X355096Y248167D01*
X354804Y248250D01*
X354512Y248458D01*
X354346Y248708D01*
X354304Y249000D01*
X354387Y249333D01*
X354596Y249583D01*
X354971Y249833D01*
G01X353429Y252017D02*
X353971Y252100D01*
X354429Y252225D01*
X354846Y252392D01*
X355304Y252600D01*
X355929Y252933D01*
Y251267D01*
G01X353429Y255117D02*
X353971Y255200D01*
X354429Y255325D01*
X354846Y255492D01*
X355304Y255700D01*
X355929Y256033D01*
Y254367D01*
G01X346500Y298000D02*
Y285000D01*
G01X364504Y272333D02*
X364171Y272125D01*
X363796Y272000D01*
X363462D01*
X363129Y272125D01*
X362879Y272333D01*
X362754Y272625D01*
X362837Y272917D01*
X363046Y273167D01*
X363421Y273333D01*
X363921Y273417D01*
X364212Y273583D01*
X364337Y273875D01*
X364254Y274167D01*
X364046Y274375D01*
X363754Y274500D01*
X363462D01*
X363171Y274417D01*
X362921Y274208D01*
G01X360529Y274500D02*
Y272000D01*
G01X361487Y274500D02*
X359571D01*
G01X358262Y272000D02*
Y274500D01*
X357262D01*
X356929Y274375D01*
X356679Y274083D01*
X356596Y273750D01*
X356679Y273417D01*
X356887Y273167D01*
X357262Y273042D01*
X358262D01*
G01X355121Y274083D02*
X354871Y274333D01*
X354579Y274458D01*
X354246Y274500D01*
X353829Y274417D01*
X353537Y274208D01*
X353454Y273958D01*
X353496Y273708D01*
X353662Y273500D01*
X354496Y273083D01*
X354871Y272792D01*
X355121Y272375D01*
X355204Y272000D01*
X353454D01*
G01X351937Y272292D02*
X351646Y272083D01*
X351312Y272000D01*
X350979Y272083D01*
X350687Y272333D01*
X350479Y272708D01*
X350396Y273083D01*
Y273542D01*
X350479Y273917D01*
X350687Y274250D01*
X350937Y274417D01*
X351229Y274500D01*
X351562Y274417D01*
X351812Y274250D01*
X351979Y274000D01*
X352062Y273667D01*
X351979Y273375D01*
X351771Y273083D01*
X351521Y272917D01*
X351229Y272875D01*
X350896Y272958D01*
X350646Y273167D01*
X350396Y273542D01*
G01X364504Y277333D02*
X364171Y277125D01*
X363796Y277000D01*
X363462D01*
X363129Y277125D01*
X362879Y277333D01*
X362754Y277625D01*
X362837Y277917D01*
X363046Y278167D01*
X363421Y278333D01*
X363921Y278417D01*
X364212Y278583D01*
X364337Y278875D01*
X364254Y279167D01*
X364046Y279375D01*
X363754Y279500D01*
X363462D01*
X363171Y279417D01*
X362921Y279208D01*
G01X360529Y279500D02*
Y277000D01*
G01X361487Y279500D02*
X359571D01*
G01X358262Y277000D02*
Y279500D01*
X357262D01*
X356929Y279375D01*
X356679Y279083D01*
X356596Y278750D01*
X356679Y278417D01*
X356887Y278167D01*
X357262Y278042D01*
X358262D01*
G01X355246Y277500D02*
X354996Y277208D01*
X354662Y277042D01*
X354287Y277000D01*
X353954Y277042D01*
X353621Y277250D01*
X353412Y277500D01*
X353371Y277750D01*
X353454Y278042D01*
X353746Y278250D01*
X354037Y278333D01*
X354412D01*
G01X354037D02*
X353787Y278458D01*
X353579Y278667D01*
X353496Y278917D01*
X353579Y279167D01*
X353787Y279375D01*
X354162Y279500D01*
X354537Y279458D01*
X354912Y279292D01*
G01X351312Y277000D02*
X351229Y277542D01*
X351104Y278000D01*
X350937Y278417D01*
X350729Y278875D01*
X350396Y279500D01*
X352062D01*
G01X350833Y282925D02*
X350625Y283258D01*
X350500Y283633D01*
Y283967D01*
X350625Y284300D01*
X350833Y284550D01*
X351125Y284675D01*
X351417Y284592D01*
X351667Y284383D01*
X351833Y284008D01*
X351917Y283508D01*
X352083Y283217D01*
X352375Y283092D01*
X352667Y283175D01*
X352875Y283383D01*
X353000Y283675D01*
Y283967D01*
X352917Y284258D01*
X352708Y284508D01*
G01X350500Y286067D02*
X353000D01*
Y287108D01*
X352875Y287442D01*
X352708Y287650D01*
X352375Y287733D01*
X352042Y287650D01*
X351833Y287400D01*
X351708Y287108D01*
Y286067D01*
G01Y287108D02*
X350500Y287733D01*
G01X351542Y289208D02*
X351833Y289500D01*
X352000Y289750D01*
X352083Y290083D01*
X352000Y290375D01*
X351833Y290583D01*
X351583Y290750D01*
X351292Y290792D01*
X351042Y290750D01*
X350792Y290583D01*
X350583Y290333D01*
X350500Y290042D01*
X350583Y289708D01*
X350833Y289417D01*
X351208Y289250D01*
X351625Y289208D01*
X352167Y289292D01*
X352458Y289417D01*
X352750Y289625D01*
X352958Y289917D01*
X353000Y290208D01*
X352917Y290500D01*
X352708Y290708D01*
G01X350500Y293017D02*
X351042Y293100D01*
X351500Y293225D01*
X351917Y293392D01*
X352375Y293600D01*
X353000Y293933D01*
Y292267D01*
G01X351000Y295283D02*
X350708Y295533D01*
X350542Y295867D01*
X350500Y296242D01*
X350542Y296575D01*
X350750Y296908D01*
X351000Y297117D01*
X351250Y297158D01*
X351542Y297075D01*
X351750Y296783D01*
X351833Y296492D01*
Y296117D01*
G01Y296492D02*
X351958Y296742D01*
X352167Y296950D01*
X352417Y297033D01*
X352667Y296950D01*
X352875Y296742D01*
X353000Y296367D01*
X352958Y295992D01*
X352792Y295617D01*
G01X378125Y287533D02*
X377792Y287325D01*
X377417Y287200D01*
X377083D01*
X376750Y287325D01*
X376500Y287533D01*
X376375Y287825D01*
X376458Y288117D01*
X376667Y288367D01*
X377042Y288533D01*
X377542Y288617D01*
X377833Y288783D01*
X377958Y289075D01*
X377875Y289367D01*
X377667Y289575D01*
X377375Y289700D01*
X377083D01*
X376792Y289617D01*
X376542Y289408D01*
G01X373233Y289492D02*
X373483Y289617D01*
X373775Y289700D01*
X374108D01*
X374483Y289575D01*
X374775Y289367D01*
X374983Y289117D01*
X375150Y288700D01*
X375192Y288325D01*
X375108Y287950D01*
X374983Y287700D01*
X374733Y287450D01*
X374442Y287283D01*
X374150Y287200D01*
X373858D01*
X373567Y287283D01*
X373317Y287408D01*
X373108Y287575D01*
G01X371050Y287200D02*
Y289700D01*
X371550Y289200D01*
G01Y287200D02*
X370550D01*
G01X367950Y289700D02*
X368283Y289617D01*
X368533Y289408D01*
X368700Y289158D01*
X368825Y288825D01*
X368867Y288450D01*
X368825Y288075D01*
X368700Y287742D01*
X368533Y287492D01*
X368283Y287283D01*
X367950Y287200D01*
X367617Y287283D01*
X367367Y287492D01*
X367200Y287742D01*
X367075Y288075D01*
X367033Y288450D01*
X367075Y288825D01*
X367200Y289158D01*
X367367Y289408D01*
X367617Y289617D01*
X367950Y289700D01*
G01X364350Y287200D02*
Y289700D01*
X365892Y287908D01*
X363808D01*
G01X361750Y289700D02*
X362083Y289617D01*
X362333Y289408D01*
X362500Y289158D01*
X362625Y288825D01*
X362667Y288450D01*
X362625Y288075D01*
X362500Y287742D01*
X362333Y287492D01*
X362083Y287283D01*
X361750Y287200D01*
X361417Y287283D01*
X361167Y287492D01*
X361000Y287742D01*
X360875Y288075D01*
X360833Y288450D01*
X360875Y288825D01*
X361000Y289158D01*
X361167Y289408D01*
X361417Y289617D01*
X361750Y289700D01*
G01X378125Y282833D02*
X377792Y282625D01*
X377417Y282500D01*
X377083D01*
X376750Y282625D01*
X376500Y282833D01*
X376375Y283125D01*
X376458Y283417D01*
X376667Y283667D01*
X377042Y283833D01*
X377542Y283917D01*
X377833Y284083D01*
X377958Y284375D01*
X377875Y284667D01*
X377667Y284875D01*
X377375Y285000D01*
X377083D01*
X376792Y284917D01*
X376542Y284708D01*
G01X373233Y284792D02*
X373483Y284917D01*
X373775Y285000D01*
X374108D01*
X374483Y284875D01*
X374775Y284667D01*
X374983Y284417D01*
X375150Y284000D01*
X375192Y283625D01*
X375108Y283250D01*
X374983Y283000D01*
X374733Y282750D01*
X374442Y282583D01*
X374150Y282500D01*
X373858D01*
X373567Y282583D01*
X373317Y282708D01*
X373108Y282875D01*
G01X371050Y282500D02*
Y285000D01*
X371550Y284500D01*
G01Y282500D02*
X370550D01*
G01X367950Y285000D02*
X368283Y284917D01*
X368533Y284708D01*
X368700Y284458D01*
X368825Y284125D01*
X368867Y283750D01*
X368825Y283375D01*
X368700Y283042D01*
X368533Y282792D01*
X368283Y282583D01*
X367950Y282500D01*
X367617Y282583D01*
X367367Y282792D01*
X367200Y283042D01*
X367075Y283375D01*
X367033Y283750D01*
X367075Y284125D01*
X367200Y284458D01*
X367367Y284708D01*
X367617Y284917D01*
X367950Y285000D01*
G01X364350Y282500D02*
Y285000D01*
X365892Y283208D01*
X363808D01*
G01X361250Y282500D02*
Y285000D01*
X362792Y283208D01*
X360708D01*
G01X355833Y282425D02*
X355625Y282758D01*
X355500Y283133D01*
Y283467D01*
X355625Y283800D01*
X355833Y284050D01*
X356125Y284175D01*
X356417Y284092D01*
X356667Y283883D01*
X356833Y283508D01*
X356917Y283008D01*
X357083Y282717D01*
X357375Y282592D01*
X357667Y282675D01*
X357875Y282883D01*
X358000Y283175D01*
Y283467D01*
X357917Y283758D01*
X357708Y284008D01*
G01X357792Y287317D02*
X357917Y287067D01*
X358000Y286775D01*
Y286442D01*
X357875Y286067D01*
X357667Y285775D01*
X357417Y285567D01*
X357000Y285400D01*
X356625Y285358D01*
X356250Y285442D01*
X356000Y285567D01*
X355750Y285817D01*
X355583Y286108D01*
X355500Y286400D01*
Y286692D01*
X355583Y286983D01*
X355708Y287233D01*
X355875Y287442D01*
G01X355792Y288792D02*
X355583Y289083D01*
X355500Y289417D01*
X355583Y289750D01*
X355833Y290042D01*
X356208Y290250D01*
X356583Y290333D01*
X357042D01*
X357417Y290250D01*
X357750Y290042D01*
X357917Y289792D01*
X358000Y289500D01*
X357917Y289167D01*
X357750Y288917D01*
X357500Y288750D01*
X357167Y288667D01*
X356875Y288750D01*
X356583Y288958D01*
X356417Y289208D01*
X356375Y289500D01*
X356458Y289833D01*
X356667Y290083D01*
X357042Y290333D01*
G01X355500Y292517D02*
X356042Y292600D01*
X356500Y292725D01*
X356917Y292892D01*
X357375Y293100D01*
X358000Y293433D01*
Y291767D01*
G01X355500Y295700D02*
X355542Y295992D01*
X355667Y296325D01*
X355875Y296533D01*
X356167Y296617D01*
X356458Y296533D01*
X356708Y296283D01*
X356833Y295908D01*
Y295492D01*
X356917Y295242D01*
X357125Y295033D01*
X357417Y294950D01*
X357708Y295075D01*
X357917Y295367D01*
X358000Y295700D01*
X357917Y296033D01*
X357708Y296325D01*
X357417Y296450D01*
X357125Y296367D01*
X356917Y296158D01*
X356833Y295908D01*
Y295492D01*
X356708Y295117D01*
X356458Y294867D01*
X356167Y294783D01*
X355875Y294867D01*
X355667Y295075D01*
X355542Y295408D01*
X355500Y295700D01*
G01X378125Y295833D02*
X377792Y295625D01*
X377417Y295500D01*
X377083D01*
X376750Y295625D01*
X376500Y295833D01*
X376375Y296125D01*
X376458Y296417D01*
X376667Y296667D01*
X377042Y296833D01*
X377542Y296917D01*
X377833Y297083D01*
X377958Y297375D01*
X377875Y297667D01*
X377667Y297875D01*
X377375Y298000D01*
X377083D01*
X376792Y297917D01*
X376542Y297708D01*
G01X373233Y297792D02*
X373483Y297917D01*
X373775Y298000D01*
X374108D01*
X374483Y297875D01*
X374775Y297667D01*
X374983Y297417D01*
X375150Y297000D01*
X375192Y296625D01*
X375108Y296250D01*
X374983Y296000D01*
X374733Y295750D01*
X374442Y295583D01*
X374150Y295500D01*
X373858D01*
X373567Y295583D01*
X373317Y295708D01*
X373108Y295875D01*
G01X371050Y295500D02*
Y298000D01*
X371550Y297500D01*
G01Y295500D02*
X370550D01*
G01X367950Y298000D02*
X368283Y297917D01*
X368533Y297708D01*
X368700Y297458D01*
X368825Y297125D01*
X368867Y296750D01*
X368825Y296375D01*
X368700Y296042D01*
X368533Y295792D01*
X368283Y295583D01*
X367950Y295500D01*
X367617Y295583D01*
X367367Y295792D01*
X367200Y296042D01*
X367075Y296375D01*
X367033Y296750D01*
X367075Y297125D01*
X367200Y297458D01*
X367367Y297708D01*
X367617Y297917D01*
X367950Y298000D01*
G01X365642Y297583D02*
X365392Y297833D01*
X365100Y297958D01*
X364767Y298000D01*
X364350Y297917D01*
X364058Y297708D01*
X363975Y297458D01*
X364017Y297208D01*
X364183Y297000D01*
X365017Y296583D01*
X365392Y296292D01*
X365642Y295875D01*
X365725Y295500D01*
X363975D01*
G01X362542Y297583D02*
X362292Y297833D01*
X362000Y297958D01*
X361667Y298000D01*
X361250Y297917D01*
X360958Y297708D01*
X360875Y297458D01*
X360917Y297208D01*
X361083Y297000D01*
X361917Y296583D01*
X362292Y296292D01*
X362542Y295875D01*
X362625Y295500D01*
X360875D01*
G01X378125Y291433D02*
X377792Y291225D01*
X377417Y291100D01*
X377083D01*
X376750Y291225D01*
X376500Y291433D01*
X376375Y291725D01*
X376458Y292017D01*
X376667Y292267D01*
X377042Y292433D01*
X377542Y292517D01*
X377833Y292683D01*
X377958Y292975D01*
X377875Y293267D01*
X377667Y293475D01*
X377375Y293600D01*
X377083D01*
X376792Y293517D01*
X376542Y293308D01*
G01X373233Y293392D02*
X373483Y293517D01*
X373775Y293600D01*
X374108D01*
X374483Y293475D01*
X374775Y293267D01*
X374983Y293017D01*
X375150Y292600D01*
X375192Y292225D01*
X375108Y291850D01*
X374983Y291600D01*
X374733Y291350D01*
X374442Y291183D01*
X374150Y291100D01*
X373858D01*
X373567Y291183D01*
X373317Y291308D01*
X373108Y291475D01*
G01X371050Y291100D02*
Y293600D01*
X371550Y293100D01*
G01Y291100D02*
X370550D01*
G01X367950Y293600D02*
X368283Y293517D01*
X368533Y293308D01*
X368700Y293058D01*
X368825Y292725D01*
X368867Y292350D01*
X368825Y291975D01*
X368700Y291642D01*
X368533Y291392D01*
X368283Y291183D01*
X367950Y291100D01*
X367617Y291183D01*
X367367Y291392D01*
X367200Y291642D01*
X367075Y291975D01*
X367033Y292350D01*
X367075Y292725D01*
X367200Y293058D01*
X367367Y293308D01*
X367617Y293517D01*
X367950Y293600D01*
G01X364350Y291100D02*
Y293600D01*
X365892Y291808D01*
X363808D01*
G01X362667Y291600D02*
X362417Y291308D01*
X362083Y291142D01*
X361708Y291100D01*
X361375Y291142D01*
X361042Y291350D01*
X360833Y291600D01*
X360792Y291850D01*
X360875Y292142D01*
X361167Y292350D01*
X361458Y292433D01*
X361833D01*
G01X361458D02*
X361208Y292558D01*
X361000Y292767D01*
X360917Y293017D01*
X361000Y293267D01*
X361208Y293475D01*
X361583Y293600D01*
X361958Y293558D01*
X362333Y293392D01*
G01X361288Y327075D02*
X361080Y327408D01*
X360955Y327783D01*
Y328117D01*
X361080Y328450D01*
X361288Y328700D01*
X361580Y328825D01*
X361872Y328742D01*
X362122Y328533D01*
X362288Y328158D01*
X362372Y327658D01*
X362538Y327367D01*
X362830Y327242D01*
X363122Y327325D01*
X363330Y327533D01*
X363455Y327825D01*
Y328117D01*
X363372Y328408D01*
X363163Y328658D01*
G01X363247Y331967D02*
X363372Y331717D01*
X363455Y331425D01*
Y331092D01*
X363330Y330717D01*
X363122Y330425D01*
X362872Y330217D01*
X362455Y330050D01*
X362080Y330008D01*
X361705Y330092D01*
X361455Y330217D01*
X361205Y330467D01*
X361038Y330758D01*
X360955Y331050D01*
Y331342D01*
X361038Y331633D01*
X361163Y331883D01*
X361330Y332092D01*
G01X360955Y334150D02*
X363455D01*
X362955Y333650D01*
G01X360955D02*
Y334650D01*
G01X363038Y336458D02*
X363288Y336708D01*
X363413Y337000D01*
X363455Y337333D01*
X363372Y337750D01*
X363163Y338042D01*
X362913Y338125D01*
X362663Y338083D01*
X362455Y337917D01*
X362038Y337083D01*
X361747Y336708D01*
X361330Y336458D01*
X360955Y336375D01*
Y338125D01*
G01X361330Y339433D02*
X361122Y339683D01*
X360997Y339975D01*
X360955Y340350D01*
X361038Y340725D01*
X361205Y341017D01*
X361497Y341225D01*
X361830Y341267D01*
X362163Y341183D01*
X362372Y340975D01*
X362538Y340683D01*
X362580Y340392D01*
X362538Y340100D01*
X362372Y339725D01*
X363455Y339850D01*
Y340975D01*
G01X361997Y342658D02*
X362288Y342950D01*
X362455Y343200D01*
X362538Y343533D01*
X362455Y343825D01*
X362288Y344033D01*
X362038Y344200D01*
X361747Y344242D01*
X361497Y344200D01*
X361247Y344033D01*
X361038Y343783D01*
X360955Y343492D01*
X361038Y343158D01*
X361288Y342867D01*
X361663Y342700D01*
X362080Y342658D01*
X362622Y342742D01*
X362913Y342867D01*
X363205Y343075D01*
X363413Y343367D01*
X363455Y343658D01*
X363372Y343950D01*
X363163Y344158D01*
G01X371625Y322833D02*
X371292Y322625D01*
X370917Y322500D01*
X370583D01*
X370250Y322625D01*
X370000Y322833D01*
X369875Y323125D01*
X369958Y323417D01*
X370167Y323667D01*
X370542Y323833D01*
X371042Y323917D01*
X371333Y324083D01*
X371458Y324375D01*
X371375Y324667D01*
X371167Y324875D01*
X370875Y325000D01*
X370583D01*
X370292Y324917D01*
X370042Y324708D01*
G01X366733Y324792D02*
X366983Y324917D01*
X367275Y325000D01*
X367608D01*
X367983Y324875D01*
X368275Y324667D01*
X368483Y324417D01*
X368650Y324000D01*
X368692Y323625D01*
X368608Y323250D01*
X368483Y323000D01*
X368233Y322750D01*
X367942Y322583D01*
X367650Y322500D01*
X367358D01*
X367067Y322583D01*
X366817Y322708D01*
X366608Y322875D01*
G01X364550Y322500D02*
Y325000D01*
X365050Y324500D01*
G01Y322500D02*
X364050D01*
G01X362242Y324583D02*
X361992Y324833D01*
X361700Y324958D01*
X361367Y325000D01*
X360950Y324917D01*
X360658Y324708D01*
X360575Y324458D01*
X360617Y324208D01*
X360783Y324000D01*
X361617Y323583D01*
X361992Y323292D01*
X362242Y322875D01*
X362325Y322500D01*
X360575D01*
G01X357850D02*
Y325000D01*
X359392Y323208D01*
X357308D01*
G01X355250Y322500D02*
X354958Y322542D01*
X354625Y322667D01*
X354417Y322875D01*
X354333Y323167D01*
X354417Y323458D01*
X354667Y323708D01*
X355042Y323833D01*
X355458D01*
X355708Y323917D01*
X355917Y324125D01*
X356000Y324417D01*
X355875Y324708D01*
X355583Y324917D01*
X355250Y325000D01*
X354917Y324917D01*
X354625Y324708D01*
X354500Y324417D01*
X354583Y324125D01*
X354792Y323917D01*
X355042Y323833D01*
X355458D01*
X355833Y323708D01*
X356083Y323458D01*
X356167Y323167D01*
X356083Y322875D01*
X355875Y322667D01*
X355542Y322542D01*
X355250Y322500D01*
G01X356333Y345875D02*
X356125Y346208D01*
X356000Y346583D01*
Y346917D01*
X356125Y347250D01*
X356333Y347500D01*
X356625Y347625D01*
X356917Y347542D01*
X357167Y347333D01*
X357333Y346958D01*
X357417Y346458D01*
X357583Y346167D01*
X357875Y346042D01*
X358167Y346125D01*
X358375Y346333D01*
X358500Y346625D01*
Y346917D01*
X358417Y347208D01*
X358208Y347458D01*
G01X358292Y350767D02*
X358417Y350517D01*
X358500Y350225D01*
Y349892D01*
X358375Y349517D01*
X358167Y349225D01*
X357917Y349017D01*
X357500Y348850D01*
X357125Y348808D01*
X356750Y348892D01*
X356500Y349017D01*
X356250Y349267D01*
X356083Y349558D01*
X356000Y349850D01*
Y350142D01*
X356083Y350433D01*
X356208Y350683D01*
X356375Y350892D01*
G01X356000Y352950D02*
X358500D01*
X358000Y352450D01*
G01X356000D02*
Y353450D01*
G01X358083Y355258D02*
X358333Y355508D01*
X358458Y355800D01*
X358500Y356133D01*
X358417Y356550D01*
X358208Y356842D01*
X357958Y356925D01*
X357708Y356883D01*
X357500Y356717D01*
X357083Y355883D01*
X356792Y355508D01*
X356375Y355258D01*
X356000Y355175D01*
Y356925D01*
G01Y359150D02*
X358500D01*
X358000Y358650D01*
G01X356000D02*
Y359650D01*
G01Y362167D02*
X356542Y362250D01*
X357000Y362375D01*
X357417Y362542D01*
X357875Y362750D01*
X358500Y363083D01*
Y361417D01*
G01X351833Y345875D02*
X351625Y346208D01*
X351500Y346583D01*
Y346917D01*
X351625Y347250D01*
X351833Y347500D01*
X352125Y347625D01*
X352417Y347542D01*
X352667Y347333D01*
X352833Y346958D01*
X352917Y346458D01*
X353083Y346167D01*
X353375Y346042D01*
X353667Y346125D01*
X353875Y346333D01*
X354000Y346625D01*
Y346917D01*
X353917Y347208D01*
X353708Y347458D01*
G01X353792Y350767D02*
X353917Y350517D01*
X354000Y350225D01*
Y349892D01*
X353875Y349517D01*
X353667Y349225D01*
X353417Y349017D01*
X353000Y348850D01*
X352625Y348808D01*
X352250Y348892D01*
X352000Y349017D01*
X351750Y349267D01*
X351583Y349558D01*
X351500Y349850D01*
Y350142D01*
X351583Y350433D01*
X351708Y350683D01*
X351875Y350892D01*
G01X351500Y352950D02*
X354000D01*
X353500Y352450D01*
G01X351500D02*
Y353450D01*
G01X353583Y355258D02*
X353833Y355508D01*
X353958Y355800D01*
X354000Y356133D01*
X353917Y356550D01*
X353708Y356842D01*
X353458Y356925D01*
X353208Y356883D01*
X353000Y356717D01*
X352583Y355883D01*
X352292Y355508D01*
X351875Y355258D01*
X351500Y355175D01*
Y356925D01*
G01Y359150D02*
X354000D01*
X353500Y358650D01*
G01X351500D02*
Y359650D01*
G01X351792Y361542D02*
X351583Y361833D01*
X351500Y362167D01*
X351583Y362500D01*
X351833Y362792D01*
X352208Y363000D01*
X352583Y363083D01*
X353042D01*
X353417Y363000D01*
X353750Y362792D01*
X353917Y362542D01*
X354000Y362250D01*
X353917Y361917D01*
X353750Y361667D01*
X353500Y361500D01*
X353167Y361417D01*
X352875Y361500D01*
X352583Y361708D01*
X352417Y361958D01*
X352375Y362250D01*
X352458Y362583D01*
X352667Y362833D01*
X353042Y363083D01*
G01X379280Y358633D02*
X378947Y358425D01*
X378572Y358300D01*
X378238D01*
X377905Y358425D01*
X377655Y358633D01*
X377530Y358925D01*
X377613Y359217D01*
X377822Y359467D01*
X378197Y359633D01*
X378697Y359717D01*
X378988Y359883D01*
X379113Y360175D01*
X379030Y360467D01*
X378822Y360675D01*
X378530Y360800D01*
X378238D01*
X377947Y360717D01*
X377697Y360508D01*
G01X374388Y360592D02*
X374638Y360717D01*
X374930Y360800D01*
X375263D01*
X375638Y360675D01*
X375930Y360467D01*
X376138Y360217D01*
X376305Y359800D01*
X376347Y359425D01*
X376263Y359050D01*
X376138Y358800D01*
X375888Y358550D01*
X375597Y358383D01*
X375305Y358300D01*
X375013D01*
X374722Y358383D01*
X374472Y358508D01*
X374263Y358675D01*
G01X372205Y358300D02*
Y360800D01*
X372705Y360300D01*
G01Y358300D02*
X371705D01*
G01X369105D02*
Y360800D01*
X369605Y360300D01*
G01Y358300D02*
X368605D01*
G01X365505D02*
Y360800D01*
X367047Y359008D01*
X364963D01*
G01X362405Y358300D02*
Y360800D01*
X363947Y359008D01*
X361863D01*
G01X379125Y354333D02*
X378792Y354125D01*
X378417Y354000D01*
X378083D01*
X377750Y354125D01*
X377500Y354333D01*
X377375Y354625D01*
X377458Y354917D01*
X377667Y355167D01*
X378042Y355333D01*
X378542Y355417D01*
X378833Y355583D01*
X378958Y355875D01*
X378875Y356167D01*
X378667Y356375D01*
X378375Y356500D01*
X378083D01*
X377792Y356417D01*
X377542Y356208D01*
G01X374233Y356292D02*
X374483Y356417D01*
X374775Y356500D01*
X375108D01*
X375483Y356375D01*
X375775Y356167D01*
X375983Y355917D01*
X376150Y355500D01*
X376192Y355125D01*
X376108Y354750D01*
X375983Y354500D01*
X375733Y354250D01*
X375442Y354083D01*
X375150Y354000D01*
X374858D01*
X374567Y354083D01*
X374317Y354208D01*
X374108Y354375D01*
G01X372050Y354000D02*
Y356500D01*
X372550Y356000D01*
G01Y354000D02*
X371550D01*
G01X368950D02*
Y356500D01*
X369450Y356000D01*
G01Y354000D02*
X368450D01*
G01X365350D02*
Y356500D01*
X366892Y354708D01*
X364808D01*
G01X363542Y356083D02*
X363292Y356333D01*
X363000Y356458D01*
X362667Y356500D01*
X362250Y356417D01*
X361958Y356208D01*
X361875Y355958D01*
X361917Y355708D01*
X362083Y355500D01*
X362917Y355083D01*
X363292Y354792D01*
X363542Y354375D01*
X363625Y354000D01*
X361875D01*
G01X349000Y398200D02*
X353000D01*
Y390800D01*
G01X373680Y537833D02*
X373347Y537625D01*
X372972Y537500D01*
X372638D01*
X372305Y537625D01*
X372055Y537833D01*
X371930Y538125D01*
X372013Y538417D01*
X372222Y538667D01*
X372597Y538833D01*
X373097Y538917D01*
X373388Y539083D01*
X373513Y539375D01*
X373430Y539667D01*
X373222Y539875D01*
X372930Y540000D01*
X372638D01*
X372347Y539917D01*
X372097Y539708D01*
G01X368788Y539792D02*
X369038Y539917D01*
X369330Y540000D01*
X369663D01*
X370038Y539875D01*
X370330Y539667D01*
X370538Y539417D01*
X370705Y539000D01*
X370747Y538625D01*
X370663Y538250D01*
X370538Y538000D01*
X370288Y537750D01*
X369997Y537583D01*
X369705Y537500D01*
X369413D01*
X369122Y537583D01*
X368872Y537708D01*
X368663Y537875D01*
G01X366605Y537500D02*
Y540000D01*
X367105Y539500D01*
G01Y537500D02*
X366105D01*
G01X363505D02*
Y540000D01*
X364005Y539500D01*
G01Y537500D02*
X363005D01*
G01X360405D02*
Y540000D01*
X360905Y539500D01*
G01Y537500D02*
X359905D01*
G01X357305D02*
X357013Y537542D01*
X356680Y537667D01*
X356472Y537875D01*
X356388Y538167D01*
X356472Y538458D01*
X356722Y538708D01*
X357097Y538833D01*
X357513D01*
X357763Y538917D01*
X357972Y539125D01*
X358055Y539417D01*
X357930Y539708D01*
X357638Y539917D01*
X357305Y540000D01*
X356972Y539917D01*
X356680Y539708D01*
X356555Y539417D01*
X356638Y539125D01*
X356847Y538917D01*
X357097Y538833D01*
X357513D01*
X357888Y538708D01*
X358138Y538458D01*
X358222Y538167D01*
X358138Y537875D01*
X357930Y537667D01*
X357597Y537542D01*
X357305Y537500D01*
G01X373680Y541833D02*
X373347Y541625D01*
X372972Y541500D01*
X372638D01*
X372305Y541625D01*
X372055Y541833D01*
X371930Y542125D01*
X372013Y542417D01*
X372222Y542667D01*
X372597Y542833D01*
X373097Y542917D01*
X373388Y543083D01*
X373513Y543375D01*
X373430Y543667D01*
X373222Y543875D01*
X372930Y544000D01*
X372638D01*
X372347Y543917D01*
X372097Y543708D01*
G01X368788Y543792D02*
X369038Y543917D01*
X369330Y544000D01*
X369663D01*
X370038Y543875D01*
X370330Y543667D01*
X370538Y543417D01*
X370705Y543000D01*
X370747Y542625D01*
X370663Y542250D01*
X370538Y542000D01*
X370288Y541750D01*
X369997Y541583D01*
X369705Y541500D01*
X369413D01*
X369122Y541583D01*
X368872Y541708D01*
X368663Y541875D01*
G01X366605Y541500D02*
Y544000D01*
X367105Y543500D01*
G01Y541500D02*
X366105D01*
G01X363505D02*
Y544000D01*
X364005Y543500D01*
G01Y541500D02*
X363005D01*
G01X360405D02*
Y544000D01*
X360905Y543500D01*
G01Y541500D02*
X359905D01*
G01X358013Y541792D02*
X357722Y541583D01*
X357388Y541500D01*
X357055Y541583D01*
X356763Y541833D01*
X356555Y542208D01*
X356472Y542583D01*
Y543042D01*
X356555Y543417D01*
X356763Y543750D01*
X357013Y543917D01*
X357305Y544000D01*
X357638Y543917D01*
X357888Y543750D01*
X358055Y543500D01*
X358138Y543167D01*
X358055Y542875D01*
X357847Y542583D01*
X357597Y542417D01*
X357305Y542375D01*
X356972Y542458D01*
X356722Y542667D01*
X356472Y543042D01*
G01X366983Y901000D02*
Y903500D01*
X365942D01*
X365608Y903375D01*
X365400Y903208D01*
X365317Y902875D01*
X365400Y902542D01*
X365650Y902333D01*
X365942Y902208D01*
X366983D01*
G01X365942D02*
X365317Y901000D01*
G01X363842Y902042D02*
X363550Y902333D01*
X363300Y902500D01*
X362967Y902583D01*
X362675Y902500D01*
X362467Y902333D01*
X362300Y902083D01*
X362258Y901792D01*
X362300Y901542D01*
X362467Y901292D01*
X362717Y901083D01*
X363008Y901000D01*
X363342Y901083D01*
X363633Y901333D01*
X363800Y901708D01*
X363842Y902125D01*
X363758Y902667D01*
X363633Y902958D01*
X363425Y903250D01*
X363133Y903458D01*
X362842Y903500D01*
X362550Y903417D01*
X362342Y903208D01*
G01X360742Y903083D02*
X360492Y903333D01*
X360200Y903458D01*
X359867Y903500D01*
X359450Y903417D01*
X359158Y903208D01*
X359075Y902958D01*
X359117Y902708D01*
X359283Y902500D01*
X360117Y902083D01*
X360492Y901792D01*
X360742Y901375D01*
X360825Y901000D01*
X359075D01*
G01X357558Y901292D02*
X357267Y901083D01*
X356933Y901000D01*
X356600Y901083D01*
X356308Y901333D01*
X356100Y901708D01*
X356017Y902083D01*
Y902542D01*
X356100Y902917D01*
X356308Y903250D01*
X356558Y903417D01*
X356850Y903500D01*
X357183Y903417D01*
X357433Y903250D01*
X357600Y903000D01*
X357683Y902667D01*
X357600Y902375D01*
X357392Y902083D01*
X357142Y901917D01*
X356850Y901875D01*
X356517Y901958D01*
X356267Y902167D01*
X356017Y902542D01*
G01X366983Y905500D02*
Y908000D01*
X365942D01*
X365608Y907875D01*
X365400Y907708D01*
X365317Y907375D01*
X365400Y907042D01*
X365650Y906833D01*
X365942Y906708D01*
X366983D01*
G01X365942D02*
X365317Y905500D01*
G01X363842Y906542D02*
X363550Y906833D01*
X363300Y907000D01*
X362967Y907083D01*
X362675Y907000D01*
X362467Y906833D01*
X362300Y906583D01*
X362258Y906292D01*
X362300Y906042D01*
X362467Y905792D01*
X362717Y905583D01*
X363008Y905500D01*
X363342Y905583D01*
X363633Y905833D01*
X363800Y906208D01*
X363842Y906625D01*
X363758Y907167D01*
X363633Y907458D01*
X363425Y907750D01*
X363133Y907958D01*
X362842Y908000D01*
X362550Y907917D01*
X362342Y907708D01*
G01X360742Y906542D02*
X360450Y906833D01*
X360200Y907000D01*
X359867Y907083D01*
X359575Y907000D01*
X359367Y906833D01*
X359200Y906583D01*
X359158Y906292D01*
X359200Y906042D01*
X359367Y905792D01*
X359617Y905583D01*
X359908Y905500D01*
X360242Y905583D01*
X360533Y905833D01*
X360700Y906208D01*
X360742Y906625D01*
X360658Y907167D01*
X360533Y907458D01*
X360325Y907750D01*
X360033Y907958D01*
X359742Y908000D01*
X359450Y907917D01*
X359242Y907708D01*
G01X356933Y905500D02*
X356850Y906042D01*
X356725Y906500D01*
X356558Y906917D01*
X356350Y907375D01*
X356017Y908000D01*
X357683D01*
G01X362646Y975634D02*
X360146D01*
G01X362646Y974676D02*
Y976592D01*
G01X360146Y977901D02*
X362646D01*
Y978901D01*
X362521Y979234D01*
X362229Y979484D01*
X361896Y979567D01*
X361563Y979484D01*
X361313Y979276D01*
X361188Y978901D01*
Y977901D01*
G01X360146Y981751D02*
X360688Y981834D01*
X361146Y981959D01*
X361563Y982126D01*
X362021Y982334D01*
X362646Y982667D01*
Y981001D01*
G01X360438Y984226D02*
X360229Y984517D01*
X360146Y984851D01*
X360229Y985184D01*
X360479Y985476D01*
X360854Y985684D01*
X361229Y985767D01*
X361688D01*
X362063Y985684D01*
X362396Y985476D01*
X362563Y985226D01*
X362646Y984934D01*
X362563Y984601D01*
X362396Y984351D01*
X362146Y984184D01*
X361813Y984101D01*
X361521Y984184D01*
X361229Y984392D01*
X361063Y984642D01*
X361021Y984934D01*
X361104Y985267D01*
X361313Y985517D01*
X361688Y985767D01*
G01X367833Y21375D02*
X367625Y21708D01*
X367500Y22083D01*
Y22417D01*
X367625Y22750D01*
X367833Y23000D01*
X368125Y23125D01*
X368417Y23042D01*
X368667Y22833D01*
X368833Y22458D01*
X368917Y21958D01*
X369083Y21667D01*
X369375Y21542D01*
X369667Y21625D01*
X369875Y21833D01*
X370000Y22125D01*
Y22417D01*
X369917Y22708D01*
X369708Y22958D01*
G01X369792Y26267D02*
X369917Y26017D01*
X370000Y25725D01*
Y25392D01*
X369875Y25017D01*
X369667Y24725D01*
X369417Y24517D01*
X369000Y24350D01*
X368625Y24308D01*
X368250Y24392D01*
X368000Y24517D01*
X367750Y24767D01*
X367583Y25058D01*
X367500Y25350D01*
Y25642D01*
X367583Y25933D01*
X367708Y26183D01*
X367875Y26392D01*
G01X367500Y28450D02*
X370000D01*
X369500Y27950D01*
G01X367500D02*
Y28950D01*
G01X370000Y31550D02*
X369917Y31217D01*
X369708Y30967D01*
X369458Y30800D01*
X369125Y30675D01*
X368750Y30633D01*
X368375Y30675D01*
X368042Y30800D01*
X367792Y30967D01*
X367583Y31217D01*
X367500Y31550D01*
X367583Y31883D01*
X367792Y32133D01*
X368042Y32300D01*
X368375Y32425D01*
X368750Y32467D01*
X369125Y32425D01*
X369458Y32300D01*
X369708Y32133D01*
X369917Y31883D01*
X370000Y31550D01*
G01X367500Y34650D02*
X370000D01*
X369500Y34150D01*
G01X367500D02*
Y35150D01*
G01X367792Y37042D02*
X367583Y37333D01*
X367500Y37667D01*
X367583Y38000D01*
X367833Y38292D01*
X368208Y38500D01*
X368583Y38583D01*
X369042D01*
X369417Y38500D01*
X369750Y38292D01*
X369917Y38042D01*
X370000Y37750D01*
X369917Y37417D01*
X369750Y37167D01*
X369500Y37000D01*
X369167Y36917D01*
X368875Y37000D01*
X368583Y37208D01*
X368417Y37458D01*
X368375Y37750D01*
X368458Y38083D01*
X368667Y38333D01*
X369042Y38583D01*
G01X373000Y98500D02*
X428500D01*
Y72500D01*
X412000D01*
Y37500D01*
X376000D01*
Y70000D01*
X368000D01*
Y98500D01*
X373000D01*
G01X379762Y56425D02*
X379554Y56758D01*
X379429Y57133D01*
Y57467D01*
X379554Y57800D01*
X379762Y58050D01*
X380054Y58175D01*
X380346Y58092D01*
X380596Y57883D01*
X380762Y57508D01*
X380846Y57008D01*
X381012Y56717D01*
X381304Y56592D01*
X381596Y56675D01*
X381804Y56883D01*
X381929Y57175D01*
Y57467D01*
X381846Y57758D01*
X381637Y58008D01*
G01X381721Y61317D02*
X381846Y61067D01*
X381929Y60775D01*
Y60442D01*
X381804Y60067D01*
X381596Y59775D01*
X381346Y59567D01*
X380929Y59400D01*
X380554Y59358D01*
X380179Y59442D01*
X379929Y59567D01*
X379679Y59817D01*
X379512Y60108D01*
X379429Y60400D01*
Y60692D01*
X379512Y60983D01*
X379637Y61233D01*
X379804Y61442D01*
G01X379721Y62792D02*
X379512Y63083D01*
X379429Y63417D01*
X379512Y63750D01*
X379762Y64042D01*
X380137Y64250D01*
X380512Y64333D01*
X380971D01*
X381346Y64250D01*
X381679Y64042D01*
X381846Y63792D01*
X381929Y63500D01*
X381846Y63167D01*
X381679Y62917D01*
X381429Y62750D01*
X381096Y62667D01*
X380804Y62750D01*
X380512Y62958D01*
X380346Y63208D01*
X380304Y63500D01*
X380387Y63833D01*
X380596Y64083D01*
X380971Y64333D01*
G01X379429Y67100D02*
X381929D01*
X380137Y65558D01*
Y67642D01*
G01X379929Y68783D02*
X379637Y69033D01*
X379471Y69367D01*
X379429Y69742D01*
X379471Y70075D01*
X379679Y70408D01*
X379929Y70617D01*
X380179Y70658D01*
X380471Y70575D01*
X380679Y70283D01*
X380762Y69992D01*
Y69617D01*
G01Y69992D02*
X380887Y70242D01*
X381096Y70450D01*
X381346Y70533D01*
X381596Y70450D01*
X381804Y70242D01*
X381929Y69867D01*
X381887Y69492D01*
X381721Y69117D01*
G01X386004Y73833D02*
X385671Y73625D01*
X385296Y73500D01*
X384962D01*
X384629Y73625D01*
X384379Y73833D01*
X384254Y74125D01*
X384337Y74417D01*
X384546Y74667D01*
X384921Y74833D01*
X385421Y74917D01*
X385712Y75083D01*
X385837Y75375D01*
X385754Y75667D01*
X385546Y75875D01*
X385254Y76000D01*
X384962D01*
X384671Y75917D01*
X384421Y75708D01*
G01X381112Y75792D02*
X381362Y75917D01*
X381654Y76000D01*
X381987D01*
X382362Y75875D01*
X382654Y75667D01*
X382862Y75417D01*
X383029Y75000D01*
X383071Y74625D01*
X382987Y74250D01*
X382862Y74000D01*
X382612Y73750D01*
X382321Y73583D01*
X382029Y73500D01*
X381737D01*
X381446Y73583D01*
X381196Y73708D01*
X380987Y73875D01*
G01X379637Y73792D02*
X379346Y73583D01*
X379012Y73500D01*
X378679Y73583D01*
X378387Y73833D01*
X378179Y74208D01*
X378096Y74583D01*
Y75042D01*
X378179Y75417D01*
X378387Y75750D01*
X378637Y75917D01*
X378929Y76000D01*
X379262Y75917D01*
X379512Y75750D01*
X379679Y75500D01*
X379762Y75167D01*
X379679Y74875D01*
X379471Y74583D01*
X379221Y74417D01*
X378929Y74375D01*
X378596Y74458D01*
X378346Y74667D01*
X378096Y75042D01*
G01X375329Y73500D02*
Y76000D01*
X376871Y74208D01*
X374787D01*
G01X372729Y73500D02*
X372437Y73542D01*
X372104Y73667D01*
X371896Y73875D01*
X371812Y74167D01*
X371896Y74458D01*
X372146Y74708D01*
X372521Y74833D01*
X372937D01*
X373187Y74917D01*
X373396Y75125D01*
X373479Y75417D01*
X373354Y75708D01*
X373062Y75917D01*
X372729Y76000D01*
X372396Y75917D01*
X372104Y75708D01*
X371979Y75417D01*
X372062Y75125D01*
X372271Y74917D01*
X372521Y74833D01*
X372937D01*
X373312Y74708D01*
X373562Y74458D01*
X373646Y74167D01*
X373562Y73875D01*
X373354Y73667D01*
X373021Y73542D01*
X372729Y73500D01*
G01X375262Y78875D02*
X375054Y79208D01*
X374929Y79583D01*
Y79917D01*
X375054Y80250D01*
X375262Y80500D01*
X375554Y80625D01*
X375846Y80542D01*
X376096Y80333D01*
X376262Y79958D01*
X376346Y79458D01*
X376512Y79167D01*
X376804Y79042D01*
X377096Y79125D01*
X377304Y79333D01*
X377429Y79625D01*
Y79917D01*
X377346Y80208D01*
X377137Y80458D01*
G01X377221Y83767D02*
X377346Y83517D01*
X377429Y83225D01*
Y82892D01*
X377304Y82517D01*
X377096Y82225D01*
X376846Y82017D01*
X376429Y81850D01*
X376054Y81808D01*
X375679Y81892D01*
X375429Y82017D01*
X375179Y82267D01*
X375012Y82558D01*
X374929Y82850D01*
Y83142D01*
X375012Y83433D01*
X375137Y83683D01*
X375304Y83892D01*
G01X374929Y85950D02*
X377429D01*
X376929Y85450D01*
G01X374929D02*
Y86450D01*
G01X377429Y89050D02*
X377346Y88717D01*
X377137Y88467D01*
X376887Y88300D01*
X376554Y88175D01*
X376179Y88133D01*
X375804Y88175D01*
X375471Y88300D01*
X375221Y88467D01*
X375012Y88717D01*
X374929Y89050D01*
X375012Y89383D01*
X375221Y89633D01*
X375471Y89800D01*
X375804Y89925D01*
X376179Y89967D01*
X376554Y89925D01*
X376887Y89800D01*
X377137Y89633D01*
X377346Y89383D01*
X377429Y89050D01*
G01X374929Y92150D02*
X377429D01*
X376929Y91650D01*
G01X374929D02*
Y92650D01*
G01Y95250D02*
X374971Y95542D01*
X375096Y95875D01*
X375304Y96083D01*
X375596Y96167D01*
X375887Y96083D01*
X376137Y95833D01*
X376262Y95458D01*
Y95042D01*
X376346Y94792D01*
X376554Y94583D01*
X376846Y94500D01*
X377137Y94625D01*
X377346Y94917D01*
X377429Y95250D01*
X377346Y95583D01*
X377137Y95875D01*
X376846Y96000D01*
X376554Y95917D01*
X376346Y95708D01*
X376262Y95458D01*
Y95042D01*
X376137Y94667D01*
X375887Y94417D01*
X375596Y94333D01*
X375304Y94417D01*
X375096Y94625D01*
X374971Y94958D01*
X374929Y95250D01*
G01X371333Y78875D02*
X371125Y79208D01*
X371000Y79583D01*
Y79917D01*
X371125Y80250D01*
X371333Y80500D01*
X371625Y80625D01*
X371917Y80542D01*
X372167Y80333D01*
X372333Y79958D01*
X372417Y79458D01*
X372583Y79167D01*
X372875Y79042D01*
X373167Y79125D01*
X373375Y79333D01*
X373500Y79625D01*
Y79917D01*
X373417Y80208D01*
X373208Y80458D01*
G01X373292Y83767D02*
X373417Y83517D01*
X373500Y83225D01*
Y82892D01*
X373375Y82517D01*
X373167Y82225D01*
X372917Y82017D01*
X372500Y81850D01*
X372125Y81808D01*
X371750Y81892D01*
X371500Y82017D01*
X371250Y82267D01*
X371083Y82558D01*
X371000Y82850D01*
Y83142D01*
X371083Y83433D01*
X371208Y83683D01*
X371375Y83892D01*
G01X371000Y85950D02*
X373500D01*
X373000Y85450D01*
G01X371000D02*
Y86450D01*
G01X373500Y89050D02*
X373417Y88717D01*
X373208Y88467D01*
X372958Y88300D01*
X372625Y88175D01*
X372250Y88133D01*
X371875Y88175D01*
X371542Y88300D01*
X371292Y88467D01*
X371083Y88717D01*
X371000Y89050D01*
X371083Y89383D01*
X371292Y89633D01*
X371542Y89800D01*
X371875Y89925D01*
X372250Y89967D01*
X372625Y89925D01*
X372958Y89800D01*
X373208Y89633D01*
X373417Y89383D01*
X373500Y89050D01*
G01X371000Y92650D02*
X373500D01*
X371708Y91108D01*
Y93192D01*
G01X371000Y95250D02*
X371042Y95542D01*
X371167Y95875D01*
X371375Y96083D01*
X371667Y96167D01*
X371958Y96083D01*
X372208Y95833D01*
X372333Y95458D01*
Y95042D01*
X372417Y94792D01*
X372625Y94583D01*
X372917Y94500D01*
X373208Y94625D01*
X373417Y94917D01*
X373500Y95250D01*
X373417Y95583D01*
X373208Y95875D01*
X372917Y96000D01*
X372625Y95917D01*
X372417Y95708D01*
X372333Y95458D01*
Y95042D01*
X372208Y94667D01*
X371958Y94417D01*
X371667Y94333D01*
X371375Y94417D01*
X371167Y94625D01*
X371042Y94958D01*
X371000Y95250D01*
G01X379262Y78875D02*
X379054Y79208D01*
X378929Y79583D01*
Y79917D01*
X379054Y80250D01*
X379262Y80500D01*
X379554Y80625D01*
X379846Y80542D01*
X380096Y80333D01*
X380262Y79958D01*
X380346Y79458D01*
X380512Y79167D01*
X380804Y79042D01*
X381096Y79125D01*
X381304Y79333D01*
X381429Y79625D01*
Y79917D01*
X381346Y80208D01*
X381137Y80458D01*
G01X381221Y83767D02*
X381346Y83517D01*
X381429Y83225D01*
Y82892D01*
X381304Y82517D01*
X381096Y82225D01*
X380846Y82017D01*
X380429Y81850D01*
X380054Y81808D01*
X379679Y81892D01*
X379429Y82017D01*
X379179Y82267D01*
X379012Y82558D01*
X378929Y82850D01*
Y83142D01*
X379012Y83433D01*
X379137Y83683D01*
X379304Y83892D01*
G01X378929Y85950D02*
X381429D01*
X380929Y85450D01*
G01X378929D02*
Y86450D01*
G01X381429Y89050D02*
X381346Y88717D01*
X381137Y88467D01*
X380887Y88300D01*
X380554Y88175D01*
X380179Y88133D01*
X379804Y88175D01*
X379471Y88300D01*
X379221Y88467D01*
X379012Y88717D01*
X378929Y89050D01*
X379012Y89383D01*
X379221Y89633D01*
X379471Y89800D01*
X379804Y89925D01*
X380179Y89967D01*
X380554Y89925D01*
X380887Y89800D01*
X381137Y89633D01*
X381346Y89383D01*
X381429Y89050D01*
G01X379971Y91358D02*
X380262Y91650D01*
X380429Y91900D01*
X380512Y92233D01*
X380429Y92525D01*
X380262Y92733D01*
X380012Y92900D01*
X379721Y92942D01*
X379471Y92900D01*
X379221Y92733D01*
X379012Y92483D01*
X378929Y92192D01*
X379012Y91858D01*
X379262Y91567D01*
X379637Y91400D01*
X380054Y91358D01*
X380596Y91442D01*
X380887Y91567D01*
X381179Y91775D01*
X381387Y92067D01*
X381429Y92358D01*
X381346Y92650D01*
X381137Y92858D01*
G01X381429Y95250D02*
X381346Y94917D01*
X381137Y94667D01*
X380887Y94500D01*
X380554Y94375D01*
X380179Y94333D01*
X379804Y94375D01*
X379471Y94500D01*
X379221Y94667D01*
X379012Y94917D01*
X378929Y95250D01*
X379012Y95583D01*
X379221Y95833D01*
X379471Y96000D01*
X379804Y96125D01*
X380179Y96167D01*
X380554Y96125D01*
X380887Y96000D01*
X381137Y95833D01*
X381346Y95583D01*
X381429Y95250D01*
G01X366373Y101925D02*
X366165Y102258D01*
X366040Y102633D01*
Y102967D01*
X366165Y103300D01*
X366373Y103550D01*
X366665Y103675D01*
X366957Y103592D01*
X367207Y103383D01*
X367373Y103008D01*
X367457Y102508D01*
X367623Y102217D01*
X367915Y102092D01*
X368207Y102175D01*
X368415Y102383D01*
X368540Y102675D01*
Y102967D01*
X368457Y103258D01*
X368248Y103508D01*
G01X368332Y106817D02*
X368457Y106567D01*
X368540Y106275D01*
Y105942D01*
X368415Y105567D01*
X368207Y105275D01*
X367957Y105067D01*
X367540Y104900D01*
X367165Y104858D01*
X366790Y104942D01*
X366540Y105067D01*
X366290Y105317D01*
X366123Y105608D01*
X366040Y105900D01*
Y106192D01*
X366123Y106483D01*
X366248Y106733D01*
X366415Y106942D01*
G01X366040Y109000D02*
X366082Y109292D01*
X366207Y109625D01*
X366415Y109833D01*
X366707Y109917D01*
X366998Y109833D01*
X367248Y109583D01*
X367373Y109208D01*
Y108792D01*
X367457Y108542D01*
X367665Y108333D01*
X367957Y108250D01*
X368248Y108375D01*
X368457Y108667D01*
X368540Y109000D01*
X368457Y109333D01*
X368248Y109625D01*
X367957Y109750D01*
X367665Y109667D01*
X367457Y109458D01*
X367373Y109208D01*
Y108792D01*
X367248Y108417D01*
X366998Y108167D01*
X366707Y108083D01*
X366415Y108167D01*
X366207Y108375D01*
X366082Y108708D01*
X366040Y109000D01*
G01X367082Y111308D02*
X367373Y111600D01*
X367540Y111850D01*
X367623Y112183D01*
X367540Y112475D01*
X367373Y112683D01*
X367123Y112850D01*
X366832Y112892D01*
X366582Y112850D01*
X366332Y112683D01*
X366123Y112433D01*
X366040Y112142D01*
X366123Y111808D01*
X366373Y111517D01*
X366748Y111350D01*
X367165Y111308D01*
X367707Y111392D01*
X367998Y111517D01*
X368290Y111725D01*
X368498Y112017D01*
X368540Y112308D01*
X368457Y112600D01*
X368248Y112808D01*
G01X366040Y115700D02*
X368540D01*
X366748Y114158D01*
Y116242D01*
G01X370373Y101925D02*
X370165Y102258D01*
X370040Y102633D01*
Y102967D01*
X370165Y103300D01*
X370373Y103550D01*
X370665Y103675D01*
X370957Y103592D01*
X371207Y103383D01*
X371373Y103008D01*
X371457Y102508D01*
X371623Y102217D01*
X371915Y102092D01*
X372207Y102175D01*
X372415Y102383D01*
X372540Y102675D01*
Y102967D01*
X372457Y103258D01*
X372248Y103508D01*
G01X372332Y106817D02*
X372457Y106567D01*
X372540Y106275D01*
Y105942D01*
X372415Y105567D01*
X372207Y105275D01*
X371957Y105067D01*
X371540Y104900D01*
X371165Y104858D01*
X370790Y104942D01*
X370540Y105067D01*
X370290Y105317D01*
X370123Y105608D01*
X370040Y105900D01*
Y106192D01*
X370123Y106483D01*
X370248Y106733D01*
X370415Y106942D01*
G01X370040Y109000D02*
X370082Y109292D01*
X370207Y109625D01*
X370415Y109833D01*
X370707Y109917D01*
X370998Y109833D01*
X371248Y109583D01*
X371373Y109208D01*
Y108792D01*
X371457Y108542D01*
X371665Y108333D01*
X371957Y108250D01*
X372248Y108375D01*
X372457Y108667D01*
X372540Y109000D01*
X372457Y109333D01*
X372248Y109625D01*
X371957Y109750D01*
X371665Y109667D01*
X371457Y109458D01*
X371373Y109208D01*
Y108792D01*
X371248Y108417D01*
X370998Y108167D01*
X370707Y108083D01*
X370415Y108167D01*
X370207Y108375D01*
X370082Y108708D01*
X370040Y109000D01*
G01X371082Y111308D02*
X371373Y111600D01*
X371540Y111850D01*
X371623Y112183D01*
X371540Y112475D01*
X371373Y112683D01*
X371123Y112850D01*
X370832Y112892D01*
X370582Y112850D01*
X370332Y112683D01*
X370123Y112433D01*
X370040Y112142D01*
X370123Y111808D01*
X370373Y111517D01*
X370748Y111350D01*
X371165Y111308D01*
X371707Y111392D01*
X371998Y111517D01*
X372290Y111725D01*
X372498Y112017D01*
X372540Y112308D01*
X372457Y112600D01*
X372248Y112808D01*
G01X370415Y114283D02*
X370207Y114533D01*
X370082Y114825D01*
X370040Y115200D01*
X370123Y115575D01*
X370290Y115867D01*
X370582Y116075D01*
X370915Y116117D01*
X371248Y116033D01*
X371457Y115825D01*
X371623Y115533D01*
X371665Y115242D01*
X371623Y114950D01*
X371457Y114575D01*
X372540Y114700D01*
Y115825D01*
G01X374373Y101925D02*
X374165Y102258D01*
X374040Y102633D01*
Y102967D01*
X374165Y103300D01*
X374373Y103550D01*
X374665Y103675D01*
X374957Y103592D01*
X375207Y103383D01*
X375373Y103008D01*
X375457Y102508D01*
X375623Y102217D01*
X375915Y102092D01*
X376207Y102175D01*
X376415Y102383D01*
X376540Y102675D01*
Y102967D01*
X376457Y103258D01*
X376248Y103508D01*
G01X376332Y106817D02*
X376457Y106567D01*
X376540Y106275D01*
Y105942D01*
X376415Y105567D01*
X376207Y105275D01*
X375957Y105067D01*
X375540Y104900D01*
X375165Y104858D01*
X374790Y104942D01*
X374540Y105067D01*
X374290Y105317D01*
X374123Y105608D01*
X374040Y105900D01*
Y106192D01*
X374123Y106483D01*
X374248Y106733D01*
X374415Y106942D01*
G01X374040Y109000D02*
X374082Y109292D01*
X374207Y109625D01*
X374415Y109833D01*
X374707Y109917D01*
X374998Y109833D01*
X375248Y109583D01*
X375373Y109208D01*
Y108792D01*
X375457Y108542D01*
X375665Y108333D01*
X375957Y108250D01*
X376248Y108375D01*
X376457Y108667D01*
X376540Y109000D01*
X376457Y109333D01*
X376248Y109625D01*
X375957Y109750D01*
X375665Y109667D01*
X375457Y109458D01*
X375373Y109208D01*
Y108792D01*
X375248Y108417D01*
X374998Y108167D01*
X374707Y108083D01*
X374415Y108167D01*
X374207Y108375D01*
X374082Y108708D01*
X374040Y109000D01*
G01X375082Y111308D02*
X375373Y111600D01*
X375540Y111850D01*
X375623Y112183D01*
X375540Y112475D01*
X375373Y112683D01*
X375123Y112850D01*
X374832Y112892D01*
X374582Y112850D01*
X374332Y112683D01*
X374123Y112433D01*
X374040Y112142D01*
X374123Y111808D01*
X374373Y111517D01*
X374748Y111350D01*
X375165Y111308D01*
X375707Y111392D01*
X375998Y111517D01*
X376290Y111725D01*
X376498Y112017D01*
X376540Y112308D01*
X376457Y112600D01*
X376248Y112808D01*
G01X375082Y114408D02*
X375373Y114700D01*
X375540Y114950D01*
X375623Y115283D01*
X375540Y115575D01*
X375373Y115783D01*
X375123Y115950D01*
X374832Y115992D01*
X374582Y115950D01*
X374332Y115783D01*
X374123Y115533D01*
X374040Y115242D01*
X374123Y114908D01*
X374373Y114617D01*
X374748Y114450D01*
X375165Y114408D01*
X375707Y114492D01*
X375998Y114617D01*
X376290Y114825D01*
X376498Y115117D01*
X376540Y115408D01*
X376457Y115700D01*
X376248Y115908D01*
G01X378373Y101875D02*
X378165Y102208D01*
X378040Y102583D01*
Y102917D01*
X378165Y103250D01*
X378373Y103500D01*
X378665Y103625D01*
X378957Y103542D01*
X379207Y103333D01*
X379373Y102958D01*
X379457Y102458D01*
X379623Y102167D01*
X379915Y102042D01*
X380207Y102125D01*
X380415Y102333D01*
X380540Y102625D01*
Y102917D01*
X380457Y103208D01*
X380248Y103458D01*
G01X380332Y106767D02*
X380457Y106517D01*
X380540Y106225D01*
Y105892D01*
X380415Y105517D01*
X380207Y105225D01*
X379957Y105017D01*
X379540Y104850D01*
X379165Y104808D01*
X378790Y104892D01*
X378540Y105017D01*
X378290Y105267D01*
X378123Y105558D01*
X378040Y105850D01*
Y106142D01*
X378123Y106433D01*
X378248Y106683D01*
X378415Y106892D01*
G01X378040Y108950D02*
X380540D01*
X380040Y108450D01*
G01X378040D02*
Y109450D01*
G01X380123Y111258D02*
X380373Y111508D01*
X380498Y111800D01*
X380540Y112133D01*
X380457Y112550D01*
X380248Y112842D01*
X379998Y112925D01*
X379748Y112883D01*
X379540Y112717D01*
X379123Y111883D01*
X378832Y111508D01*
X378415Y111258D01*
X378040Y111175D01*
Y112925D01*
G01X378332Y114442D02*
X378123Y114733D01*
X378040Y115067D01*
X378123Y115400D01*
X378373Y115692D01*
X378748Y115900D01*
X379123Y115983D01*
X379582D01*
X379957Y115900D01*
X380290Y115692D01*
X380457Y115442D01*
X380540Y115150D01*
X380457Y114817D01*
X380290Y114567D01*
X380040Y114400D01*
X379707Y114317D01*
X379415Y114400D01*
X379123Y114608D01*
X378957Y114858D01*
X378915Y115150D01*
X378998Y115483D01*
X379207Y115733D01*
X379582Y115983D01*
G01X379082Y117458D02*
X379373Y117750D01*
X379540Y118000D01*
X379623Y118333D01*
X379540Y118625D01*
X379373Y118833D01*
X379123Y119000D01*
X378832Y119042D01*
X378582Y119000D01*
X378332Y118833D01*
X378123Y118583D01*
X378040Y118292D01*
X378123Y117958D01*
X378373Y117667D01*
X378748Y117500D01*
X379165Y117458D01*
X379707Y117542D01*
X379998Y117667D01*
X380290Y117875D01*
X380498Y118167D01*
X380540Y118458D01*
X380457Y118750D01*
X380248Y118958D01*
G01X368833Y133425D02*
X368625Y133758D01*
X368500Y134133D01*
Y134467D01*
X368625Y134800D01*
X368833Y135050D01*
X369125Y135175D01*
X369417Y135092D01*
X369667Y134883D01*
X369833Y134508D01*
X369917Y134008D01*
X370083Y133717D01*
X370375Y133592D01*
X370667Y133675D01*
X370875Y133883D01*
X371000Y134175D01*
Y134467D01*
X370917Y134758D01*
X370708Y135008D01*
G01X370792Y138317D02*
X370917Y138067D01*
X371000Y137775D01*
Y137442D01*
X370875Y137067D01*
X370667Y136775D01*
X370417Y136567D01*
X370000Y136400D01*
X369625Y136358D01*
X369250Y136442D01*
X369000Y136567D01*
X368750Y136817D01*
X368583Y137108D01*
X368500Y137400D01*
Y137692D01*
X368583Y137983D01*
X368708Y138233D01*
X368875Y138442D01*
G01X368792Y139792D02*
X368583Y140083D01*
X368500Y140417D01*
X368583Y140750D01*
X368833Y141042D01*
X369208Y141250D01*
X369583Y141333D01*
X370042D01*
X370417Y141250D01*
X370750Y141042D01*
X370917Y140792D01*
X371000Y140500D01*
X370917Y140167D01*
X370750Y139917D01*
X370500Y139750D01*
X370167Y139667D01*
X369875Y139750D01*
X369583Y139958D01*
X369417Y140208D01*
X369375Y140500D01*
X369458Y140833D01*
X369667Y141083D01*
X370042Y141333D01*
G01X368500Y144100D02*
X371000D01*
X369208Y142558D01*
Y144642D01*
G01X368500Y146617D02*
X369042Y146700D01*
X369500Y146825D01*
X369917Y146992D01*
X370375Y147200D01*
X371000Y147533D01*
Y145867D01*
G01X386575Y128833D02*
X386242Y128625D01*
X385867Y128500D01*
X385533D01*
X385200Y128625D01*
X384950Y128833D01*
X384825Y129125D01*
X384908Y129417D01*
X385117Y129667D01*
X385492Y129833D01*
X385992Y129917D01*
X386283Y130083D01*
X386408Y130375D01*
X386325Y130667D01*
X386117Y130875D01*
X385825Y131000D01*
X385533D01*
X385242Y130917D01*
X384992Y130708D01*
G01X381683Y130792D02*
X381933Y130917D01*
X382225Y131000D01*
X382558D01*
X382933Y130875D01*
X383225Y130667D01*
X383433Y130417D01*
X383600Y130000D01*
X383642Y129625D01*
X383558Y129250D01*
X383433Y129000D01*
X383183Y128750D01*
X382892Y128583D01*
X382600Y128500D01*
X382308D01*
X382017Y128583D01*
X381767Y128708D01*
X381558Y128875D01*
G01X380208Y128792D02*
X379917Y128583D01*
X379583Y128500D01*
X379250Y128583D01*
X378958Y128833D01*
X378750Y129208D01*
X378667Y129583D01*
Y130042D01*
X378750Y130417D01*
X378958Y130750D01*
X379208Y130917D01*
X379500Y131000D01*
X379833Y130917D01*
X380083Y130750D01*
X380250Y130500D01*
X380333Y130167D01*
X380250Y129875D01*
X380042Y129583D01*
X379792Y129417D01*
X379500Y129375D01*
X379167Y129458D01*
X378917Y129667D01*
X378667Y130042D01*
G01X377317Y128875D02*
X377067Y128667D01*
X376775Y128542D01*
X376400Y128500D01*
X376025Y128583D01*
X375733Y128750D01*
X375525Y129042D01*
X375483Y129375D01*
X375567Y129708D01*
X375775Y129917D01*
X376067Y130083D01*
X376358Y130125D01*
X376650Y130083D01*
X377025Y129917D01*
X376900Y131000D01*
X375775D01*
G01X374092Y130583D02*
X373842Y130833D01*
X373550Y130958D01*
X373217Y131000D01*
X372800Y130917D01*
X372508Y130708D01*
X372425Y130458D01*
X372467Y130208D01*
X372633Y130000D01*
X373467Y129583D01*
X373842Y129292D01*
X374092Y128875D01*
X374175Y128500D01*
X372425D01*
G01X377833Y134925D02*
X377625Y135258D01*
X377500Y135633D01*
Y135967D01*
X377625Y136300D01*
X377833Y136550D01*
X378125Y136675D01*
X378417Y136592D01*
X378667Y136383D01*
X378833Y136008D01*
X378917Y135508D01*
X379083Y135217D01*
X379375Y135092D01*
X379667Y135175D01*
X379875Y135383D01*
X380000Y135675D01*
Y135967D01*
X379917Y136258D01*
X379708Y136508D01*
G01X379792Y139817D02*
X379917Y139567D01*
X380000Y139275D01*
Y138942D01*
X379875Y138567D01*
X379667Y138275D01*
X379417Y138067D01*
X379000Y137900D01*
X378625Y137858D01*
X378250Y137942D01*
X378000Y138067D01*
X377750Y138317D01*
X377583Y138608D01*
X377500Y138900D01*
Y139192D01*
X377583Y139483D01*
X377708Y139733D01*
X377875Y139942D01*
G01X377792Y141292D02*
X377583Y141583D01*
X377500Y141917D01*
X377583Y142250D01*
X377833Y142542D01*
X378208Y142750D01*
X378583Y142833D01*
X379042D01*
X379417Y142750D01*
X379750Y142542D01*
X379917Y142292D01*
X380000Y142000D01*
X379917Y141667D01*
X379750Y141417D01*
X379500Y141250D01*
X379167Y141167D01*
X378875Y141250D01*
X378583Y141458D01*
X378417Y141708D01*
X378375Y142000D01*
X378458Y142333D01*
X378667Y142583D01*
X379042Y142833D01*
G01X377500Y145600D02*
X380000D01*
X378208Y144058D01*
Y146142D01*
G01X377500Y148700D02*
X380000D01*
X378208Y147158D01*
Y149242D01*
G01X386500Y168000D02*
X393500D01*
Y193000D01*
X397000D01*
Y212000D01*
X367000D01*
Y204500D01*
X369000D01*
Y176500D01*
X382500D01*
Y168000D01*
X386500D01*
G01X371200Y185240D02*
X375200D01*
Y177840D01*
G01X378829Y193300D02*
X382829D01*
Y185900D01*
G01X369429Y209200D02*
X373429D01*
Y201800D01*
G01X370262Y218425D02*
X370054Y218758D01*
X369929Y219133D01*
Y219467D01*
X370054Y219800D01*
X370262Y220050D01*
X370554Y220175D01*
X370846Y220092D01*
X371096Y219883D01*
X371262Y219508D01*
X371346Y219008D01*
X371512Y218717D01*
X371804Y218592D01*
X372096Y218675D01*
X372304Y218883D01*
X372429Y219175D01*
Y219467D01*
X372346Y219758D01*
X372137Y220008D01*
G01X372221Y223317D02*
X372346Y223067D01*
X372429Y222775D01*
Y222442D01*
X372304Y222067D01*
X372096Y221775D01*
X371846Y221567D01*
X371429Y221400D01*
X371054Y221358D01*
X370679Y221442D01*
X370429Y221567D01*
X370179Y221817D01*
X370012Y222108D01*
X369929Y222400D01*
Y222692D01*
X370012Y222983D01*
X370137Y223233D01*
X370304Y223442D01*
G01X370221Y224792D02*
X370012Y225083D01*
X369929Y225417D01*
X370012Y225750D01*
X370262Y226042D01*
X370637Y226250D01*
X371012Y226333D01*
X371471D01*
X371846Y226250D01*
X372179Y226042D01*
X372346Y225792D01*
X372429Y225500D01*
X372346Y225167D01*
X372179Y224917D01*
X371929Y224750D01*
X371596Y224667D01*
X371304Y224750D01*
X371012Y224958D01*
X370846Y225208D01*
X370804Y225500D01*
X370887Y225833D01*
X371096Y226083D01*
X371471Y226333D01*
G01X369929Y228600D02*
X369971Y228892D01*
X370096Y229225D01*
X370304Y229433D01*
X370596Y229517D01*
X370887Y229433D01*
X371137Y229183D01*
X371262Y228808D01*
Y228392D01*
X371346Y228142D01*
X371554Y227933D01*
X371846Y227850D01*
X372137Y227975D01*
X372346Y228267D01*
X372429Y228600D01*
X372346Y228933D01*
X372137Y229225D01*
X371846Y229350D01*
X371554Y229267D01*
X371346Y229058D01*
X371262Y228808D01*
Y228392D01*
X371137Y228017D01*
X370887Y227767D01*
X370596Y227683D01*
X370304Y227767D01*
X370096Y227975D01*
X369971Y228308D01*
X369929Y228600D01*
G01X372429Y231700D02*
X372346Y231367D01*
X372137Y231117D01*
X371887Y230950D01*
X371554Y230825D01*
X371179Y230783D01*
X370804Y230825D01*
X370471Y230950D01*
X370221Y231117D01*
X370012Y231367D01*
X369929Y231700D01*
X370012Y232033D01*
X370221Y232283D01*
X370471Y232450D01*
X370804Y232575D01*
X371179Y232617D01*
X371554Y232575D01*
X371887Y232450D01*
X372137Y232283D01*
X372346Y232033D01*
X372429Y231700D01*
G01X377262Y218425D02*
X377054Y218758D01*
X376929Y219133D01*
Y219467D01*
X377054Y219800D01*
X377262Y220050D01*
X377554Y220175D01*
X377846Y220092D01*
X378096Y219883D01*
X378262Y219508D01*
X378346Y219008D01*
X378512Y218717D01*
X378804Y218592D01*
X379096Y218675D01*
X379304Y218883D01*
X379429Y219175D01*
Y219467D01*
X379346Y219758D01*
X379137Y220008D01*
G01X379221Y223317D02*
X379346Y223067D01*
X379429Y222775D01*
Y222442D01*
X379304Y222067D01*
X379096Y221775D01*
X378846Y221567D01*
X378429Y221400D01*
X378054Y221358D01*
X377679Y221442D01*
X377429Y221567D01*
X377179Y221817D01*
X377012Y222108D01*
X376929Y222400D01*
Y222692D01*
X377012Y222983D01*
X377137Y223233D01*
X377304Y223442D01*
G01X377221Y224792D02*
X377012Y225083D01*
X376929Y225417D01*
X377012Y225750D01*
X377262Y226042D01*
X377637Y226250D01*
X378012Y226333D01*
X378471D01*
X378846Y226250D01*
X379179Y226042D01*
X379346Y225792D01*
X379429Y225500D01*
X379346Y225167D01*
X379179Y224917D01*
X378929Y224750D01*
X378596Y224667D01*
X378304Y224750D01*
X378012Y224958D01*
X377846Y225208D01*
X377804Y225500D01*
X377887Y225833D01*
X378096Y226083D01*
X378471Y226333D01*
G01X376929Y228600D02*
X376971Y228892D01*
X377096Y229225D01*
X377304Y229433D01*
X377596Y229517D01*
X377887Y229433D01*
X378137Y229183D01*
X378262Y228808D01*
Y228392D01*
X378346Y228142D01*
X378554Y227933D01*
X378846Y227850D01*
X379137Y227975D01*
X379346Y228267D01*
X379429Y228600D01*
X379346Y228933D01*
X379137Y229225D01*
X378846Y229350D01*
X378554Y229267D01*
X378346Y229058D01*
X378262Y228808D01*
Y228392D01*
X378137Y228017D01*
X377887Y227767D01*
X377596Y227683D01*
X377304Y227767D01*
X377096Y227975D01*
X376971Y228308D01*
X376929Y228600D01*
G01Y231700D02*
X379429D01*
X378929Y231200D01*
G01X376929D02*
Y232200D01*
G01X364762Y223125D02*
X364554Y223458D01*
X364429Y223833D01*
Y224167D01*
X364554Y224500D01*
X364762Y224750D01*
X365054Y224875D01*
X365346Y224792D01*
X365596Y224583D01*
X365762Y224208D01*
X365846Y223708D01*
X366012Y223417D01*
X366304Y223292D01*
X366596Y223375D01*
X366804Y223583D01*
X366929Y223875D01*
Y224167D01*
X366846Y224458D01*
X366637Y224708D01*
G01X366721Y228017D02*
X366846Y227767D01*
X366929Y227475D01*
Y227142D01*
X366804Y226767D01*
X366596Y226475D01*
X366346Y226267D01*
X365929Y226100D01*
X365554Y226058D01*
X365179Y226142D01*
X364929Y226267D01*
X364679Y226517D01*
X364512Y226808D01*
X364429Y227100D01*
Y227392D01*
X364512Y227683D01*
X364637Y227933D01*
X364804Y228142D01*
G01X364429Y230200D02*
X366929D01*
X366429Y229700D01*
G01X364429D02*
Y230700D01*
G01X366929Y233300D02*
X366846Y232967D01*
X366637Y232717D01*
X366387Y232550D01*
X366054Y232425D01*
X365679Y232383D01*
X365304Y232425D01*
X364971Y232550D01*
X364721Y232717D01*
X364512Y232967D01*
X364429Y233300D01*
X364512Y233633D01*
X364721Y233883D01*
X364971Y234050D01*
X365304Y234175D01*
X365679Y234217D01*
X366054Y234175D01*
X366387Y234050D01*
X366637Y233883D01*
X366846Y233633D01*
X366929Y233300D01*
G01Y236400D02*
X366846Y236067D01*
X366637Y235817D01*
X366387Y235650D01*
X366054Y235525D01*
X365679Y235483D01*
X365304Y235525D01*
X364971Y235650D01*
X364721Y235817D01*
X364512Y236067D01*
X364429Y236400D01*
X364512Y236733D01*
X364721Y236983D01*
X364971Y237150D01*
X365304Y237275D01*
X365679Y237317D01*
X366054Y237275D01*
X366387Y237150D01*
X366637Y236983D01*
X366846Y236733D01*
X366929Y236400D01*
G01X364721Y238792D02*
X364512Y239083D01*
X364429Y239417D01*
X364512Y239750D01*
X364762Y240042D01*
X365137Y240250D01*
X365512Y240333D01*
X365971D01*
X366346Y240250D01*
X366679Y240042D01*
X366846Y239792D01*
X366929Y239500D01*
X366846Y239167D01*
X366679Y238917D01*
X366429Y238750D01*
X366096Y238667D01*
X365804Y238750D01*
X365512Y238958D01*
X365346Y239208D01*
X365304Y239500D01*
X365387Y239833D01*
X365596Y240083D01*
X365971Y240333D01*
G01X386625Y238833D02*
X386292Y238625D01*
X385917Y238500D01*
X385583D01*
X385250Y238625D01*
X385000Y238833D01*
X384875Y239125D01*
X384958Y239417D01*
X385167Y239667D01*
X385542Y239833D01*
X386042Y239917D01*
X386333Y240083D01*
X386458Y240375D01*
X386375Y240667D01*
X386167Y240875D01*
X385875Y241000D01*
X385583D01*
X385292Y240917D01*
X385042Y240708D01*
G01X381733Y240792D02*
X381983Y240917D01*
X382275Y241000D01*
X382608D01*
X382983Y240875D01*
X383275Y240667D01*
X383483Y240417D01*
X383650Y240000D01*
X383692Y239625D01*
X383608Y239250D01*
X383483Y239000D01*
X383233Y238750D01*
X382942Y238583D01*
X382650Y238500D01*
X382358D01*
X382067Y238583D01*
X381817Y238708D01*
X381608Y238875D01*
G01X379550Y238500D02*
Y241000D01*
X380050Y240500D01*
G01Y238500D02*
X379050D01*
G01X376450Y241000D02*
X376783Y240917D01*
X377033Y240708D01*
X377200Y240458D01*
X377325Y240125D01*
X377367Y239750D01*
X377325Y239375D01*
X377200Y239042D01*
X377033Y238792D01*
X376783Y238583D01*
X376450Y238500D01*
X376117Y238583D01*
X375867Y238792D01*
X375700Y239042D01*
X375575Y239375D01*
X375533Y239750D01*
X375575Y240125D01*
X375700Y240458D01*
X375867Y240708D01*
X376117Y240917D01*
X376450Y241000D01*
G01X373350D02*
X373683Y240917D01*
X373933Y240708D01*
X374100Y240458D01*
X374225Y240125D01*
X374267Y239750D01*
X374225Y239375D01*
X374100Y239042D01*
X373933Y238792D01*
X373683Y238583D01*
X373350Y238500D01*
X373017Y238583D01*
X372767Y238792D01*
X372600Y239042D01*
X372475Y239375D01*
X372433Y239750D01*
X372475Y240125D01*
X372600Y240458D01*
X372767Y240708D01*
X373017Y240917D01*
X373350Y241000D01*
G01X369750Y238500D02*
Y241000D01*
X371292Y239208D01*
X369208D01*
G01X386575Y243333D02*
X386242Y243125D01*
X385867Y243000D01*
X385533D01*
X385200Y243125D01*
X384950Y243333D01*
X384825Y243625D01*
X384908Y243917D01*
X385117Y244167D01*
X385492Y244333D01*
X385992Y244417D01*
X386283Y244583D01*
X386408Y244875D01*
X386325Y245167D01*
X386117Y245375D01*
X385825Y245500D01*
X385533D01*
X385242Y245417D01*
X384992Y245208D01*
G01X381683Y245292D02*
X381933Y245417D01*
X382225Y245500D01*
X382558D01*
X382933Y245375D01*
X383225Y245167D01*
X383433Y244917D01*
X383600Y244500D01*
X383642Y244125D01*
X383558Y243750D01*
X383433Y243500D01*
X383183Y243250D01*
X382892Y243083D01*
X382600Y243000D01*
X382308D01*
X382017Y243083D01*
X381767Y243208D01*
X381558Y243375D01*
G01X380208Y243292D02*
X379917Y243083D01*
X379583Y243000D01*
X379250Y243083D01*
X378958Y243333D01*
X378750Y243708D01*
X378667Y244083D01*
Y244542D01*
X378750Y244917D01*
X378958Y245250D01*
X379208Y245417D01*
X379500Y245500D01*
X379833Y245417D01*
X380083Y245250D01*
X380250Y245000D01*
X380333Y244667D01*
X380250Y244375D01*
X380042Y244083D01*
X379792Y243917D01*
X379500Y243875D01*
X379167Y243958D01*
X378917Y244167D01*
X378667Y244542D01*
G01X376483Y243000D02*
X376400Y243542D01*
X376275Y244000D01*
X376108Y244417D01*
X375900Y244875D01*
X375567Y245500D01*
X377233D01*
G01X373300Y243000D02*
Y245500D01*
X373800Y245000D01*
G01Y243000D02*
X372800D01*
G01X383054Y263333D02*
X382721Y263125D01*
X382346Y263000D01*
X382012D01*
X381679Y263125D01*
X381429Y263333D01*
X381304Y263625D01*
X381387Y263917D01*
X381596Y264167D01*
X381971Y264333D01*
X382471Y264417D01*
X382762Y264583D01*
X382887Y264875D01*
X382804Y265167D01*
X382596Y265375D01*
X382304Y265500D01*
X382012D01*
X381721Y265417D01*
X381471Y265208D01*
G01X378162Y265292D02*
X378412Y265417D01*
X378704Y265500D01*
X379037D01*
X379412Y265375D01*
X379704Y265167D01*
X379912Y264917D01*
X380079Y264500D01*
X380121Y264125D01*
X380037Y263750D01*
X379912Y263500D01*
X379662Y263250D01*
X379371Y263083D01*
X379079Y263000D01*
X378787D01*
X378496Y263083D01*
X378246Y263208D01*
X378037Y263375D01*
G01X375979Y263000D02*
Y265500D01*
X376479Y265000D01*
G01Y263000D02*
X375479D01*
G01X372879Y265500D02*
X373212Y265417D01*
X373462Y265208D01*
X373629Y264958D01*
X373754Y264625D01*
X373796Y264250D01*
X373754Y263875D01*
X373629Y263542D01*
X373462Y263292D01*
X373212Y263083D01*
X372879Y263000D01*
X372546Y263083D01*
X372296Y263292D01*
X372129Y263542D01*
X372004Y263875D01*
X371962Y264250D01*
X372004Y264625D01*
X372129Y264958D01*
X372296Y265208D01*
X372546Y265417D01*
X372879Y265500D01*
G01X370696Y263500D02*
X370446Y263208D01*
X370112Y263042D01*
X369737Y263000D01*
X369404Y263042D01*
X369071Y263250D01*
X368862Y263500D01*
X368821Y263750D01*
X368904Y264042D01*
X369196Y264250D01*
X369487Y264333D01*
X369862D01*
G01X369487D02*
X369237Y264458D01*
X369029Y264667D01*
X368946Y264917D01*
X369029Y265167D01*
X369237Y265375D01*
X369612Y265500D01*
X369987Y265458D01*
X370362Y265292D01*
G01X366679Y265500D02*
X367012Y265417D01*
X367262Y265208D01*
X367429Y264958D01*
X367554Y264625D01*
X367596Y264250D01*
X367554Y263875D01*
X367429Y263542D01*
X367262Y263292D01*
X367012Y263083D01*
X366679Y263000D01*
X366346Y263083D01*
X366096Y263292D01*
X365929Y263542D01*
X365804Y263875D01*
X365762Y264250D01*
X365804Y264625D01*
X365929Y264958D01*
X366096Y265208D01*
X366346Y265417D01*
X366679Y265500D01*
G01X383054Y267833D02*
X382721Y267625D01*
X382346Y267500D01*
X382012D01*
X381679Y267625D01*
X381429Y267833D01*
X381304Y268125D01*
X381387Y268417D01*
X381596Y268667D01*
X381971Y268833D01*
X382471Y268917D01*
X382762Y269083D01*
X382887Y269375D01*
X382804Y269667D01*
X382596Y269875D01*
X382304Y270000D01*
X382012D01*
X381721Y269917D01*
X381471Y269708D01*
G01X378162Y269792D02*
X378412Y269917D01*
X378704Y270000D01*
X379037D01*
X379412Y269875D01*
X379704Y269667D01*
X379912Y269417D01*
X380079Y269000D01*
X380121Y268625D01*
X380037Y268250D01*
X379912Y268000D01*
X379662Y267750D01*
X379371Y267583D01*
X379079Y267500D01*
X378787D01*
X378496Y267583D01*
X378246Y267708D01*
X378037Y267875D01*
G01X375979Y267500D02*
Y270000D01*
X376479Y269500D01*
G01Y267500D02*
X375479D01*
G01X372879Y270000D02*
X373212Y269917D01*
X373462Y269708D01*
X373629Y269458D01*
X373754Y269125D01*
X373796Y268750D01*
X373754Y268375D01*
X373629Y268042D01*
X373462Y267792D01*
X373212Y267583D01*
X372879Y267500D01*
X372546Y267583D01*
X372296Y267792D01*
X372129Y268042D01*
X372004Y268375D01*
X371962Y268750D01*
X372004Y269125D01*
X372129Y269458D01*
X372296Y269708D01*
X372546Y269917D01*
X372879Y270000D01*
G01X370571Y268542D02*
X370279Y268833D01*
X370029Y269000D01*
X369696Y269083D01*
X369404Y269000D01*
X369196Y268833D01*
X369029Y268583D01*
X368987Y268292D01*
X369029Y268042D01*
X369196Y267792D01*
X369446Y267583D01*
X369737Y267500D01*
X370071Y267583D01*
X370362Y267833D01*
X370529Y268208D01*
X370571Y268625D01*
X370487Y269167D01*
X370362Y269458D01*
X370154Y269750D01*
X369862Y269958D01*
X369571Y270000D01*
X369279Y269917D01*
X369071Y269708D01*
G01X367596Y268000D02*
X367346Y267708D01*
X367012Y267542D01*
X366637Y267500D01*
X366304Y267542D01*
X365971Y267750D01*
X365762Y268000D01*
X365721Y268250D01*
X365804Y268542D01*
X366096Y268750D01*
X366387Y268833D01*
X366762D01*
G01X366387D02*
X366137Y268958D01*
X365929Y269167D01*
X365846Y269417D01*
X365929Y269667D01*
X366137Y269875D01*
X366512Y270000D01*
X366887Y269958D01*
X367262Y269792D01*
G01X383054Y272333D02*
X382721Y272125D01*
X382346Y272000D01*
X382012D01*
X381679Y272125D01*
X381429Y272333D01*
X381304Y272625D01*
X381387Y272917D01*
X381596Y273167D01*
X381971Y273333D01*
X382471Y273417D01*
X382762Y273583D01*
X382887Y273875D01*
X382804Y274167D01*
X382596Y274375D01*
X382304Y274500D01*
X382012D01*
X381721Y274417D01*
X381471Y274208D01*
G01X378162Y274292D02*
X378412Y274417D01*
X378704Y274500D01*
X379037D01*
X379412Y274375D01*
X379704Y274167D01*
X379912Y273917D01*
X380079Y273500D01*
X380121Y273125D01*
X380037Y272750D01*
X379912Y272500D01*
X379662Y272250D01*
X379371Y272083D01*
X379079Y272000D01*
X378787D01*
X378496Y272083D01*
X378246Y272208D01*
X378037Y272375D01*
G01X375979Y272000D02*
Y274500D01*
X376479Y274000D01*
G01Y272000D02*
X375479D01*
G01X372879Y274500D02*
X373212Y274417D01*
X373462Y274208D01*
X373629Y273958D01*
X373754Y273625D01*
X373796Y273250D01*
X373754Y272875D01*
X373629Y272542D01*
X373462Y272292D01*
X373212Y272083D01*
X372879Y272000D01*
X372546Y272083D01*
X372296Y272292D01*
X372129Y272542D01*
X372004Y272875D01*
X371962Y273250D01*
X372004Y273625D01*
X372129Y273958D01*
X372296Y274208D01*
X372546Y274417D01*
X372879Y274500D01*
G01X370571Y274083D02*
X370321Y274333D01*
X370029Y274458D01*
X369696Y274500D01*
X369279Y274417D01*
X368987Y274208D01*
X368904Y273958D01*
X368946Y273708D01*
X369112Y273500D01*
X369946Y273083D01*
X370321Y272792D01*
X370571Y272375D01*
X370654Y272000D01*
X368904D01*
G01X366679D02*
Y274500D01*
X367179Y274000D01*
G01Y272000D02*
X366179D01*
G01X383004Y276833D02*
X382671Y276625D01*
X382296Y276500D01*
X381962D01*
X381629Y276625D01*
X381379Y276833D01*
X381254Y277125D01*
X381337Y277417D01*
X381546Y277667D01*
X381921Y277833D01*
X382421Y277917D01*
X382712Y278083D01*
X382837Y278375D01*
X382754Y278667D01*
X382546Y278875D01*
X382254Y279000D01*
X381962D01*
X381671Y278917D01*
X381421Y278708D01*
G01X379862Y276500D02*
Y279000D01*
X378821D01*
X378487Y278875D01*
X378279Y278708D01*
X378196Y278375D01*
X378279Y278042D01*
X378529Y277833D01*
X378821Y277708D01*
X379862D01*
G01X378821D02*
X378196Y276500D01*
G01X376721Y277542D02*
X376429Y277833D01*
X376179Y278000D01*
X375846Y278083D01*
X375554Y278000D01*
X375346Y277833D01*
X375179Y277583D01*
X375137Y277292D01*
X375179Y277042D01*
X375346Y276792D01*
X375596Y276583D01*
X375887Y276500D01*
X376221Y276583D01*
X376512Y276833D01*
X376679Y277208D01*
X376721Y277625D01*
X376637Y278167D01*
X376512Y278458D01*
X376304Y278750D01*
X376012Y278958D01*
X375721Y279000D01*
X375429Y278917D01*
X375221Y278708D01*
G01X372829Y276500D02*
X372537Y276542D01*
X372204Y276667D01*
X371996Y276875D01*
X371912Y277167D01*
X371996Y277458D01*
X372246Y277708D01*
X372621Y277833D01*
X373037D01*
X373287Y277917D01*
X373496Y278125D01*
X373579Y278417D01*
X373454Y278708D01*
X373162Y278917D01*
X372829Y279000D01*
X372496Y278917D01*
X372204Y278708D01*
X372079Y278417D01*
X372162Y278125D01*
X372371Y277917D01*
X372621Y277833D01*
X373037D01*
X373412Y277708D01*
X373662Y277458D01*
X373746Y277167D01*
X373662Y276875D01*
X373454Y276667D01*
X373121Y276542D01*
X372829Y276500D01*
G01X369729Y279000D02*
X370062Y278917D01*
X370312Y278708D01*
X370479Y278458D01*
X370604Y278125D01*
X370646Y277750D01*
X370604Y277375D01*
X370479Y277042D01*
X370312Y276792D01*
X370062Y276583D01*
X369729Y276500D01*
X369396Y276583D01*
X369146Y276792D01*
X368979Y277042D01*
X368854Y277375D01*
X368812Y277750D01*
X368854Y278125D01*
X368979Y278458D01*
X369146Y278708D01*
X369396Y278917D01*
X369729Y279000D01*
G01X365833Y326875D02*
X365625Y327208D01*
X365500Y327583D01*
Y327917D01*
X365625Y328250D01*
X365833Y328500D01*
X366125Y328625D01*
X366417Y328542D01*
X366667Y328333D01*
X366833Y327958D01*
X366917Y327458D01*
X367083Y327167D01*
X367375Y327042D01*
X367667Y327125D01*
X367875Y327333D01*
X368000Y327625D01*
Y327917D01*
X367917Y328208D01*
X367708Y328458D01*
G01X367792Y331767D02*
X367917Y331517D01*
X368000Y331225D01*
Y330892D01*
X367875Y330517D01*
X367667Y330225D01*
X367417Y330017D01*
X367000Y329850D01*
X366625Y329808D01*
X366250Y329892D01*
X366000Y330017D01*
X365750Y330267D01*
X365583Y330558D01*
X365500Y330850D01*
Y331142D01*
X365583Y331433D01*
X365708Y331683D01*
X365875Y331892D01*
G01X365500Y333950D02*
X368000D01*
X367500Y333450D01*
G01X365500D02*
Y334450D01*
G01X367583Y336258D02*
X367833Y336508D01*
X367958Y336800D01*
X368000Y337133D01*
X367917Y337550D01*
X367708Y337842D01*
X367458Y337925D01*
X367208Y337883D01*
X367000Y337717D01*
X366583Y336883D01*
X366292Y336508D01*
X365875Y336258D01*
X365500Y336175D01*
Y337925D01*
G01X365875Y339233D02*
X365667Y339483D01*
X365542Y339775D01*
X365500Y340150D01*
X365583Y340525D01*
X365750Y340817D01*
X366042Y341025D01*
X366375Y341067D01*
X366708Y340983D01*
X366917Y340775D01*
X367083Y340483D01*
X367125Y340192D01*
X367083Y339900D01*
X366917Y339525D01*
X368000Y339650D01*
Y340775D01*
G01X365500Y343167D02*
X366042Y343250D01*
X366500Y343375D01*
X366917Y343542D01*
X367375Y343750D01*
X368000Y344083D01*
Y342417D01*
G01X390125Y366833D02*
X389792Y366625D01*
X389417Y366500D01*
X389083D01*
X388750Y366625D01*
X388500Y366833D01*
X388375Y367125D01*
X388458Y367417D01*
X388667Y367667D01*
X389042Y367833D01*
X389542Y367917D01*
X389833Y368083D01*
X389958Y368375D01*
X389875Y368667D01*
X389667Y368875D01*
X389375Y369000D01*
X389083D01*
X388792Y368917D01*
X388542Y368708D01*
G01X386150Y369000D02*
Y366500D01*
G01X387108Y369000D02*
X385192D01*
G01X383883Y366500D02*
Y369000D01*
X382883D01*
X382550Y368875D01*
X382300Y368583D01*
X382217Y368250D01*
X382300Y367917D01*
X382508Y367667D01*
X382883Y367542D01*
X383883D01*
G01X379950Y366500D02*
Y369000D01*
X380450Y368500D01*
G01Y366500D02*
X379450D01*
G01X377642Y367542D02*
X377350Y367833D01*
X377100Y368000D01*
X376767Y368083D01*
X376475Y368000D01*
X376267Y367833D01*
X376100Y367583D01*
X376058Y367292D01*
X376100Y367042D01*
X376267Y366792D01*
X376517Y366583D01*
X376808Y366500D01*
X377142Y366583D01*
X377433Y366833D01*
X377600Y367208D01*
X377642Y367625D01*
X377558Y368167D01*
X377433Y368458D01*
X377225Y368750D01*
X376933Y368958D01*
X376642Y369000D01*
X376350Y368917D01*
X376142Y368708D01*
G01X374667Y367000D02*
X374417Y366708D01*
X374083Y366542D01*
X373708Y366500D01*
X373375Y366542D01*
X373042Y366750D01*
X372833Y367000D01*
X372792Y367250D01*
X372875Y367542D01*
X373167Y367750D01*
X373458Y367833D01*
X373833D01*
G01X373458D02*
X373208Y367958D01*
X373000Y368167D01*
X372917Y368417D01*
X373000Y368667D01*
X373208Y368875D01*
X373583Y369000D01*
X373958Y368958D01*
X374333Y368792D01*
G01X391075Y412333D02*
X390742Y412125D01*
X390367Y412000D01*
X390033D01*
X389700Y412125D01*
X389450Y412333D01*
X389325Y412625D01*
X389408Y412917D01*
X389617Y413167D01*
X389992Y413333D01*
X390492Y413417D01*
X390783Y413583D01*
X390908Y413875D01*
X390825Y414167D01*
X390617Y414375D01*
X390325Y414500D01*
X390033D01*
X389742Y414417D01*
X389492Y414208D01*
G01X387100Y414500D02*
Y412000D01*
G01X388058Y414500D02*
X386142D01*
G01X384833Y412000D02*
Y414500D01*
X383833D01*
X383500Y414375D01*
X383250Y414083D01*
X383167Y413750D01*
X383250Y413417D01*
X383458Y413167D01*
X383833Y413042D01*
X384833D01*
G01X380900Y412000D02*
X380608Y412042D01*
X380275Y412167D01*
X380067Y412375D01*
X379983Y412667D01*
X380067Y412958D01*
X380317Y413208D01*
X380692Y413333D01*
X381108D01*
X381358Y413417D01*
X381567Y413625D01*
X381650Y413917D01*
X381525Y414208D01*
X381233Y414417D01*
X380900Y414500D01*
X380567Y414417D01*
X380275Y414208D01*
X380150Y413917D01*
X380233Y413625D01*
X380442Y413417D01*
X380692Y413333D01*
X381108D01*
X381483Y413208D01*
X381733Y412958D01*
X381817Y412667D01*
X381733Y412375D01*
X381525Y412167D01*
X381192Y412042D01*
X380900Y412000D01*
G01X377800Y414500D02*
X378133Y414417D01*
X378383Y414208D01*
X378550Y413958D01*
X378675Y413625D01*
X378717Y413250D01*
X378675Y412875D01*
X378550Y412542D01*
X378383Y412292D01*
X378133Y412083D01*
X377800Y412000D01*
X377467Y412083D01*
X377217Y412292D01*
X377050Y412542D01*
X376925Y412875D01*
X376883Y413250D01*
X376925Y413625D01*
X377050Y413958D01*
X377217Y414208D01*
X377467Y414417D01*
X377800Y414500D01*
G01X389755Y426500D02*
Y424000D01*
G01X390713Y426500D02*
X388797D01*
G01X387488Y424000D02*
Y426500D01*
X386488D01*
X386155Y426375D01*
X385905Y426083D01*
X385822Y425750D01*
X385905Y425417D01*
X386113Y425167D01*
X386488Y425042D01*
X387488D01*
G01X384347Y426083D02*
X384097Y426333D01*
X383805Y426458D01*
X383472Y426500D01*
X383055Y426417D01*
X382763Y426208D01*
X382680Y425958D01*
X382722Y425708D01*
X382888Y425500D01*
X383722Y425083D01*
X384097Y424792D01*
X384347Y424375D01*
X384430Y424000D01*
X382680D01*
G01X381247Y425042D02*
X380955Y425333D01*
X380705Y425500D01*
X380372Y425583D01*
X380080Y425500D01*
X379872Y425333D01*
X379705Y425083D01*
X379663Y424792D01*
X379705Y424542D01*
X379872Y424292D01*
X380122Y424083D01*
X380413Y424000D01*
X380747Y424083D01*
X381038Y424333D01*
X381205Y424708D01*
X381247Y425125D01*
X381163Y425667D01*
X381038Y425958D01*
X380830Y426250D01*
X380538Y426458D01*
X380247Y426500D01*
X379955Y426417D01*
X379747Y426208D01*
G01X376855Y424000D02*
Y426500D01*
X378397Y424708D01*
X376313D01*
G01X390630Y431333D02*
X390297Y431125D01*
X389922Y431000D01*
X389588D01*
X389255Y431125D01*
X389005Y431333D01*
X388880Y431625D01*
X388963Y431917D01*
X389172Y432167D01*
X389547Y432333D01*
X390047Y432417D01*
X390338Y432583D01*
X390463Y432875D01*
X390380Y433167D01*
X390172Y433375D01*
X389880Y433500D01*
X389588D01*
X389297Y433417D01*
X389047Y433208D01*
G01X387488Y431000D02*
Y433500D01*
X386447D01*
X386113Y433375D01*
X385905Y433208D01*
X385822Y432875D01*
X385905Y432542D01*
X386155Y432333D01*
X386447Y432208D01*
X387488D01*
G01X386447D02*
X385822Y431000D01*
G01X383638D02*
X383555Y431542D01*
X383430Y432000D01*
X383263Y432417D01*
X383055Y432875D01*
X382722Y433500D01*
X384388D01*
G01X379955Y431000D02*
Y433500D01*
X381497Y431708D01*
X379413D01*
G01X377355Y431000D02*
X377063Y431042D01*
X376730Y431167D01*
X376522Y431375D01*
X376438Y431667D01*
X376522Y431958D01*
X376772Y432208D01*
X377147Y432333D01*
X377563D01*
X377813Y432417D01*
X378022Y432625D01*
X378105Y432917D01*
X377980Y433208D01*
X377688Y433417D01*
X377355Y433500D01*
X377022Y433417D01*
X376730Y433208D01*
X376605Y432917D01*
X376688Y432625D01*
X376897Y432417D01*
X377147Y432333D01*
X377563D01*
X377938Y432208D01*
X378188Y431958D01*
X378272Y431667D01*
X378188Y431375D01*
X377980Y431167D01*
X377647Y431042D01*
X377355Y431000D01*
G01X396680Y447833D02*
X396347Y447625D01*
X395972Y447500D01*
X395638D01*
X395305Y447625D01*
X395055Y447833D01*
X394930Y448125D01*
X395013Y448417D01*
X395222Y448667D01*
X395597Y448833D01*
X396097Y448917D01*
X396388Y449083D01*
X396513Y449375D01*
X396430Y449667D01*
X396222Y449875D01*
X395930Y450000D01*
X395638D01*
X395347Y449917D01*
X395097Y449708D01*
G01X391788Y449792D02*
X392038Y449917D01*
X392330Y450000D01*
X392663D01*
X393038Y449875D01*
X393330Y449667D01*
X393538Y449417D01*
X393705Y449000D01*
X393747Y448625D01*
X393663Y448250D01*
X393538Y448000D01*
X393288Y447750D01*
X392997Y447583D01*
X392705Y447500D01*
X392413D01*
X392122Y447583D01*
X391872Y447708D01*
X391663Y447875D01*
G01X389605Y447500D02*
Y450000D01*
X390105Y449500D01*
G01Y447500D02*
X389105D01*
G01X387297Y449583D02*
X387047Y449833D01*
X386755Y449958D01*
X386422Y450000D01*
X386005Y449917D01*
X385713Y449708D01*
X385630Y449458D01*
X385672Y449208D01*
X385838Y449000D01*
X386672Y448583D01*
X387047Y448292D01*
X387297Y447875D01*
X387380Y447500D01*
X385630D01*
G01X383405Y450000D02*
X383738Y449917D01*
X383988Y449708D01*
X384155Y449458D01*
X384280Y449125D01*
X384322Y448750D01*
X384280Y448375D01*
X384155Y448042D01*
X383988Y447792D01*
X383738Y447583D01*
X383405Y447500D01*
X383072Y447583D01*
X382822Y447792D01*
X382655Y448042D01*
X382530Y448375D01*
X382488Y448750D01*
X382530Y449125D01*
X382655Y449458D01*
X382822Y449708D01*
X383072Y449917D01*
X383405Y450000D01*
G01X381097Y449583D02*
X380847Y449833D01*
X380555Y449958D01*
X380222Y450000D01*
X379805Y449917D01*
X379513Y449708D01*
X379430Y449458D01*
X379472Y449208D01*
X379638Y449000D01*
X380472Y448583D01*
X380847Y448292D01*
X381097Y447875D01*
X381180Y447500D01*
X379430D01*
G01X385200Y903500D02*
Y899500D01*
X377800D01*
G01X385200Y908000D02*
Y904000D01*
X377800D01*
G01X367678Y975350D02*
X365178D01*
G01X367678Y974392D02*
Y976308D01*
G01X365178Y977617D02*
X367678D01*
Y978617D01*
X367553Y978950D01*
X367261Y979200D01*
X366928Y979283D01*
X366595Y979200D01*
X366345Y978992D01*
X366220Y978617D01*
Y977617D01*
G01X365178Y981467D02*
X365720Y981550D01*
X366178Y981675D01*
X366595Y981842D01*
X367053Y982050D01*
X367678Y982383D01*
Y980717D01*
G01X365178Y984650D02*
X365220Y984942D01*
X365345Y985275D01*
X365553Y985483D01*
X365845Y985567D01*
X366136Y985483D01*
X366386Y985233D01*
X366511Y984858D01*
Y984442D01*
X366595Y984192D01*
X366803Y983983D01*
X367095Y983900D01*
X367386Y984025D01*
X367595Y984317D01*
X367678Y984650D01*
X367595Y984983D01*
X367386Y985275D01*
X367095Y985400D01*
X366803Y985317D01*
X366595Y985108D01*
X366511Y984858D01*
Y984442D01*
X366386Y984067D01*
X366136Y983817D01*
X365845Y983733D01*
X365553Y983817D01*
X365345Y984025D01*
X365220Y984358D01*
X365178Y984650D01*
G01X385500Y9467D02*
X388000D01*
Y10467D01*
X387875Y10800D01*
X387583Y11050D01*
X387250Y11133D01*
X386917Y11050D01*
X386667Y10842D01*
X386542Y10467D01*
Y9467D01*
G01X387792Y14317D02*
X387917Y14067D01*
X388000Y13775D01*
Y13442D01*
X387875Y13067D01*
X387667Y12775D01*
X387417Y12567D01*
X387000Y12400D01*
X386625Y12358D01*
X386250Y12442D01*
X386000Y12567D01*
X385750Y12817D01*
X385583Y13108D01*
X385500Y13400D01*
Y13692D01*
X385583Y13983D01*
X385708Y14233D01*
X385875Y14442D01*
G01X385500Y16500D02*
X388000D01*
X387500Y16000D01*
G01X385500D02*
Y17000D01*
G01X385792Y18892D02*
X385583Y19183D01*
X385500Y19517D01*
X385583Y19850D01*
X385833Y20142D01*
X386208Y20350D01*
X386583Y20433D01*
X387042D01*
X387417Y20350D01*
X387750Y20142D01*
X387917Y19892D01*
X388000Y19600D01*
X387917Y19267D01*
X387750Y19017D01*
X387500Y18850D01*
X387167Y18767D01*
X386875Y18850D01*
X386583Y19058D01*
X386417Y19308D01*
X386375Y19600D01*
X386458Y19933D01*
X386667Y20183D01*
X387042Y20433D01*
G01X385500Y23200D02*
X388000D01*
X386208Y21658D01*
Y23742D01*
G01X390500Y9467D02*
X393000D01*
Y10467D01*
X392875Y10800D01*
X392583Y11050D01*
X392250Y11133D01*
X391917Y11050D01*
X391667Y10842D01*
X391542Y10467D01*
Y9467D01*
G01X392792Y14317D02*
X392917Y14067D01*
X393000Y13775D01*
Y13442D01*
X392875Y13067D01*
X392667Y12775D01*
X392417Y12567D01*
X392000Y12400D01*
X391625Y12358D01*
X391250Y12442D01*
X391000Y12567D01*
X390750Y12817D01*
X390583Y13108D01*
X390500Y13400D01*
Y13692D01*
X390583Y13983D01*
X390708Y14233D01*
X390875Y14442D01*
G01X390500Y16500D02*
X393000D01*
X392500Y16000D01*
G01X390500D02*
Y17000D01*
G01X390792Y18892D02*
X390583Y19183D01*
X390500Y19517D01*
X390583Y19850D01*
X390833Y20142D01*
X391208Y20350D01*
X391583Y20433D01*
X392042D01*
X392417Y20350D01*
X392750Y20142D01*
X392917Y19892D01*
X393000Y19600D01*
X392917Y19267D01*
X392750Y19017D01*
X392500Y18850D01*
X392167Y18767D01*
X391875Y18850D01*
X391583Y19058D01*
X391417Y19308D01*
X391375Y19600D01*
X391458Y19933D01*
X391667Y20183D01*
X392042Y20433D01*
G01X390875Y21783D02*
X390667Y22033D01*
X390542Y22325D01*
X390500Y22700D01*
X390583Y23075D01*
X390750Y23367D01*
X391042Y23575D01*
X391375Y23617D01*
X391708Y23533D01*
X391917Y23325D01*
X392083Y23033D01*
X392125Y22742D01*
X392083Y22450D01*
X391917Y22075D01*
X393000Y22200D01*
Y23325D01*
G01X394333Y39425D02*
X394125Y39758D01*
X394000Y40133D01*
Y40467D01*
X394125Y40800D01*
X394333Y41050D01*
X394625Y41175D01*
X394917Y41092D01*
X395167Y40883D01*
X395333Y40508D01*
X395417Y40008D01*
X395583Y39717D01*
X395875Y39592D01*
X396167Y39675D01*
X396375Y39883D01*
X396500Y40175D01*
Y40467D01*
X396417Y40758D01*
X396208Y41008D01*
G01X396292Y44317D02*
X396417Y44067D01*
X396500Y43775D01*
Y43442D01*
X396375Y43067D01*
X396167Y42775D01*
X395917Y42567D01*
X395500Y42400D01*
X395125Y42358D01*
X394750Y42442D01*
X394500Y42567D01*
X394250Y42817D01*
X394083Y43108D01*
X394000Y43400D01*
Y43692D01*
X394083Y43983D01*
X394208Y44233D01*
X394375Y44442D01*
G01X394292Y45792D02*
X394083Y46083D01*
X394000Y46417D01*
X394083Y46750D01*
X394333Y47042D01*
X394708Y47250D01*
X395083Y47333D01*
X395542D01*
X395917Y47250D01*
X396250Y47042D01*
X396417Y46792D01*
X396500Y46500D01*
X396417Y46167D01*
X396250Y45917D01*
X396000Y45750D01*
X395667Y45667D01*
X395375Y45750D01*
X395083Y45958D01*
X394917Y46208D01*
X394875Y46500D01*
X394958Y46833D01*
X395167Y47083D01*
X395542Y47333D01*
G01X394292Y48892D02*
X394083Y49183D01*
X394000Y49517D01*
X394083Y49850D01*
X394333Y50142D01*
X394708Y50350D01*
X395083Y50433D01*
X395542D01*
X395917Y50350D01*
X396250Y50142D01*
X396417Y49892D01*
X396500Y49600D01*
X396417Y49267D01*
X396250Y49017D01*
X396000Y48850D01*
X395667Y48767D01*
X395375Y48850D01*
X395083Y49058D01*
X394917Y49308D01*
X394875Y49600D01*
X394958Y49933D01*
X395167Y50183D01*
X395542Y50433D01*
G01X395042Y51908D02*
X395333Y52200D01*
X395500Y52450D01*
X395583Y52783D01*
X395500Y53075D01*
X395333Y53283D01*
X395083Y53450D01*
X394792Y53492D01*
X394542Y53450D01*
X394292Y53283D01*
X394083Y53033D01*
X394000Y52742D01*
X394083Y52408D01*
X394333Y52117D01*
X394708Y51950D01*
X395125Y51908D01*
X395667Y51992D01*
X395958Y52117D01*
X396250Y52325D01*
X396458Y52617D01*
X396500Y52908D01*
X396417Y53200D01*
X396208Y53408D01*
G01X389333Y39425D02*
X389125Y39758D01*
X389000Y40133D01*
Y40467D01*
X389125Y40800D01*
X389333Y41050D01*
X389625Y41175D01*
X389917Y41092D01*
X390167Y40883D01*
X390333Y40508D01*
X390417Y40008D01*
X390583Y39717D01*
X390875Y39592D01*
X391167Y39675D01*
X391375Y39883D01*
X391500Y40175D01*
Y40467D01*
X391417Y40758D01*
X391208Y41008D01*
G01X391292Y44317D02*
X391417Y44067D01*
X391500Y43775D01*
Y43442D01*
X391375Y43067D01*
X391167Y42775D01*
X390917Y42567D01*
X390500Y42400D01*
X390125Y42358D01*
X389750Y42442D01*
X389500Y42567D01*
X389250Y42817D01*
X389083Y43108D01*
X389000Y43400D01*
Y43692D01*
X389083Y43983D01*
X389208Y44233D01*
X389375Y44442D01*
G01X389292Y45792D02*
X389083Y46083D01*
X389000Y46417D01*
X389083Y46750D01*
X389333Y47042D01*
X389708Y47250D01*
X390083Y47333D01*
X390542D01*
X390917Y47250D01*
X391250Y47042D01*
X391417Y46792D01*
X391500Y46500D01*
X391417Y46167D01*
X391250Y45917D01*
X391000Y45750D01*
X390667Y45667D01*
X390375Y45750D01*
X390083Y45958D01*
X389917Y46208D01*
X389875Y46500D01*
X389958Y46833D01*
X390167Y47083D01*
X390542Y47333D01*
G01X389292Y48892D02*
X389083Y49183D01*
X389000Y49517D01*
X389083Y49850D01*
X389333Y50142D01*
X389708Y50350D01*
X390083Y50433D01*
X390542D01*
X390917Y50350D01*
X391250Y50142D01*
X391417Y49892D01*
X391500Y49600D01*
X391417Y49267D01*
X391250Y49017D01*
X391000Y48850D01*
X390667Y48767D01*
X390375Y48850D01*
X390083Y49058D01*
X389917Y49308D01*
X389875Y49600D01*
X389958Y49933D01*
X390167Y50183D01*
X390542Y50433D01*
G01X389000Y52617D02*
X389542Y52700D01*
X390000Y52825D01*
X390417Y52992D01*
X390875Y53200D01*
X391500Y53533D01*
Y51867D01*
G01X384333Y39925D02*
X384125Y40258D01*
X384000Y40633D01*
Y40967D01*
X384125Y41300D01*
X384333Y41550D01*
X384625Y41675D01*
X384917Y41592D01*
X385167Y41383D01*
X385333Y41008D01*
X385417Y40508D01*
X385583Y40217D01*
X385875Y40092D01*
X386167Y40175D01*
X386375Y40383D01*
X386500Y40675D01*
Y40967D01*
X386417Y41258D01*
X386208Y41508D01*
G01X386292Y44817D02*
X386417Y44567D01*
X386500Y44275D01*
Y43942D01*
X386375Y43567D01*
X386167Y43275D01*
X385917Y43067D01*
X385500Y42900D01*
X385125Y42858D01*
X384750Y42942D01*
X384500Y43067D01*
X384250Y43317D01*
X384083Y43608D01*
X384000Y43900D01*
Y44192D01*
X384083Y44483D01*
X384208Y44733D01*
X384375Y44942D01*
G01X384292Y46292D02*
X384083Y46583D01*
X384000Y46917D01*
X384083Y47250D01*
X384333Y47542D01*
X384708Y47750D01*
X385083Y47833D01*
X385542D01*
X385917Y47750D01*
X386250Y47542D01*
X386417Y47292D01*
X386500Y47000D01*
X386417Y46667D01*
X386250Y46417D01*
X386000Y46250D01*
X385667Y46167D01*
X385375Y46250D01*
X385083Y46458D01*
X384917Y46708D01*
X384875Y47000D01*
X384958Y47333D01*
X385167Y47583D01*
X385542Y47833D01*
G01X384292Y49392D02*
X384083Y49683D01*
X384000Y50017D01*
X384083Y50350D01*
X384333Y50642D01*
X384708Y50850D01*
X385083Y50933D01*
X385542D01*
X385917Y50850D01*
X386250Y50642D01*
X386417Y50392D01*
X386500Y50100D01*
X386417Y49767D01*
X386250Y49517D01*
X386000Y49350D01*
X385667Y49267D01*
X385375Y49350D01*
X385083Y49558D01*
X384917Y49808D01*
X384875Y50100D01*
X384958Y50433D01*
X385167Y50683D01*
X385542Y50933D01*
G01X384000Y53200D02*
X384042Y53492D01*
X384167Y53825D01*
X384375Y54033D01*
X384667Y54117D01*
X384958Y54033D01*
X385208Y53783D01*
X385333Y53408D01*
Y52992D01*
X385417Y52742D01*
X385625Y52533D01*
X385917Y52450D01*
X386208Y52575D01*
X386417Y52867D01*
X386500Y53200D01*
X386417Y53533D01*
X386208Y53825D01*
X385917Y53950D01*
X385625Y53867D01*
X385417Y53658D01*
X385333Y53408D01*
Y52992D01*
X385208Y52617D01*
X384958Y52367D01*
X384667Y52283D01*
X384375Y52367D01*
X384167Y52575D01*
X384042Y52908D01*
X384000Y53200D01*
G01X389562Y56425D02*
X389354Y56758D01*
X389229Y57133D01*
Y57467D01*
X389354Y57800D01*
X389562Y58050D01*
X389854Y58175D01*
X390146Y58092D01*
X390396Y57883D01*
X390562Y57508D01*
X390646Y57008D01*
X390812Y56717D01*
X391104Y56592D01*
X391396Y56675D01*
X391604Y56883D01*
X391729Y57175D01*
Y57467D01*
X391646Y57758D01*
X391437Y58008D01*
G01X391729Y60400D02*
X389229D01*
G01X391729Y59442D02*
Y61358D01*
G01X389229Y62667D02*
X391729D01*
Y63667D01*
X391604Y64000D01*
X391312Y64250D01*
X390979Y64333D01*
X390646Y64250D01*
X390396Y64042D01*
X390271Y63667D01*
Y62667D01*
G01X389604Y65683D02*
X389396Y65933D01*
X389271Y66225D01*
X389229Y66600D01*
X389312Y66975D01*
X389479Y67267D01*
X389771Y67475D01*
X390104Y67517D01*
X390437Y67433D01*
X390646Y67225D01*
X390812Y66933D01*
X390854Y66642D01*
X390812Y66350D01*
X390646Y65975D01*
X391729Y66100D01*
Y67225D01*
G01X389729Y68783D02*
X389437Y69033D01*
X389271Y69367D01*
X389229Y69742D01*
X389271Y70075D01*
X389479Y70408D01*
X389729Y70617D01*
X389979Y70658D01*
X390271Y70575D01*
X390479Y70283D01*
X390562Y69992D01*
Y69617D01*
G01Y69992D02*
X390687Y70242D01*
X390896Y70450D01*
X391146Y70533D01*
X391396Y70450D01*
X391604Y70242D01*
X391729Y69867D01*
X391687Y69492D01*
X391521Y69117D01*
G01X384651Y56425D02*
X384443Y56758D01*
X384318Y57133D01*
Y57467D01*
X384443Y57800D01*
X384651Y58050D01*
X384943Y58175D01*
X385235Y58092D01*
X385485Y57883D01*
X385651Y57508D01*
X385735Y57008D01*
X385901Y56717D01*
X386193Y56592D01*
X386485Y56675D01*
X386693Y56883D01*
X386818Y57175D01*
Y57467D01*
X386735Y57758D01*
X386526Y58008D01*
G01X386818Y60400D02*
X384318D01*
G01X386818Y59442D02*
Y61358D01*
G01X384318Y62667D02*
X386818D01*
Y63667D01*
X386693Y64000D01*
X386401Y64250D01*
X386068Y64333D01*
X385735Y64250D01*
X385485Y64042D01*
X385360Y63667D01*
Y62667D01*
G01X384693Y65683D02*
X384485Y65933D01*
X384360Y66225D01*
X384318Y66600D01*
X384401Y66975D01*
X384568Y67267D01*
X384860Y67475D01*
X385193Y67517D01*
X385526Y67433D01*
X385735Y67225D01*
X385901Y66933D01*
X385943Y66642D01*
X385901Y66350D01*
X385735Y65975D01*
X386818Y66100D01*
Y67225D01*
G01X384693Y68783D02*
X384485Y69033D01*
X384360Y69325D01*
X384318Y69700D01*
X384401Y70075D01*
X384568Y70367D01*
X384860Y70575D01*
X385193Y70617D01*
X385526Y70533D01*
X385735Y70325D01*
X385901Y70033D01*
X385943Y69742D01*
X385901Y69450D01*
X385735Y69075D01*
X386818Y69200D01*
Y70325D01*
G01X402075Y73833D02*
X401742Y73625D01*
X401367Y73500D01*
X401033D01*
X400700Y73625D01*
X400450Y73833D01*
X400325Y74125D01*
X400408Y74417D01*
X400617Y74667D01*
X400992Y74833D01*
X401492Y74917D01*
X401783Y75083D01*
X401908Y75375D01*
X401825Y75667D01*
X401617Y75875D01*
X401325Y76000D01*
X401033D01*
X400742Y75917D01*
X400492Y75708D01*
G01X398100Y76000D02*
Y73500D01*
G01X399058Y76000D02*
X397142D01*
G01X395833Y73500D02*
Y76000D01*
X394833D01*
X394500Y75875D01*
X394250Y75583D01*
X394167Y75250D01*
X394250Y74917D01*
X394458Y74667D01*
X394833Y74542D01*
X395833D01*
G01X391983Y73500D02*
X391900Y74042D01*
X391775Y74500D01*
X391608Y74917D01*
X391400Y75375D01*
X391067Y76000D01*
X392733D01*
G01X389592Y74542D02*
X389300Y74833D01*
X389050Y75000D01*
X388717Y75083D01*
X388425Y75000D01*
X388217Y74833D01*
X388050Y74583D01*
X388008Y74292D01*
X388050Y74042D01*
X388217Y73792D01*
X388467Y73583D01*
X388758Y73500D01*
X389092Y73583D01*
X389383Y73833D01*
X389550Y74208D01*
X389592Y74625D01*
X389508Y75167D01*
X389383Y75458D01*
X389175Y75750D01*
X388883Y75958D01*
X388592Y76000D01*
X388300Y75917D01*
X388092Y75708D01*
G01X388262Y78875D02*
X388054Y79208D01*
X387929Y79583D01*
Y79917D01*
X388054Y80250D01*
X388262Y80500D01*
X388554Y80625D01*
X388846Y80542D01*
X389096Y80333D01*
X389262Y79958D01*
X389346Y79458D01*
X389512Y79167D01*
X389804Y79042D01*
X390096Y79125D01*
X390304Y79333D01*
X390429Y79625D01*
Y79917D01*
X390346Y80208D01*
X390137Y80458D01*
G01X390221Y83767D02*
X390346Y83517D01*
X390429Y83225D01*
Y82892D01*
X390304Y82517D01*
X390096Y82225D01*
X389846Y82017D01*
X389429Y81850D01*
X389054Y81808D01*
X388679Y81892D01*
X388429Y82017D01*
X388179Y82267D01*
X388012Y82558D01*
X387929Y82850D01*
Y83142D01*
X388012Y83433D01*
X388137Y83683D01*
X388304Y83892D01*
G01X387929Y85950D02*
X390429D01*
X389929Y85450D01*
G01X387929D02*
Y86450D01*
G01X390429Y89050D02*
X390346Y88717D01*
X390137Y88467D01*
X389887Y88300D01*
X389554Y88175D01*
X389179Y88133D01*
X388804Y88175D01*
X388471Y88300D01*
X388221Y88467D01*
X388012Y88717D01*
X387929Y89050D01*
X388012Y89383D01*
X388221Y89633D01*
X388471Y89800D01*
X388804Y89925D01*
X389179Y89967D01*
X389554Y89925D01*
X389887Y89800D01*
X390137Y89633D01*
X390346Y89383D01*
X390429Y89050D01*
G01X388304Y91233D02*
X388096Y91483D01*
X387971Y91775D01*
X387929Y92150D01*
X388012Y92525D01*
X388179Y92817D01*
X388471Y93025D01*
X388804Y93067D01*
X389137Y92983D01*
X389346Y92775D01*
X389512Y92483D01*
X389554Y92192D01*
X389512Y91900D01*
X389346Y91525D01*
X390429Y91650D01*
Y92775D01*
G01X388971Y94458D02*
X389262Y94750D01*
X389429Y95000D01*
X389512Y95333D01*
X389429Y95625D01*
X389262Y95833D01*
X389012Y96000D01*
X388721Y96042D01*
X388471Y96000D01*
X388221Y95833D01*
X388012Y95583D01*
X387929Y95292D01*
X388012Y94958D01*
X388262Y94667D01*
X388637Y94500D01*
X389054Y94458D01*
X389596Y94542D01*
X389887Y94667D01*
X390179Y94875D01*
X390387Y95167D01*
X390429Y95458D01*
X390346Y95750D01*
X390137Y95958D01*
G01X383762Y78875D02*
X383554Y79208D01*
X383429Y79583D01*
Y79917D01*
X383554Y80250D01*
X383762Y80500D01*
X384054Y80625D01*
X384346Y80542D01*
X384596Y80333D01*
X384762Y79958D01*
X384846Y79458D01*
X385012Y79167D01*
X385304Y79042D01*
X385596Y79125D01*
X385804Y79333D01*
X385929Y79625D01*
Y79917D01*
X385846Y80208D01*
X385637Y80458D01*
G01X385721Y83767D02*
X385846Y83517D01*
X385929Y83225D01*
Y82892D01*
X385804Y82517D01*
X385596Y82225D01*
X385346Y82017D01*
X384929Y81850D01*
X384554Y81808D01*
X384179Y81892D01*
X383929Y82017D01*
X383679Y82267D01*
X383512Y82558D01*
X383429Y82850D01*
Y83142D01*
X383512Y83433D01*
X383637Y83683D01*
X383804Y83892D01*
G01X383429Y85950D02*
X385929D01*
X385429Y85450D01*
G01X383429D02*
Y86450D01*
G01X385929Y89050D02*
X385846Y88717D01*
X385637Y88467D01*
X385387Y88300D01*
X385054Y88175D01*
X384679Y88133D01*
X384304Y88175D01*
X383971Y88300D01*
X383721Y88467D01*
X383512Y88717D01*
X383429Y89050D01*
X383512Y89383D01*
X383721Y89633D01*
X383971Y89800D01*
X384304Y89925D01*
X384679Y89967D01*
X385054Y89925D01*
X385387Y89800D01*
X385637Y89633D01*
X385846Y89383D01*
X385929Y89050D01*
G01X384471Y91358D02*
X384762Y91650D01*
X384929Y91900D01*
X385012Y92233D01*
X384929Y92525D01*
X384762Y92733D01*
X384512Y92900D01*
X384221Y92942D01*
X383971Y92900D01*
X383721Y92733D01*
X383512Y92483D01*
X383429Y92192D01*
X383512Y91858D01*
X383762Y91567D01*
X384137Y91400D01*
X384554Y91358D01*
X385096Y91442D01*
X385387Y91567D01*
X385679Y91775D01*
X385887Y92067D01*
X385929Y92358D01*
X385846Y92650D01*
X385637Y92858D01*
G01X385512Y94458D02*
X385762Y94708D01*
X385887Y95000D01*
X385929Y95333D01*
X385846Y95750D01*
X385637Y96042D01*
X385387Y96125D01*
X385137Y96083D01*
X384929Y95917D01*
X384512Y95083D01*
X384221Y94708D01*
X383804Y94458D01*
X383429Y94375D01*
Y96125D01*
G01X396762Y78875D02*
X396554Y79208D01*
X396429Y79583D01*
Y79917D01*
X396554Y80250D01*
X396762Y80500D01*
X397054Y80625D01*
X397346Y80542D01*
X397596Y80333D01*
X397762Y79958D01*
X397846Y79458D01*
X398012Y79167D01*
X398304Y79042D01*
X398596Y79125D01*
X398804Y79333D01*
X398929Y79625D01*
Y79917D01*
X398846Y80208D01*
X398637Y80458D01*
G01X398721Y83767D02*
X398846Y83517D01*
X398929Y83225D01*
Y82892D01*
X398804Y82517D01*
X398596Y82225D01*
X398346Y82017D01*
X397929Y81850D01*
X397554Y81808D01*
X397179Y81892D01*
X396929Y82017D01*
X396679Y82267D01*
X396512Y82558D01*
X396429Y82850D01*
Y83142D01*
X396512Y83433D01*
X396637Y83683D01*
X396804Y83892D01*
G01X396429Y85950D02*
X398929D01*
X398429Y85450D01*
G01X396429D02*
Y86450D01*
G01X398929Y89050D02*
X398846Y88717D01*
X398637Y88467D01*
X398387Y88300D01*
X398054Y88175D01*
X397679Y88133D01*
X397304Y88175D01*
X396971Y88300D01*
X396721Y88467D01*
X396512Y88717D01*
X396429Y89050D01*
X396512Y89383D01*
X396721Y89633D01*
X396971Y89800D01*
X397304Y89925D01*
X397679Y89967D01*
X398054Y89925D01*
X398387Y89800D01*
X398637Y89633D01*
X398846Y89383D01*
X398929Y89050D01*
G01X396429Y92650D02*
X398929D01*
X397137Y91108D01*
Y93192D01*
G01X396429Y95250D02*
X398929D01*
X398429Y94750D01*
G01X396429D02*
Y95750D01*
G01X392262Y78875D02*
X392054Y79208D01*
X391929Y79583D01*
Y79917D01*
X392054Y80250D01*
X392262Y80500D01*
X392554Y80625D01*
X392846Y80542D01*
X393096Y80333D01*
X393262Y79958D01*
X393346Y79458D01*
X393512Y79167D01*
X393804Y79042D01*
X394096Y79125D01*
X394304Y79333D01*
X394429Y79625D01*
Y79917D01*
X394346Y80208D01*
X394137Y80458D01*
G01X394221Y83767D02*
X394346Y83517D01*
X394429Y83225D01*
Y82892D01*
X394304Y82517D01*
X394096Y82225D01*
X393846Y82017D01*
X393429Y81850D01*
X393054Y81808D01*
X392679Y81892D01*
X392429Y82017D01*
X392179Y82267D01*
X392012Y82558D01*
X391929Y82850D01*
Y83142D01*
X392012Y83433D01*
X392137Y83683D01*
X392304Y83892D01*
G01X391929Y85950D02*
X394429D01*
X393929Y85450D01*
G01X391929D02*
Y86450D01*
G01X394429Y89050D02*
X394346Y88717D01*
X394137Y88467D01*
X393887Y88300D01*
X393554Y88175D01*
X393179Y88133D01*
X392804Y88175D01*
X392471Y88300D01*
X392221Y88467D01*
X392012Y88717D01*
X391929Y89050D01*
X392012Y89383D01*
X392221Y89633D01*
X392471Y89800D01*
X392804Y89925D01*
X393179Y89967D01*
X393554Y89925D01*
X393887Y89800D01*
X394137Y89633D01*
X394346Y89383D01*
X394429Y89050D01*
G01X391929Y92650D02*
X394429D01*
X392637Y91108D01*
Y93192D01*
G01X394012Y94458D02*
X394262Y94708D01*
X394387Y95000D01*
X394429Y95333D01*
X394346Y95750D01*
X394137Y96042D01*
X393887Y96125D01*
X393637Y96083D01*
X393429Y95917D01*
X393012Y95083D01*
X392721Y94708D01*
X392304Y94458D01*
X391929Y94375D01*
Y96125D01*
G01X382373Y104925D02*
X382165Y105258D01*
X382040Y105633D01*
Y105967D01*
X382165Y106300D01*
X382373Y106550D01*
X382665Y106675D01*
X382957Y106592D01*
X383207Y106383D01*
X383373Y106008D01*
X383457Y105508D01*
X383623Y105217D01*
X383915Y105092D01*
X384207Y105175D01*
X384415Y105383D01*
X384540Y105675D01*
Y105967D01*
X384457Y106258D01*
X384248Y106508D01*
G01X384332Y109817D02*
X384457Y109567D01*
X384540Y109275D01*
Y108942D01*
X384415Y108567D01*
X384207Y108275D01*
X383957Y108067D01*
X383540Y107900D01*
X383165Y107858D01*
X382790Y107942D01*
X382540Y108067D01*
X382290Y108317D01*
X382123Y108608D01*
X382040Y108900D01*
Y109192D01*
X382123Y109483D01*
X382248Y109733D01*
X382415Y109942D01*
G01X382040Y112000D02*
X382082Y112292D01*
X382207Y112625D01*
X382415Y112833D01*
X382707Y112917D01*
X382998Y112833D01*
X383248Y112583D01*
X383373Y112208D01*
Y111792D01*
X383457Y111542D01*
X383665Y111333D01*
X383957Y111250D01*
X384248Y111375D01*
X384457Y111667D01*
X384540Y112000D01*
X384457Y112333D01*
X384248Y112625D01*
X383957Y112750D01*
X383665Y112667D01*
X383457Y112458D01*
X383373Y112208D01*
Y111792D01*
X383248Y111417D01*
X382998Y111167D01*
X382707Y111083D01*
X382415Y111167D01*
X382207Y111375D01*
X382082Y111708D01*
X382040Y112000D01*
G01X383082Y114308D02*
X383373Y114600D01*
X383540Y114850D01*
X383623Y115183D01*
X383540Y115475D01*
X383373Y115683D01*
X383123Y115850D01*
X382832Y115892D01*
X382582Y115850D01*
X382332Y115683D01*
X382123Y115433D01*
X382040Y115142D01*
X382123Y114808D01*
X382373Y114517D01*
X382748Y114350D01*
X383165Y114308D01*
X383707Y114392D01*
X383998Y114517D01*
X384290Y114725D01*
X384498Y115017D01*
X384540Y115308D01*
X384457Y115600D01*
X384248Y115808D01*
G01X382040Y118200D02*
X382082Y118492D01*
X382207Y118825D01*
X382415Y119033D01*
X382707Y119117D01*
X382998Y119033D01*
X383248Y118783D01*
X383373Y118408D01*
Y117992D01*
X383457Y117742D01*
X383665Y117533D01*
X383957Y117450D01*
X384248Y117575D01*
X384457Y117867D01*
X384540Y118200D01*
X384457Y118533D01*
X384248Y118825D01*
X383957Y118950D01*
X383665Y118867D01*
X383457Y118658D01*
X383373Y118408D01*
Y117992D01*
X383248Y117617D01*
X382998Y117367D01*
X382707Y117283D01*
X382415Y117367D01*
X382207Y117575D01*
X382082Y117908D01*
X382040Y118200D01*
G01X386373Y104925D02*
X386165Y105258D01*
X386040Y105633D01*
Y105967D01*
X386165Y106300D01*
X386373Y106550D01*
X386665Y106675D01*
X386957Y106592D01*
X387207Y106383D01*
X387373Y106008D01*
X387457Y105508D01*
X387623Y105217D01*
X387915Y105092D01*
X388207Y105175D01*
X388415Y105383D01*
X388540Y105675D01*
Y105967D01*
X388457Y106258D01*
X388248Y106508D01*
G01X388332Y109817D02*
X388457Y109567D01*
X388540Y109275D01*
Y108942D01*
X388415Y108567D01*
X388207Y108275D01*
X387957Y108067D01*
X387540Y107900D01*
X387165Y107858D01*
X386790Y107942D01*
X386540Y108067D01*
X386290Y108317D01*
X386123Y108608D01*
X386040Y108900D01*
Y109192D01*
X386123Y109483D01*
X386248Y109733D01*
X386415Y109942D01*
G01X386040Y112000D02*
X386082Y112292D01*
X386207Y112625D01*
X386415Y112833D01*
X386707Y112917D01*
X386998Y112833D01*
X387248Y112583D01*
X387373Y112208D01*
Y111792D01*
X387457Y111542D01*
X387665Y111333D01*
X387957Y111250D01*
X388248Y111375D01*
X388457Y111667D01*
X388540Y112000D01*
X388457Y112333D01*
X388248Y112625D01*
X387957Y112750D01*
X387665Y112667D01*
X387457Y112458D01*
X387373Y112208D01*
Y111792D01*
X387248Y111417D01*
X386998Y111167D01*
X386707Y111083D01*
X386415Y111167D01*
X386207Y111375D01*
X386082Y111708D01*
X386040Y112000D01*
G01X387082Y114308D02*
X387373Y114600D01*
X387540Y114850D01*
X387623Y115183D01*
X387540Y115475D01*
X387373Y115683D01*
X387123Y115850D01*
X386832Y115892D01*
X386582Y115850D01*
X386332Y115683D01*
X386123Y115433D01*
X386040Y115142D01*
X386123Y114808D01*
X386373Y114517D01*
X386748Y114350D01*
X387165Y114308D01*
X387707Y114392D01*
X387998Y114517D01*
X388290Y114725D01*
X388498Y115017D01*
X388540Y115308D01*
X388457Y115600D01*
X388248Y115808D01*
G01X386332Y117492D02*
X386123Y117783D01*
X386040Y118117D01*
X386123Y118450D01*
X386373Y118742D01*
X386748Y118950D01*
X387123Y119033D01*
X387582D01*
X387957Y118950D01*
X388290Y118742D01*
X388457Y118492D01*
X388540Y118200D01*
X388457Y117867D01*
X388290Y117617D01*
X388040Y117450D01*
X387707Y117367D01*
X387415Y117450D01*
X387123Y117658D01*
X386957Y117908D01*
X386915Y118200D01*
X386998Y118533D01*
X387207Y118783D01*
X387582Y119033D01*
G01X390373Y104925D02*
X390165Y105258D01*
X390040Y105633D01*
Y105967D01*
X390165Y106300D01*
X390373Y106550D01*
X390665Y106675D01*
X390957Y106592D01*
X391207Y106383D01*
X391373Y106008D01*
X391457Y105508D01*
X391623Y105217D01*
X391915Y105092D01*
X392207Y105175D01*
X392415Y105383D01*
X392540Y105675D01*
Y105967D01*
X392457Y106258D01*
X392248Y106508D01*
G01X392332Y109817D02*
X392457Y109567D01*
X392540Y109275D01*
Y108942D01*
X392415Y108567D01*
X392207Y108275D01*
X391957Y108067D01*
X391540Y107900D01*
X391165Y107858D01*
X390790Y107942D01*
X390540Y108067D01*
X390290Y108317D01*
X390123Y108608D01*
X390040Y108900D01*
Y109192D01*
X390123Y109483D01*
X390248Y109733D01*
X390415Y109942D01*
G01X390040Y112000D02*
X390082Y112292D01*
X390207Y112625D01*
X390415Y112833D01*
X390707Y112917D01*
X390998Y112833D01*
X391248Y112583D01*
X391373Y112208D01*
Y111792D01*
X391457Y111542D01*
X391665Y111333D01*
X391957Y111250D01*
X392248Y111375D01*
X392457Y111667D01*
X392540Y112000D01*
X392457Y112333D01*
X392248Y112625D01*
X391957Y112750D01*
X391665Y112667D01*
X391457Y112458D01*
X391373Y112208D01*
Y111792D01*
X391248Y111417D01*
X390998Y111167D01*
X390707Y111083D01*
X390415Y111167D01*
X390207Y111375D01*
X390082Y111708D01*
X390040Y112000D01*
G01Y115017D02*
X390582Y115100D01*
X391040Y115225D01*
X391457Y115392D01*
X391915Y115600D01*
X392540Y115933D01*
Y114267D01*
G01Y118200D02*
X392457Y117867D01*
X392248Y117617D01*
X391998Y117450D01*
X391665Y117325D01*
X391290Y117283D01*
X390915Y117325D01*
X390582Y117450D01*
X390332Y117617D01*
X390123Y117867D01*
X390040Y118200D01*
X390123Y118533D01*
X390332Y118783D01*
X390582Y118950D01*
X390915Y119075D01*
X391290Y119117D01*
X391665Y119075D01*
X391998Y118950D01*
X392248Y118783D01*
X392457Y118533D01*
X392540Y118200D01*
G01X394373Y104992D02*
X394165Y105325D01*
X394040Y105700D01*
Y106034D01*
X394165Y106367D01*
X394373Y106617D01*
X394665Y106742D01*
X394957Y106659D01*
X395207Y106450D01*
X395373Y106075D01*
X395457Y105575D01*
X395623Y105284D01*
X395915Y105159D01*
X396207Y105242D01*
X396415Y105450D01*
X396540Y105742D01*
Y106034D01*
X396457Y106325D01*
X396248Y106575D01*
G01X396332Y109884D02*
X396457Y109634D01*
X396540Y109342D01*
Y109009D01*
X396415Y108634D01*
X396207Y108342D01*
X395957Y108134D01*
X395540Y107967D01*
X395165Y107925D01*
X394790Y108009D01*
X394540Y108134D01*
X394290Y108384D01*
X394123Y108675D01*
X394040Y108967D01*
Y109259D01*
X394123Y109550D01*
X394248Y109800D01*
X394415Y110009D01*
G01X394040Y112067D02*
X394082Y112359D01*
X394207Y112692D01*
X394415Y112900D01*
X394707Y112984D01*
X394998Y112900D01*
X395248Y112650D01*
X395373Y112275D01*
Y111859D01*
X395457Y111609D01*
X395665Y111400D01*
X395957Y111317D01*
X396248Y111442D01*
X396457Y111734D01*
X396540Y112067D01*
X396457Y112400D01*
X396248Y112692D01*
X395957Y112817D01*
X395665Y112734D01*
X395457Y112525D01*
X395373Y112275D01*
Y111859D01*
X395248Y111484D01*
X394998Y111234D01*
X394707Y111150D01*
X394415Y111234D01*
X394207Y111442D01*
X394082Y111775D01*
X394040Y112067D01*
G01Y115084D02*
X394582Y115167D01*
X395040Y115292D01*
X395457Y115459D01*
X395915Y115667D01*
X396540Y116000D01*
Y114334D01*
G01X394040Y118267D02*
X396540D01*
X396040Y117767D01*
G01X394040D02*
Y118767D01*
G01X391833Y131425D02*
X391625Y131758D01*
X391500Y132133D01*
Y132467D01*
X391625Y132800D01*
X391833Y133050D01*
X392125Y133175D01*
X392417Y133092D01*
X392667Y132883D01*
X392833Y132508D01*
X392917Y132008D01*
X393083Y131717D01*
X393375Y131592D01*
X393667Y131675D01*
X393875Y131883D01*
X394000Y132175D01*
Y132467D01*
X393917Y132758D01*
X393708Y133008D01*
G01X393792Y136317D02*
X393917Y136067D01*
X394000Y135775D01*
Y135442D01*
X393875Y135067D01*
X393667Y134775D01*
X393417Y134567D01*
X393000Y134400D01*
X392625Y134358D01*
X392250Y134442D01*
X392000Y134567D01*
X391750Y134817D01*
X391583Y135108D01*
X391500Y135400D01*
Y135692D01*
X391583Y135983D01*
X391708Y136233D01*
X391875Y136442D01*
G01X391792Y137792D02*
X391583Y138083D01*
X391500Y138417D01*
X391583Y138750D01*
X391833Y139042D01*
X392208Y139250D01*
X392583Y139333D01*
X393042D01*
X393417Y139250D01*
X393750Y139042D01*
X393917Y138792D01*
X394000Y138500D01*
X393917Y138167D01*
X393750Y137917D01*
X393500Y137750D01*
X393167Y137667D01*
X392875Y137750D01*
X392583Y137958D01*
X392417Y138208D01*
X392375Y138500D01*
X392458Y138833D01*
X392667Y139083D01*
X393042Y139333D01*
G01X391500Y142100D02*
X394000D01*
X392208Y140558D01*
Y142642D01*
G01X391500Y144700D02*
X394000D01*
X393500Y144200D01*
G01X391500D02*
Y145200D01*
G01X383833Y132925D02*
X383625Y133258D01*
X383500Y133633D01*
Y133967D01*
X383625Y134300D01*
X383833Y134550D01*
X384125Y134675D01*
X384417Y134592D01*
X384667Y134383D01*
X384833Y134008D01*
X384917Y133508D01*
X385083Y133217D01*
X385375Y133092D01*
X385667Y133175D01*
X385875Y133383D01*
X386000Y133675D01*
Y133967D01*
X385917Y134258D01*
X385708Y134508D01*
G01X385792Y137817D02*
X385917Y137567D01*
X386000Y137275D01*
Y136942D01*
X385875Y136567D01*
X385667Y136275D01*
X385417Y136067D01*
X385000Y135900D01*
X384625Y135858D01*
X384250Y135942D01*
X384000Y136067D01*
X383750Y136317D01*
X383583Y136608D01*
X383500Y136900D01*
Y137192D01*
X383583Y137483D01*
X383708Y137733D01*
X383875Y137942D01*
G01X383792Y139292D02*
X383583Y139583D01*
X383500Y139917D01*
X383583Y140250D01*
X383833Y140542D01*
X384208Y140750D01*
X384583Y140833D01*
X385042D01*
X385417Y140750D01*
X385750Y140542D01*
X385917Y140292D01*
X386000Y140000D01*
X385917Y139667D01*
X385750Y139417D01*
X385500Y139250D01*
X385167Y139167D01*
X384875Y139250D01*
X384583Y139458D01*
X384417Y139708D01*
X384375Y140000D01*
X384458Y140333D01*
X384667Y140583D01*
X385042Y140833D01*
G01X383500Y143600D02*
X386000D01*
X384208Y142058D01*
Y144142D01*
G01X383792Y145492D02*
X383583Y145783D01*
X383500Y146117D01*
X383583Y146450D01*
X383833Y146742D01*
X384208Y146950D01*
X384583Y147033D01*
X385042D01*
X385417Y146950D01*
X385750Y146742D01*
X385917Y146492D01*
X386000Y146200D01*
X385917Y145867D01*
X385750Y145617D01*
X385500Y145450D01*
X385167Y145367D01*
X384875Y145450D01*
X384583Y145658D01*
X384417Y145908D01*
X384375Y146200D01*
X384458Y146533D01*
X384667Y146783D01*
X385042Y147033D01*
G01X396333Y131425D02*
X396125Y131758D01*
X396000Y132133D01*
Y132467D01*
X396125Y132800D01*
X396333Y133050D01*
X396625Y133175D01*
X396917Y133092D01*
X397167Y132883D01*
X397333Y132508D01*
X397417Y132008D01*
X397583Y131717D01*
X397875Y131592D01*
X398167Y131675D01*
X398375Y131883D01*
X398500Y132175D01*
Y132467D01*
X398417Y132758D01*
X398208Y133008D01*
G01X398292Y136317D02*
X398417Y136067D01*
X398500Y135775D01*
Y135442D01*
X398375Y135067D01*
X398167Y134775D01*
X397917Y134567D01*
X397500Y134400D01*
X397125Y134358D01*
X396750Y134442D01*
X396500Y134567D01*
X396250Y134817D01*
X396083Y135108D01*
X396000Y135400D01*
Y135692D01*
X396083Y135983D01*
X396208Y136233D01*
X396375Y136442D01*
G01X396292Y137792D02*
X396083Y138083D01*
X396000Y138417D01*
X396083Y138750D01*
X396333Y139042D01*
X396708Y139250D01*
X397083Y139333D01*
X397542D01*
X397917Y139250D01*
X398250Y139042D01*
X398417Y138792D01*
X398500Y138500D01*
X398417Y138167D01*
X398250Y137917D01*
X398000Y137750D01*
X397667Y137667D01*
X397375Y137750D01*
X397083Y137958D01*
X396917Y138208D01*
X396875Y138500D01*
X396958Y138833D01*
X397167Y139083D01*
X397542Y139333D01*
G01X396000Y142100D02*
X398500D01*
X396708Y140558D01*
Y142642D01*
G01X398083Y143908D02*
X398333Y144158D01*
X398458Y144450D01*
X398500Y144783D01*
X398417Y145200D01*
X398208Y145492D01*
X397958Y145575D01*
X397708Y145533D01*
X397500Y145367D01*
X397083Y144533D01*
X396792Y144158D01*
X396375Y143908D01*
X396000Y143825D01*
Y145575D01*
G01X382500Y168000D02*
Y158500D01*
X388000D01*
Y156500D01*
G01X391500Y218000D02*
X399000D01*
Y222000D01*
X420500D01*
Y250000D01*
X413000D01*
Y269000D01*
X385000D01*
G01X395929Y219300D02*
X391929D01*
Y226700D01*
G01X408575Y241333D02*
X408242Y241125D01*
X407867Y241000D01*
X407533D01*
X407200Y241125D01*
X406950Y241333D01*
X406825Y241625D01*
X406908Y241917D01*
X407117Y242167D01*
X407492Y242333D01*
X407992Y242417D01*
X408283Y242583D01*
X408408Y242875D01*
X408325Y243167D01*
X408117Y243375D01*
X407825Y243500D01*
X407533D01*
X407242Y243417D01*
X406992Y243208D01*
G01X404600Y243500D02*
Y241000D01*
G01X405558Y243500D02*
X403642D01*
G01X402333Y241000D02*
Y243500D01*
X401333D01*
X401000Y243375D01*
X400750Y243083D01*
X400667Y242750D01*
X400750Y242417D01*
X400958Y242167D01*
X401333Y242042D01*
X402333D01*
G01X399317Y241375D02*
X399067Y241167D01*
X398775Y241042D01*
X398400Y241000D01*
X398025Y241083D01*
X397733Y241250D01*
X397525Y241542D01*
X397483Y241875D01*
X397567Y242208D01*
X397775Y242417D01*
X398067Y242583D01*
X398358Y242625D01*
X398650Y242583D01*
X399025Y242417D01*
X398900Y243500D01*
X397775D01*
G01X395300Y241000D02*
X395008Y241042D01*
X394675Y241167D01*
X394467Y241375D01*
X394383Y241667D01*
X394467Y241958D01*
X394717Y242208D01*
X395092Y242333D01*
X395508D01*
X395758Y242417D01*
X395967Y242625D01*
X396050Y242917D01*
X395925Y243208D01*
X395633Y243417D01*
X395300Y243500D01*
X394967Y243417D01*
X394675Y243208D01*
X394550Y242917D01*
X394633Y242625D01*
X394842Y242417D01*
X395092Y242333D01*
X395508D01*
X395883Y242208D01*
X396133Y241958D01*
X396217Y241667D01*
X396133Y241375D01*
X395925Y241167D01*
X395592Y241042D01*
X395300Y241000D01*
G01X394833Y247425D02*
X394625Y247758D01*
X394500Y248133D01*
Y248467D01*
X394625Y248800D01*
X394833Y249050D01*
X395125Y249175D01*
X395417Y249092D01*
X395667Y248883D01*
X395833Y248508D01*
X395917Y248008D01*
X396083Y247717D01*
X396375Y247592D01*
X396667Y247675D01*
X396875Y247883D01*
X397000Y248175D01*
Y248467D01*
X396917Y248758D01*
X396708Y249008D01*
G01X394500Y250567D02*
X397000D01*
Y251608D01*
X396875Y251942D01*
X396708Y252150D01*
X396375Y252233D01*
X396042Y252150D01*
X395833Y251900D01*
X395708Y251608D01*
Y250567D01*
G01Y251608D02*
X394500Y252233D01*
G01X395542Y253708D02*
X395833Y254000D01*
X396000Y254250D01*
X396083Y254583D01*
X396000Y254875D01*
X395833Y255083D01*
X395583Y255250D01*
X395292Y255292D01*
X395042Y255250D01*
X394792Y255083D01*
X394583Y254833D01*
X394500Y254542D01*
X394583Y254208D01*
X394833Y253917D01*
X395208Y253750D01*
X395625Y253708D01*
X396167Y253792D01*
X396458Y253917D01*
X396750Y254125D01*
X396958Y254417D01*
X397000Y254708D01*
X396917Y255000D01*
X396708Y255208D01*
G01X394500Y258100D02*
X397000D01*
X395208Y256558D01*
Y258642D01*
G01X396583Y259908D02*
X396833Y260158D01*
X396958Y260450D01*
X397000Y260783D01*
X396917Y261200D01*
X396708Y261492D01*
X396458Y261575D01*
X396208Y261533D01*
X396000Y261367D01*
X395583Y260533D01*
X395292Y260158D01*
X394875Y259908D01*
X394500Y259825D01*
Y261575D01*
G01X381333Y280875D02*
X381125Y281208D01*
X381000Y281583D01*
Y281917D01*
X381125Y282250D01*
X381333Y282500D01*
X381625Y282625D01*
X381917Y282542D01*
X382167Y282333D01*
X382333Y281958D01*
X382417Y281458D01*
X382583Y281167D01*
X382875Y281042D01*
X383167Y281125D01*
X383375Y281333D01*
X383500Y281625D01*
Y281917D01*
X383417Y282208D01*
X383208Y282458D01*
G01X383292Y285767D02*
X383417Y285517D01*
X383500Y285225D01*
Y284892D01*
X383375Y284517D01*
X383167Y284225D01*
X382917Y284017D01*
X382500Y283850D01*
X382125Y283808D01*
X381750Y283892D01*
X381500Y284017D01*
X381250Y284267D01*
X381083Y284558D01*
X381000Y284850D01*
Y285142D01*
X381083Y285433D01*
X381208Y285683D01*
X381375Y285892D01*
G01X381000Y287950D02*
X383500D01*
X383000Y287450D01*
G01X381000D02*
Y288450D01*
G01X383500Y291050D02*
X383417Y290717D01*
X383208Y290467D01*
X382958Y290300D01*
X382625Y290175D01*
X382250Y290133D01*
X381875Y290175D01*
X381542Y290300D01*
X381292Y290467D01*
X381083Y290717D01*
X381000Y291050D01*
X381083Y291383D01*
X381292Y291633D01*
X381542Y291800D01*
X381875Y291925D01*
X382250Y291967D01*
X382625Y291925D01*
X382958Y291800D01*
X383208Y291633D01*
X383417Y291383D01*
X383500Y291050D01*
G01X381500Y293233D02*
X381208Y293483D01*
X381042Y293817D01*
X381000Y294192D01*
X381042Y294525D01*
X381250Y294858D01*
X381500Y295067D01*
X381750Y295108D01*
X382042Y295025D01*
X382250Y294733D01*
X382333Y294442D01*
Y294067D01*
G01Y294442D02*
X382458Y294692D01*
X382667Y294900D01*
X382917Y294983D01*
X383167Y294900D01*
X383375Y294692D01*
X383500Y294317D01*
X383458Y293942D01*
X383292Y293567D01*
G01X381000Y297250D02*
X383500D01*
X383000Y296750D01*
G01X381000D02*
Y297750D01*
G01X395833Y299875D02*
X395625Y300208D01*
X395500Y300583D01*
Y300917D01*
X395625Y301250D01*
X395833Y301500D01*
X396125Y301625D01*
X396417Y301542D01*
X396667Y301333D01*
X396833Y300958D01*
X396917Y300458D01*
X397083Y300167D01*
X397375Y300042D01*
X397667Y300125D01*
X397875Y300333D01*
X398000Y300625D01*
Y300917D01*
X397917Y301208D01*
X397708Y301458D01*
G01X397792Y304767D02*
X397917Y304517D01*
X398000Y304225D01*
Y303892D01*
X397875Y303517D01*
X397667Y303225D01*
X397417Y303017D01*
X397000Y302850D01*
X396625Y302808D01*
X396250Y302892D01*
X396000Y303017D01*
X395750Y303267D01*
X395583Y303558D01*
X395500Y303850D01*
Y304142D01*
X395583Y304433D01*
X395708Y304683D01*
X395875Y304892D01*
G01X395500Y306950D02*
X398000D01*
X397500Y306450D01*
G01X395500D02*
Y307450D01*
G01X397583Y309258D02*
X397833Y309508D01*
X397958Y309800D01*
X398000Y310133D01*
X397917Y310550D01*
X397708Y310842D01*
X397458Y310925D01*
X397208Y310883D01*
X397000Y310717D01*
X396583Y309883D01*
X396292Y309508D01*
X395875Y309258D01*
X395500Y309175D01*
Y310925D01*
G01X398000Y313150D02*
X397917Y312817D01*
X397708Y312567D01*
X397458Y312400D01*
X397125Y312275D01*
X396750Y312233D01*
X396375Y312275D01*
X396042Y312400D01*
X395792Y312567D01*
X395583Y312817D01*
X395500Y313150D01*
X395583Y313483D01*
X395792Y313733D01*
X396042Y313900D01*
X396375Y314025D01*
X396750Y314067D01*
X397125Y314025D01*
X397458Y313900D01*
X397708Y313733D01*
X397917Y313483D01*
X398000Y313150D01*
G01X396000Y315333D02*
X395708Y315583D01*
X395542Y315917D01*
X395500Y316292D01*
X395542Y316625D01*
X395750Y316958D01*
X396000Y317167D01*
X396250Y317208D01*
X396542Y317125D01*
X396750Y316833D01*
X396833Y316542D01*
Y316167D01*
G01Y316542D02*
X396958Y316792D01*
X397167Y317000D01*
X397417Y317083D01*
X397667Y317000D01*
X397875Y316792D01*
X398000Y316417D01*
X397958Y316042D01*
X397792Y315667D01*
G01X409230Y345583D02*
X408897Y345375D01*
X408522Y345250D01*
X408188D01*
X407855Y345375D01*
X407605Y345583D01*
X407480Y345875D01*
X407563Y346167D01*
X407772Y346417D01*
X408147Y346583D01*
X408647Y346667D01*
X408938Y346833D01*
X409063Y347125D01*
X408980Y347417D01*
X408772Y347625D01*
X408480Y347750D01*
X408188D01*
X407897Y347667D01*
X407647Y347458D01*
G01X404338Y347542D02*
X404588Y347667D01*
X404880Y347750D01*
X405213D01*
X405588Y347625D01*
X405880Y347417D01*
X406088Y347167D01*
X406255Y346750D01*
X406297Y346375D01*
X406213Y346000D01*
X406088Y345750D01*
X405838Y345500D01*
X405547Y345333D01*
X405255Y345250D01*
X404963D01*
X404672Y345333D01*
X404422Y345458D01*
X404213Y345625D01*
G01X402155Y345250D02*
Y347750D01*
X402655Y347250D01*
G01Y345250D02*
X401655D01*
G01X399847Y347333D02*
X399597Y347583D01*
X399305Y347708D01*
X398972Y347750D01*
X398555Y347667D01*
X398263Y347458D01*
X398180Y347208D01*
X398222Y346958D01*
X398388Y346750D01*
X399222Y346333D01*
X399597Y346042D01*
X399847Y345625D01*
X399930Y345250D01*
X398180D01*
G01X396747Y347333D02*
X396497Y347583D01*
X396205Y347708D01*
X395872Y347750D01*
X395455Y347667D01*
X395163Y347458D01*
X395080Y347208D01*
X395122Y346958D01*
X395288Y346750D01*
X396122Y346333D01*
X396497Y346042D01*
X396747Y345625D01*
X396830Y345250D01*
X395080D01*
G01X392855D02*
Y347750D01*
X393355Y347250D01*
G01Y345250D02*
X392355D01*
G01X403125Y338333D02*
X402792Y338125D01*
X402417Y338000D01*
X402083D01*
X401750Y338125D01*
X401500Y338333D01*
X401375Y338625D01*
X401458Y338917D01*
X401667Y339167D01*
X402042Y339333D01*
X402542Y339417D01*
X402833Y339583D01*
X402958Y339875D01*
X402875Y340167D01*
X402667Y340375D01*
X402375Y340500D01*
X402083D01*
X401792Y340417D01*
X401542Y340208D01*
G01X398233Y340292D02*
X398483Y340417D01*
X398775Y340500D01*
X399108D01*
X399483Y340375D01*
X399775Y340167D01*
X399983Y339917D01*
X400150Y339500D01*
X400192Y339125D01*
X400108Y338750D01*
X399983Y338500D01*
X399733Y338250D01*
X399442Y338083D01*
X399150Y338000D01*
X398858D01*
X398567Y338083D01*
X398317Y338208D01*
X398108Y338375D01*
G01X396050Y338000D02*
Y340500D01*
X396550Y340000D01*
G01Y338000D02*
X395550D01*
G01X393742Y340083D02*
X393492Y340333D01*
X393200Y340458D01*
X392867Y340500D01*
X392450Y340417D01*
X392158Y340208D01*
X392075Y339958D01*
X392117Y339708D01*
X392283Y339500D01*
X393117Y339083D01*
X393492Y338792D01*
X393742Y338375D01*
X393825Y338000D01*
X392075D01*
G01X389850D02*
Y340500D01*
X390350Y340000D01*
G01Y338000D02*
X389350D01*
G01X386750D02*
Y340500D01*
X387250Y340000D01*
G01Y338000D02*
X386250D01*
G01X403180Y371333D02*
X402847Y371125D01*
X402472Y371000D01*
X402138D01*
X401805Y371125D01*
X401555Y371333D01*
X401430Y371625D01*
X401513Y371917D01*
X401722Y372167D01*
X402097Y372333D01*
X402597Y372417D01*
X402888Y372583D01*
X403013Y372875D01*
X402930Y373167D01*
X402722Y373375D01*
X402430Y373500D01*
X402138D01*
X401847Y373417D01*
X401597Y373208D01*
G01X398288Y373292D02*
X398538Y373417D01*
X398830Y373500D01*
X399163D01*
X399538Y373375D01*
X399830Y373167D01*
X400038Y372917D01*
X400205Y372500D01*
X400247Y372125D01*
X400163Y371750D01*
X400038Y371500D01*
X399788Y371250D01*
X399497Y371083D01*
X399205Y371000D01*
X398913D01*
X398622Y371083D01*
X398372Y371208D01*
X398163Y371375D01*
G01X396105Y371000D02*
Y373500D01*
X396605Y373000D01*
G01Y371000D02*
X395605D01*
G01X393797Y373083D02*
X393547Y373333D01*
X393255Y373458D01*
X392922Y373500D01*
X392505Y373417D01*
X392213Y373208D01*
X392130Y372958D01*
X392172Y372708D01*
X392338Y372500D01*
X393172Y372083D01*
X393547Y371792D01*
X393797Y371375D01*
X393880Y371000D01*
X392130D01*
G01X389905D02*
Y373500D01*
X390405Y373000D01*
G01Y371000D02*
X389405D01*
G01X386305D02*
Y373500D01*
X387847Y371708D01*
X385763D01*
G01X390333Y392375D02*
X390125Y392708D01*
X390000Y393083D01*
Y393417D01*
X390125Y393750D01*
X390333Y394000D01*
X390625Y394125D01*
X390917Y394042D01*
X391167Y393833D01*
X391333Y393458D01*
X391417Y392958D01*
X391583Y392667D01*
X391875Y392542D01*
X392167Y392625D01*
X392375Y392833D01*
X392500Y393125D01*
Y393417D01*
X392417Y393708D01*
X392208Y393958D01*
G01X392500Y396350D02*
X390000D01*
G01X392500Y395392D02*
Y397308D01*
G01X390000Y398617D02*
X392500D01*
Y399617D01*
X392375Y399950D01*
X392083Y400200D01*
X391750Y400283D01*
X391417Y400200D01*
X391167Y399992D01*
X391042Y399617D01*
Y398617D01*
G01X390000Y402550D02*
X392500D01*
X392000Y402050D01*
G01X390000D02*
Y403050D01*
G01X391042Y404858D02*
X391333Y405150D01*
X391500Y405400D01*
X391583Y405733D01*
X391500Y406025D01*
X391333Y406233D01*
X391083Y406400D01*
X390792Y406442D01*
X390542Y406400D01*
X390292Y406233D01*
X390083Y405983D01*
X390000Y405692D01*
X390083Y405358D01*
X390333Y405067D01*
X390708Y404900D01*
X391125Y404858D01*
X391667Y404942D01*
X391958Y405067D01*
X392250Y405275D01*
X392458Y405567D01*
X392500Y405858D01*
X392417Y406150D01*
X392208Y406358D01*
G01X390000Y409250D02*
X392500D01*
X390708Y407708D01*
Y409792D01*
G01X402255Y421000D02*
Y418500D01*
G01X403213Y421000D02*
X401297D01*
G01X399988Y418500D02*
Y421000D01*
X398988D01*
X398655Y420875D01*
X398405Y420583D01*
X398322Y420250D01*
X398405Y419917D01*
X398613Y419667D01*
X398988Y419542D01*
X399988D01*
G01X396847Y420583D02*
X396597Y420833D01*
X396305Y420958D01*
X395972Y421000D01*
X395555Y420917D01*
X395263Y420708D01*
X395180Y420458D01*
X395222Y420208D01*
X395388Y420000D01*
X396222Y419583D01*
X396597Y419292D01*
X396847Y418875D01*
X396930Y418500D01*
X395180D01*
G01X393747Y419542D02*
X393455Y419833D01*
X393205Y420000D01*
X392872Y420083D01*
X392580Y420000D01*
X392372Y419833D01*
X392205Y419583D01*
X392163Y419292D01*
X392205Y419042D01*
X392372Y418792D01*
X392622Y418583D01*
X392913Y418500D01*
X393247Y418583D01*
X393538Y418833D01*
X393705Y419208D01*
X393747Y419625D01*
X393663Y420167D01*
X393538Y420458D01*
X393330Y420750D01*
X393038Y420958D01*
X392747Y421000D01*
X392455Y420917D01*
X392247Y420708D01*
G01X390647Y420583D02*
X390397Y420833D01*
X390105Y420958D01*
X389772Y421000D01*
X389355Y420917D01*
X389063Y420708D01*
X388980Y420458D01*
X389022Y420208D01*
X389188Y420000D01*
X390022Y419583D01*
X390397Y419292D01*
X390647Y418875D01*
X390730Y418500D01*
X388980D01*
G01X396555Y429300D02*
X392555D01*
Y436700D01*
G01X391000Y946200D02*
X395000D01*
Y938800D01*
G01Y946200D02*
X399000D01*
Y938800D01*
G01X399373Y39425D02*
X399165Y39758D01*
X399040Y40133D01*
Y40467D01*
X399165Y40800D01*
X399373Y41050D01*
X399665Y41175D01*
X399957Y41092D01*
X400207Y40883D01*
X400373Y40508D01*
X400457Y40008D01*
X400623Y39717D01*
X400915Y39592D01*
X401207Y39675D01*
X401415Y39883D01*
X401540Y40175D01*
Y40467D01*
X401457Y40758D01*
X401248Y41008D01*
G01X401332Y44317D02*
X401457Y44067D01*
X401540Y43775D01*
Y43442D01*
X401415Y43067D01*
X401207Y42775D01*
X400957Y42567D01*
X400540Y42400D01*
X400165Y42358D01*
X399790Y42442D01*
X399540Y42567D01*
X399290Y42817D01*
X399123Y43108D01*
X399040Y43400D01*
Y43692D01*
X399123Y43983D01*
X399248Y44233D01*
X399415Y44442D01*
G01X399332Y45792D02*
X399123Y46083D01*
X399040Y46417D01*
X399123Y46750D01*
X399373Y47042D01*
X399748Y47250D01*
X400123Y47333D01*
X400582D01*
X400957Y47250D01*
X401290Y47042D01*
X401457Y46792D01*
X401540Y46500D01*
X401457Y46167D01*
X401290Y45917D01*
X401040Y45750D01*
X400707Y45667D01*
X400415Y45750D01*
X400123Y45958D01*
X399957Y46208D01*
X399915Y46500D01*
X399998Y46833D01*
X400207Y47083D01*
X400582Y47333D01*
G01X399332Y48892D02*
X399123Y49183D01*
X399040Y49517D01*
X399123Y49850D01*
X399373Y50142D01*
X399748Y50350D01*
X400123Y50433D01*
X400582D01*
X400957Y50350D01*
X401290Y50142D01*
X401457Y49892D01*
X401540Y49600D01*
X401457Y49267D01*
X401290Y49017D01*
X401040Y48850D01*
X400707Y48767D01*
X400415Y48850D01*
X400123Y49058D01*
X399957Y49308D01*
X399915Y49600D01*
X399998Y49933D01*
X400207Y50183D01*
X400582Y50433D01*
G01X399415Y51783D02*
X399207Y52033D01*
X399082Y52325D01*
X399040Y52700D01*
X399123Y53075D01*
X399290Y53367D01*
X399582Y53575D01*
X399915Y53617D01*
X400248Y53533D01*
X400457Y53325D01*
X400623Y53033D01*
X400665Y52742D01*
X400623Y52450D01*
X400457Y52075D01*
X401540Y52200D01*
Y53325D01*
G01X399333Y56425D02*
X399125Y56758D01*
X399000Y57133D01*
Y57467D01*
X399125Y57800D01*
X399333Y58050D01*
X399625Y58175D01*
X399917Y58092D01*
X400167Y57883D01*
X400333Y57508D01*
X400417Y57008D01*
X400583Y56717D01*
X400875Y56592D01*
X401167Y56675D01*
X401375Y56883D01*
X401500Y57175D01*
Y57467D01*
X401417Y57758D01*
X401208Y58008D01*
G01X401500Y60400D02*
X399000D01*
G01X401500Y59442D02*
Y61358D01*
G01X399000Y62667D02*
X401500D01*
Y63667D01*
X401375Y64000D01*
X401083Y64250D01*
X400750Y64333D01*
X400417Y64250D01*
X400167Y64042D01*
X400042Y63667D01*
Y62667D01*
G01X399000Y67100D02*
X401500D01*
X399708Y65558D01*
Y67642D01*
G01X401083Y68908D02*
X401333Y69158D01*
X401458Y69450D01*
X401500Y69783D01*
X401417Y70200D01*
X401208Y70492D01*
X400958Y70575D01*
X400708Y70533D01*
X400500Y70367D01*
X400083Y69533D01*
X399792Y69158D01*
X399375Y68908D01*
X399000Y68825D01*
Y70575D01*
G01X404333Y56425D02*
X404125Y56758D01*
X404000Y57133D01*
Y57467D01*
X404125Y57800D01*
X404333Y58050D01*
X404625Y58175D01*
X404917Y58092D01*
X405167Y57883D01*
X405333Y57508D01*
X405417Y57008D01*
X405583Y56717D01*
X405875Y56592D01*
X406167Y56675D01*
X406375Y56883D01*
X406500Y57175D01*
Y57467D01*
X406417Y57758D01*
X406208Y58008D01*
G01X404000Y59567D02*
X406500D01*
Y60608D01*
X406375Y60942D01*
X406208Y61150D01*
X405875Y61233D01*
X405542Y61150D01*
X405333Y60900D01*
X405208Y60608D01*
Y59567D01*
G01Y60608D02*
X404000Y61233D01*
G01X405042Y62708D02*
X405333Y63000D01*
X405500Y63250D01*
X405583Y63583D01*
X405500Y63875D01*
X405333Y64083D01*
X405083Y64250D01*
X404792Y64292D01*
X404542Y64250D01*
X404292Y64083D01*
X404083Y63833D01*
X404000Y63542D01*
X404083Y63208D01*
X404333Y62917D01*
X404708Y62750D01*
X405125Y62708D01*
X405667Y62792D01*
X405958Y62917D01*
X406250Y63125D01*
X406458Y63417D01*
X406500Y63708D01*
X406417Y64000D01*
X406208Y64208D01*
G01X405042Y65808D02*
X405333Y66100D01*
X405500Y66350D01*
X405583Y66683D01*
X405500Y66975D01*
X405333Y67183D01*
X405083Y67350D01*
X404792Y67392D01*
X404542Y67350D01*
X404292Y67183D01*
X404083Y66933D01*
X404000Y66642D01*
X404083Y66308D01*
X404333Y66017D01*
X404708Y65850D01*
X405125Y65808D01*
X405667Y65892D01*
X405958Y66017D01*
X406250Y66225D01*
X406458Y66517D01*
X406500Y66808D01*
X406417Y67100D01*
X406208Y67308D01*
G01X404292Y68992D02*
X404083Y69283D01*
X404000Y69617D01*
X404083Y69950D01*
X404333Y70242D01*
X404708Y70450D01*
X405083Y70533D01*
X405542D01*
X405917Y70450D01*
X406250Y70242D01*
X406417Y69992D01*
X406500Y69700D01*
X406417Y69367D01*
X406250Y69117D01*
X406000Y68950D01*
X405667Y68867D01*
X405375Y68950D01*
X405083Y69158D01*
X404917Y69408D01*
X404875Y69700D01*
X404958Y70033D01*
X405167Y70283D01*
X405542Y70533D01*
G01X408773Y75225D02*
X408565Y75558D01*
X408440Y75933D01*
Y76267D01*
X408565Y76600D01*
X408773Y76850D01*
X409065Y76975D01*
X409357Y76892D01*
X409607Y76683D01*
X409773Y76308D01*
X409857Y75808D01*
X410023Y75517D01*
X410315Y75392D01*
X410607Y75475D01*
X410815Y75683D01*
X410940Y75975D01*
Y76267D01*
X410857Y76558D01*
X410648Y76808D01*
G01X408440Y78367D02*
X410940D01*
Y79408D01*
X410815Y79742D01*
X410648Y79950D01*
X410315Y80033D01*
X409982Y79950D01*
X409773Y79700D01*
X409648Y79408D01*
Y78367D01*
G01Y79408D02*
X408440Y80033D01*
G01X409482Y81508D02*
X409773Y81800D01*
X409940Y82050D01*
X410023Y82383D01*
X409940Y82675D01*
X409773Y82883D01*
X409523Y83050D01*
X409232Y83092D01*
X408982Y83050D01*
X408732Y82883D01*
X408523Y82633D01*
X408440Y82342D01*
X408523Y82008D01*
X408773Y81717D01*
X409148Y81550D01*
X409565Y81508D01*
X410107Y81592D01*
X410398Y81717D01*
X410690Y81925D01*
X410898Y82217D01*
X410940Y82508D01*
X410857Y82800D01*
X410648Y83008D01*
G01X409482Y84608D02*
X409773Y84900D01*
X409940Y85150D01*
X410023Y85483D01*
X409940Y85775D01*
X409773Y85983D01*
X409523Y86150D01*
X409232Y86192D01*
X408982Y86150D01*
X408732Y85983D01*
X408523Y85733D01*
X408440Y85442D01*
X408523Y85108D01*
X408773Y84817D01*
X409148Y84650D01*
X409565Y84608D01*
X410107Y84692D01*
X410398Y84817D01*
X410690Y85025D01*
X410898Y85317D01*
X410940Y85608D01*
X410857Y85900D01*
X410648Y86108D01*
G01X408815Y87583D02*
X408607Y87833D01*
X408482Y88125D01*
X408440Y88500D01*
X408523Y88875D01*
X408690Y89167D01*
X408982Y89375D01*
X409315Y89417D01*
X409648Y89333D01*
X409857Y89125D01*
X410023Y88833D01*
X410065Y88542D01*
X410023Y88250D01*
X409857Y87875D01*
X410940Y88000D01*
Y89125D01*
G01X404773Y75225D02*
X404565Y75558D01*
X404440Y75933D01*
Y76267D01*
X404565Y76600D01*
X404773Y76850D01*
X405065Y76975D01*
X405357Y76892D01*
X405607Y76683D01*
X405773Y76308D01*
X405857Y75808D01*
X406023Y75517D01*
X406315Y75392D01*
X406607Y75475D01*
X406815Y75683D01*
X406940Y75975D01*
Y76267D01*
X406857Y76558D01*
X406648Y76808D01*
G01X404440Y78367D02*
X406940D01*
Y79408D01*
X406815Y79742D01*
X406648Y79950D01*
X406315Y80033D01*
X405982Y79950D01*
X405773Y79700D01*
X405648Y79408D01*
Y78367D01*
G01Y79408D02*
X404440Y80033D01*
G01X405482Y81508D02*
X405773Y81800D01*
X405940Y82050D01*
X406023Y82383D01*
X405940Y82675D01*
X405773Y82883D01*
X405523Y83050D01*
X405232Y83092D01*
X404982Y83050D01*
X404732Y82883D01*
X404523Y82633D01*
X404440Y82342D01*
X404523Y82008D01*
X404773Y81717D01*
X405148Y81550D01*
X405565Y81508D01*
X406107Y81592D01*
X406398Y81717D01*
X406690Y81925D01*
X406898Y82217D01*
X406940Y82508D01*
X406857Y82800D01*
X406648Y83008D01*
G01X404440Y85400D02*
X404482Y85692D01*
X404607Y86025D01*
X404815Y86233D01*
X405107Y86317D01*
X405398Y86233D01*
X405648Y85983D01*
X405773Y85608D01*
Y85192D01*
X405857Y84942D01*
X406065Y84733D01*
X406357Y84650D01*
X406648Y84775D01*
X406857Y85067D01*
X406940Y85400D01*
X406857Y85733D01*
X406648Y86025D01*
X406357Y86150D01*
X406065Y86067D01*
X405857Y85858D01*
X405773Y85608D01*
Y85192D01*
X405648Y84817D01*
X405398Y84567D01*
X405107Y84483D01*
X404815Y84567D01*
X404607Y84775D01*
X404482Y85108D01*
X404440Y85400D01*
G01X405482Y87708D02*
X405773Y88000D01*
X405940Y88250D01*
X406023Y88583D01*
X405940Y88875D01*
X405773Y89083D01*
X405523Y89250D01*
X405232Y89292D01*
X404982Y89250D01*
X404732Y89083D01*
X404523Y88833D01*
X404440Y88542D01*
X404523Y88208D01*
X404773Y87917D01*
X405148Y87750D01*
X405565Y87708D01*
X406107Y87792D01*
X406398Y87917D01*
X406690Y88125D01*
X406898Y88417D01*
X406940Y88708D01*
X406857Y89000D01*
X406648Y89208D01*
G01X400833Y78875D02*
X400625Y79208D01*
X400500Y79583D01*
Y79917D01*
X400625Y80250D01*
X400833Y80500D01*
X401125Y80625D01*
X401417Y80542D01*
X401667Y80333D01*
X401833Y79958D01*
X401917Y79458D01*
X402083Y79167D01*
X402375Y79042D01*
X402667Y79125D01*
X402875Y79333D01*
X403000Y79625D01*
Y79917D01*
X402917Y80208D01*
X402708Y80458D01*
G01X402792Y83767D02*
X402917Y83517D01*
X403000Y83225D01*
Y82892D01*
X402875Y82517D01*
X402667Y82225D01*
X402417Y82017D01*
X402000Y81850D01*
X401625Y81808D01*
X401250Y81892D01*
X401000Y82017D01*
X400750Y82267D01*
X400583Y82558D01*
X400500Y82850D01*
Y83142D01*
X400583Y83433D01*
X400708Y83683D01*
X400875Y83892D01*
G01X400500Y85950D02*
X403000D01*
X402500Y85450D01*
G01X400500D02*
Y86450D01*
G01X403000Y89050D02*
X402917Y88717D01*
X402708Y88467D01*
X402458Y88300D01*
X402125Y88175D01*
X401750Y88133D01*
X401375Y88175D01*
X401042Y88300D01*
X400792Y88467D01*
X400583Y88717D01*
X400500Y89050D01*
X400583Y89383D01*
X400792Y89633D01*
X401042Y89800D01*
X401375Y89925D01*
X401750Y89967D01*
X402125Y89925D01*
X402458Y89800D01*
X402708Y89633D01*
X402917Y89383D01*
X403000Y89050D01*
G01X400500Y92650D02*
X403000D01*
X401208Y91108D01*
Y93192D01*
G01X400792Y94542D02*
X400583Y94833D01*
X400500Y95167D01*
X400583Y95500D01*
X400833Y95792D01*
X401208Y96000D01*
X401583Y96083D01*
X402042D01*
X402417Y96000D01*
X402750Y95792D01*
X402917Y95542D01*
X403000Y95250D01*
X402917Y94917D01*
X402750Y94667D01*
X402500Y94500D01*
X402167Y94417D01*
X401875Y94500D01*
X401583Y94708D01*
X401417Y94958D01*
X401375Y95250D01*
X401458Y95583D01*
X401667Y95833D01*
X402042Y96083D01*
G01X426575Y79333D02*
X426242Y79125D01*
X425867Y79000D01*
X425533D01*
X425200Y79125D01*
X424950Y79333D01*
X424825Y79625D01*
X424908Y79917D01*
X425117Y80167D01*
X425492Y80333D01*
X425992Y80417D01*
X426283Y80583D01*
X426408Y80875D01*
X426325Y81167D01*
X426117Y81375D01*
X425825Y81500D01*
X425533D01*
X425242Y81417D01*
X424992Y81208D01*
G01X421683Y81292D02*
X421933Y81417D01*
X422225Y81500D01*
X422558D01*
X422933Y81375D01*
X423225Y81167D01*
X423433Y80917D01*
X423600Y80500D01*
X423642Y80125D01*
X423558Y79750D01*
X423433Y79500D01*
X423183Y79250D01*
X422892Y79083D01*
X422600Y79000D01*
X422308D01*
X422017Y79083D01*
X421767Y79208D01*
X421558Y79375D01*
G01X420208Y79292D02*
X419917Y79083D01*
X419583Y79000D01*
X419250Y79083D01*
X418958Y79333D01*
X418750Y79708D01*
X418667Y80083D01*
Y80542D01*
X418750Y80917D01*
X418958Y81250D01*
X419208Y81417D01*
X419500Y81500D01*
X419833Y81417D01*
X420083Y81250D01*
X420250Y81000D01*
X420333Y80667D01*
X420250Y80375D01*
X420042Y80083D01*
X419792Y79917D01*
X419500Y79875D01*
X419167Y79958D01*
X418917Y80167D01*
X418667Y80542D01*
G01X416400Y79000D02*
X416108Y79042D01*
X415775Y79167D01*
X415567Y79375D01*
X415483Y79667D01*
X415567Y79958D01*
X415817Y80208D01*
X416192Y80333D01*
X416608D01*
X416858Y80417D01*
X417067Y80625D01*
X417150Y80917D01*
X417025Y81208D01*
X416733Y81417D01*
X416400Y81500D01*
X416067Y81417D01*
X415775Y81208D01*
X415650Y80917D01*
X415733Y80625D01*
X415942Y80417D01*
X416192Y80333D01*
X416608D01*
X416983Y80208D01*
X417233Y79958D01*
X417317Y79667D01*
X417233Y79375D01*
X417025Y79167D01*
X416692Y79042D01*
X416400Y79000D01*
G01X414092Y80042D02*
X413800Y80333D01*
X413550Y80500D01*
X413217Y80583D01*
X412925Y80500D01*
X412717Y80333D01*
X412550Y80083D01*
X412508Y79792D01*
X412550Y79542D01*
X412717Y79292D01*
X412967Y79083D01*
X413258Y79000D01*
X413592Y79083D01*
X413883Y79333D01*
X414050Y79708D01*
X414092Y80125D01*
X414008Y80667D01*
X413883Y80958D01*
X413675Y81250D01*
X413383Y81458D01*
X413092Y81500D01*
X412800Y81417D01*
X412592Y81208D01*
G01X426454Y85453D02*
X426121Y85245D01*
X425746Y85120D01*
X425412D01*
X425079Y85245D01*
X424829Y85453D01*
X424704Y85745D01*
X424787Y86037D01*
X424996Y86287D01*
X425371Y86453D01*
X425871Y86537D01*
X426162Y86703D01*
X426287Y86995D01*
X426204Y87287D01*
X425996Y87495D01*
X425704Y87620D01*
X425412D01*
X425121Y87537D01*
X424871Y87328D01*
G01X421562Y87412D02*
X421812Y87537D01*
X422104Y87620D01*
X422437D01*
X422812Y87495D01*
X423104Y87287D01*
X423312Y87037D01*
X423479Y86620D01*
X423521Y86245D01*
X423437Y85870D01*
X423312Y85620D01*
X423062Y85370D01*
X422771Y85203D01*
X422479Y85120D01*
X422187D01*
X421896Y85203D01*
X421646Y85328D01*
X421437Y85495D01*
G01X420087Y85412D02*
X419796Y85203D01*
X419462Y85120D01*
X419129Y85203D01*
X418837Y85453D01*
X418629Y85828D01*
X418546Y86203D01*
Y86662D01*
X418629Y87037D01*
X418837Y87370D01*
X419087Y87537D01*
X419379Y87620D01*
X419712Y87537D01*
X419962Y87370D01*
X420129Y87120D01*
X420212Y86787D01*
X420129Y86495D01*
X419921Y86203D01*
X419671Y86037D01*
X419379Y85995D01*
X419046Y86078D01*
X418796Y86287D01*
X418546Y86662D01*
G01X416279Y85120D02*
X415987Y85162D01*
X415654Y85287D01*
X415446Y85495D01*
X415362Y85787D01*
X415446Y86078D01*
X415696Y86328D01*
X416071Y86453D01*
X416487D01*
X416737Y86537D01*
X416946Y86745D01*
X417029Y87037D01*
X416904Y87328D01*
X416612Y87537D01*
X416279Y87620D01*
X415946Y87537D01*
X415654Y87328D01*
X415529Y87037D01*
X415612Y86745D01*
X415821Y86537D01*
X416071Y86453D01*
X416487D01*
X416862Y86328D01*
X417112Y86078D01*
X417196Y85787D01*
X417112Y85495D01*
X416904Y85287D01*
X416571Y85162D01*
X416279Y85120D01*
G01X413262D02*
X413179Y85662D01*
X413054Y86120D01*
X412887Y86537D01*
X412679Y86995D01*
X412346Y87620D01*
X414012D01*
G01X398373Y104992D02*
X398165Y105325D01*
X398040Y105700D01*
Y106034D01*
X398165Y106367D01*
X398373Y106617D01*
X398665Y106742D01*
X398957Y106659D01*
X399207Y106450D01*
X399373Y106075D01*
X399457Y105575D01*
X399623Y105284D01*
X399915Y105159D01*
X400207Y105242D01*
X400415Y105450D01*
X400540Y105742D01*
Y106034D01*
X400457Y106325D01*
X400248Y106575D01*
G01X400332Y109884D02*
X400457Y109634D01*
X400540Y109342D01*
Y109009D01*
X400415Y108634D01*
X400207Y108342D01*
X399957Y108134D01*
X399540Y107967D01*
X399165Y107925D01*
X398790Y108009D01*
X398540Y108134D01*
X398290Y108384D01*
X398123Y108675D01*
X398040Y108967D01*
Y109259D01*
X398123Y109550D01*
X398248Y109800D01*
X398415Y110009D01*
G01X398040Y112067D02*
X398082Y112359D01*
X398207Y112692D01*
X398415Y112900D01*
X398707Y112984D01*
X398998Y112900D01*
X399248Y112650D01*
X399373Y112275D01*
Y111859D01*
X399457Y111609D01*
X399665Y111400D01*
X399957Y111317D01*
X400248Y111442D01*
X400457Y111734D01*
X400540Y112067D01*
X400457Y112400D01*
X400248Y112692D01*
X399957Y112817D01*
X399665Y112734D01*
X399457Y112525D01*
X399373Y112275D01*
Y111859D01*
X399248Y111484D01*
X398998Y111234D01*
X398707Y111150D01*
X398415Y111234D01*
X398207Y111442D01*
X398082Y111775D01*
X398040Y112067D01*
G01Y115084D02*
X398582Y115167D01*
X399040Y115292D01*
X399457Y115459D01*
X399915Y115667D01*
X400540Y116000D01*
Y114334D01*
G01X400123Y117475D02*
X400373Y117725D01*
X400498Y118017D01*
X400540Y118350D01*
X400457Y118767D01*
X400248Y119059D01*
X399998Y119142D01*
X399748Y119100D01*
X399540Y118934D01*
X399123Y118100D01*
X398832Y117725D01*
X398415Y117475D01*
X398040Y117392D01*
Y119142D01*
G01X402373Y104925D02*
X402165Y105258D01*
X402040Y105633D01*
Y105967D01*
X402165Y106300D01*
X402373Y106550D01*
X402665Y106675D01*
X402957Y106592D01*
X403207Y106383D01*
X403373Y106008D01*
X403457Y105508D01*
X403623Y105217D01*
X403915Y105092D01*
X404207Y105175D01*
X404415Y105383D01*
X404540Y105675D01*
Y105967D01*
X404457Y106258D01*
X404248Y106508D01*
G01X404332Y109817D02*
X404457Y109567D01*
X404540Y109275D01*
Y108942D01*
X404415Y108567D01*
X404207Y108275D01*
X403957Y108067D01*
X403540Y107900D01*
X403165Y107858D01*
X402790Y107942D01*
X402540Y108067D01*
X402290Y108317D01*
X402123Y108608D01*
X402040Y108900D01*
Y109192D01*
X402123Y109483D01*
X402248Y109733D01*
X402415Y109942D01*
G01X402040Y112000D02*
X402082Y112292D01*
X402207Y112625D01*
X402415Y112833D01*
X402707Y112917D01*
X402998Y112833D01*
X403248Y112583D01*
X403373Y112208D01*
Y111792D01*
X403457Y111542D01*
X403665Y111333D01*
X403957Y111250D01*
X404248Y111375D01*
X404457Y111667D01*
X404540Y112000D01*
X404457Y112333D01*
X404248Y112625D01*
X403957Y112750D01*
X403665Y112667D01*
X403457Y112458D01*
X403373Y112208D01*
Y111792D01*
X403248Y111417D01*
X402998Y111167D01*
X402707Y111083D01*
X402415Y111167D01*
X402207Y111375D01*
X402082Y111708D01*
X402040Y112000D01*
G01Y115017D02*
X402582Y115100D01*
X403040Y115225D01*
X403457Y115392D01*
X403915Y115600D01*
X404540Y115933D01*
Y114267D01*
G01X402540Y117283D02*
X402248Y117533D01*
X402082Y117867D01*
X402040Y118242D01*
X402082Y118575D01*
X402290Y118908D01*
X402540Y119117D01*
X402790Y119158D01*
X403082Y119075D01*
X403290Y118783D01*
X403373Y118492D01*
Y118117D01*
G01Y118492D02*
X403498Y118742D01*
X403707Y118950D01*
X403957Y119033D01*
X404207Y118950D01*
X404415Y118742D01*
X404540Y118367D01*
X404498Y117992D01*
X404332Y117617D01*
G01X406373Y104925D02*
X406165Y105258D01*
X406040Y105633D01*
Y105967D01*
X406165Y106300D01*
X406373Y106550D01*
X406665Y106675D01*
X406957Y106592D01*
X407207Y106383D01*
X407373Y106008D01*
X407457Y105508D01*
X407623Y105217D01*
X407915Y105092D01*
X408207Y105175D01*
X408415Y105383D01*
X408540Y105675D01*
Y105967D01*
X408457Y106258D01*
X408248Y106508D01*
G01X408332Y109817D02*
X408457Y109567D01*
X408540Y109275D01*
Y108942D01*
X408415Y108567D01*
X408207Y108275D01*
X407957Y108067D01*
X407540Y107900D01*
X407165Y107858D01*
X406790Y107942D01*
X406540Y108067D01*
X406290Y108317D01*
X406123Y108608D01*
X406040Y108900D01*
Y109192D01*
X406123Y109483D01*
X406248Y109733D01*
X406415Y109942D01*
G01X406040Y112000D02*
X406082Y112292D01*
X406207Y112625D01*
X406415Y112833D01*
X406707Y112917D01*
X406998Y112833D01*
X407248Y112583D01*
X407373Y112208D01*
Y111792D01*
X407457Y111542D01*
X407665Y111333D01*
X407957Y111250D01*
X408248Y111375D01*
X408457Y111667D01*
X408540Y112000D01*
X408457Y112333D01*
X408248Y112625D01*
X407957Y112750D01*
X407665Y112667D01*
X407457Y112458D01*
X407373Y112208D01*
Y111792D01*
X407248Y111417D01*
X406998Y111167D01*
X406707Y111083D01*
X406415Y111167D01*
X406207Y111375D01*
X406082Y111708D01*
X406040Y112000D01*
G01Y115017D02*
X406582Y115100D01*
X407040Y115225D01*
X407457Y115392D01*
X407915Y115600D01*
X408540Y115933D01*
Y114267D01*
G01X406040Y118700D02*
X408540D01*
X406748Y117158D01*
Y119242D01*
G01X410373Y104925D02*
X410165Y105258D01*
X410040Y105633D01*
Y105967D01*
X410165Y106300D01*
X410373Y106550D01*
X410665Y106675D01*
X410957Y106592D01*
X411207Y106383D01*
X411373Y106008D01*
X411457Y105508D01*
X411623Y105217D01*
X411915Y105092D01*
X412207Y105175D01*
X412415Y105383D01*
X412540Y105675D01*
Y105967D01*
X412457Y106258D01*
X412248Y106508D01*
G01X412332Y109817D02*
X412457Y109567D01*
X412540Y109275D01*
Y108942D01*
X412415Y108567D01*
X412207Y108275D01*
X411957Y108067D01*
X411540Y107900D01*
X411165Y107858D01*
X410790Y107942D01*
X410540Y108067D01*
X410290Y108317D01*
X410123Y108608D01*
X410040Y108900D01*
Y109192D01*
X410123Y109483D01*
X410248Y109733D01*
X410415Y109942D01*
G01X410040Y112000D02*
X410082Y112292D01*
X410207Y112625D01*
X410415Y112833D01*
X410707Y112917D01*
X410998Y112833D01*
X411248Y112583D01*
X411373Y112208D01*
Y111792D01*
X411457Y111542D01*
X411665Y111333D01*
X411957Y111250D01*
X412248Y111375D01*
X412457Y111667D01*
X412540Y112000D01*
X412457Y112333D01*
X412248Y112625D01*
X411957Y112750D01*
X411665Y112667D01*
X411457Y112458D01*
X411373Y112208D01*
Y111792D01*
X411248Y111417D01*
X410998Y111167D01*
X410707Y111083D01*
X410415Y111167D01*
X410207Y111375D01*
X410082Y111708D01*
X410040Y112000D01*
G01Y115017D02*
X410582Y115100D01*
X411040Y115225D01*
X411457Y115392D01*
X411915Y115600D01*
X412540Y115933D01*
Y114267D01*
G01X410415Y117283D02*
X410207Y117533D01*
X410082Y117825D01*
X410040Y118200D01*
X410123Y118575D01*
X410290Y118867D01*
X410582Y119075D01*
X410915Y119117D01*
X411248Y119033D01*
X411457Y118825D01*
X411623Y118533D01*
X411665Y118242D01*
X411623Y117950D01*
X411457Y117575D01*
X412540Y117700D01*
Y118825D01*
G01X399000Y163000D02*
X442500D01*
Y143000D01*
X440500D01*
Y136500D01*
X406500D01*
Y150000D01*
X404500D01*
Y154500D01*
X397500D01*
G01X410000Y136500D02*
Y129000D01*
X418500D01*
Y98500D01*
X423000Y103000D01*
X414000D01*
X418500Y98500D01*
G01X400833Y131425D02*
X400625Y131758D01*
X400500Y132133D01*
Y132467D01*
X400625Y132800D01*
X400833Y133050D01*
X401125Y133175D01*
X401417Y133092D01*
X401667Y132883D01*
X401833Y132508D01*
X401917Y132008D01*
X402083Y131717D01*
X402375Y131592D01*
X402667Y131675D01*
X402875Y131883D01*
X403000Y132175D01*
Y132467D01*
X402917Y132758D01*
X402708Y133008D01*
G01X402792Y136317D02*
X402917Y136067D01*
X403000Y135775D01*
Y135442D01*
X402875Y135067D01*
X402667Y134775D01*
X402417Y134567D01*
X402000Y134400D01*
X401625Y134358D01*
X401250Y134442D01*
X401000Y134567D01*
X400750Y134817D01*
X400583Y135108D01*
X400500Y135400D01*
Y135692D01*
X400583Y135983D01*
X400708Y136233D01*
X400875Y136442D01*
G01X400792Y137792D02*
X400583Y138083D01*
X400500Y138417D01*
X400583Y138750D01*
X400833Y139042D01*
X401208Y139250D01*
X401583Y139333D01*
X402042D01*
X402417Y139250D01*
X402750Y139042D01*
X402917Y138792D01*
X403000Y138500D01*
X402917Y138167D01*
X402750Y137917D01*
X402500Y137750D01*
X402167Y137667D01*
X401875Y137750D01*
X401583Y137958D01*
X401417Y138208D01*
X401375Y138500D01*
X401458Y138833D01*
X401667Y139083D01*
X402042Y139333D01*
G01X400875Y140683D02*
X400667Y140933D01*
X400542Y141225D01*
X400500Y141600D01*
X400583Y141975D01*
X400750Y142267D01*
X401042Y142475D01*
X401375Y142517D01*
X401708Y142433D01*
X401917Y142225D01*
X402083Y141933D01*
X402125Y141642D01*
X402083Y141350D01*
X401917Y140975D01*
X403000Y141100D01*
Y142225D01*
G01Y144700D02*
X402917Y144367D01*
X402708Y144117D01*
X402458Y143950D01*
X402125Y143825D01*
X401750Y143783D01*
X401375Y143825D01*
X401042Y143950D01*
X400792Y144117D01*
X400583Y144367D01*
X400500Y144700D01*
X400583Y145033D01*
X400792Y145283D01*
X401042Y145450D01*
X401375Y145575D01*
X401750Y145617D01*
X402125Y145575D01*
X402458Y145450D01*
X402708Y145283D01*
X402917Y145033D01*
X403000Y144700D01*
G01X397000Y212000D02*
X442000D01*
Y191500D01*
X444500D01*
Y187000D01*
G01X415429Y234800D02*
X411429D01*
Y242200D01*
G01X404929Y228300D02*
X400929D01*
Y235700D01*
G01X408929Y228300D02*
X404929D01*
Y235700D01*
G01X411300Y223000D02*
Y227000D01*
X418700D01*
G01X407762Y252425D02*
X407554Y252758D01*
X407429Y253133D01*
Y253467D01*
X407554Y253800D01*
X407762Y254050D01*
X408054Y254175D01*
X408346Y254092D01*
X408596Y253883D01*
X408762Y253508D01*
X408846Y253008D01*
X409012Y252717D01*
X409304Y252592D01*
X409596Y252675D01*
X409804Y252883D01*
X409929Y253175D01*
Y253467D01*
X409846Y253758D01*
X409637Y254008D01*
G01X407429Y255567D02*
X409929D01*
Y256608D01*
X409804Y256942D01*
X409637Y257150D01*
X409304Y257233D01*
X408971Y257150D01*
X408762Y256900D01*
X408637Y256608D01*
Y255567D01*
G01Y256608D02*
X407429Y257233D01*
G01X407721Y258792D02*
X407512Y259083D01*
X407429Y259417D01*
X407512Y259750D01*
X407762Y260042D01*
X408137Y260250D01*
X408512Y260333D01*
X408971D01*
X409346Y260250D01*
X409679Y260042D01*
X409846Y259792D01*
X409929Y259500D01*
X409846Y259167D01*
X409679Y258917D01*
X409429Y258750D01*
X409096Y258667D01*
X408804Y258750D01*
X408512Y258958D01*
X408346Y259208D01*
X408304Y259500D01*
X408387Y259833D01*
X408596Y260083D01*
X408971Y260333D01*
G01X409512Y261808D02*
X409762Y262058D01*
X409887Y262350D01*
X409929Y262683D01*
X409846Y263100D01*
X409637Y263392D01*
X409387Y263475D01*
X409137Y263433D01*
X408929Y263267D01*
X408512Y262433D01*
X408221Y262058D01*
X407804Y261808D01*
X407429Y261725D01*
Y263475D01*
G01Y266200D02*
X409929D01*
X408137Y264658D01*
Y266742D01*
G01X399262Y252425D02*
X399054Y252758D01*
X398929Y253133D01*
Y253467D01*
X399054Y253800D01*
X399262Y254050D01*
X399554Y254175D01*
X399846Y254092D01*
X400096Y253883D01*
X400262Y253508D01*
X400346Y253008D01*
X400512Y252717D01*
X400804Y252592D01*
X401096Y252675D01*
X401304Y252883D01*
X401429Y253175D01*
Y253467D01*
X401346Y253758D01*
X401137Y254008D01*
G01X398929Y255567D02*
X401429D01*
Y256608D01*
X401304Y256942D01*
X401137Y257150D01*
X400804Y257233D01*
X400471Y257150D01*
X400262Y256900D01*
X400137Y256608D01*
Y255567D01*
G01Y256608D02*
X398929Y257233D01*
G01Y259500D02*
X398971Y259792D01*
X399096Y260125D01*
X399304Y260333D01*
X399596Y260417D01*
X399887Y260333D01*
X400137Y260083D01*
X400262Y259708D01*
Y259292D01*
X400346Y259042D01*
X400554Y258833D01*
X400846Y258750D01*
X401137Y258875D01*
X401346Y259167D01*
X401429Y259500D01*
X401346Y259833D01*
X401137Y260125D01*
X400846Y260250D01*
X400554Y260167D01*
X400346Y259958D01*
X400262Y259708D01*
Y259292D01*
X400137Y258917D01*
X399887Y258667D01*
X399596Y258583D01*
X399304Y258667D01*
X399096Y258875D01*
X398971Y259208D01*
X398929Y259500D01*
G01X399971Y261808D02*
X400262Y262100D01*
X400429Y262350D01*
X400512Y262683D01*
X400429Y262975D01*
X400262Y263183D01*
X400012Y263350D01*
X399721Y263392D01*
X399471Y263350D01*
X399221Y263183D01*
X399012Y262933D01*
X398929Y262642D01*
X399012Y262308D01*
X399262Y262017D01*
X399637Y261850D01*
X400054Y261808D01*
X400596Y261892D01*
X400887Y262017D01*
X401179Y262225D01*
X401387Y262517D01*
X401429Y262808D01*
X401346Y263100D01*
X401137Y263308D01*
G01X398929Y266200D02*
X401429D01*
X399637Y264658D01*
Y266742D01*
G01X403262Y252425D02*
X403054Y252758D01*
X402929Y253133D01*
Y253467D01*
X403054Y253800D01*
X403262Y254050D01*
X403554Y254175D01*
X403846Y254092D01*
X404096Y253883D01*
X404262Y253508D01*
X404346Y253008D01*
X404512Y252717D01*
X404804Y252592D01*
X405096Y252675D01*
X405304Y252883D01*
X405429Y253175D01*
Y253467D01*
X405346Y253758D01*
X405137Y254008D01*
G01X402929Y255567D02*
X405429D01*
Y256608D01*
X405304Y256942D01*
X405137Y257150D01*
X404804Y257233D01*
X404471Y257150D01*
X404262Y256900D01*
X404137Y256608D01*
Y255567D01*
G01Y256608D02*
X402929Y257233D01*
G01X403971Y258708D02*
X404262Y259000D01*
X404429Y259250D01*
X404512Y259583D01*
X404429Y259875D01*
X404262Y260083D01*
X404012Y260250D01*
X403721Y260292D01*
X403471Y260250D01*
X403221Y260083D01*
X403012Y259833D01*
X402929Y259542D01*
X403012Y259208D01*
X403262Y258917D01*
X403637Y258750D01*
X404054Y258708D01*
X404596Y258792D01*
X404887Y258917D01*
X405179Y259125D01*
X405387Y259417D01*
X405429Y259708D01*
X405346Y260000D01*
X405137Y260208D01*
G01X402929Y262600D02*
X402971Y262892D01*
X403096Y263225D01*
X403304Y263433D01*
X403596Y263517D01*
X403887Y263433D01*
X404137Y263183D01*
X404262Y262808D01*
Y262392D01*
X404346Y262142D01*
X404554Y261933D01*
X404846Y261850D01*
X405137Y261975D01*
X405346Y262267D01*
X405429Y262600D01*
X405346Y262933D01*
X405137Y263225D01*
X404846Y263350D01*
X404554Y263267D01*
X404346Y263058D01*
X404262Y262808D01*
Y262392D01*
X404137Y262017D01*
X403887Y261767D01*
X403596Y261683D01*
X403304Y261767D01*
X403096Y261975D01*
X402971Y262308D01*
X402929Y262600D01*
G01X405012Y264908D02*
X405262Y265158D01*
X405387Y265450D01*
X405429Y265783D01*
X405346Y266200D01*
X405137Y266492D01*
X404887Y266575D01*
X404637Y266533D01*
X404429Y266367D01*
X404012Y265533D01*
X403721Y265158D01*
X403304Y264908D01*
X402929Y264825D01*
Y266575D01*
G01X416575Y246333D02*
X416242Y246125D01*
X415867Y246000D01*
X415533D01*
X415200Y246125D01*
X414950Y246333D01*
X414825Y246625D01*
X414908Y246917D01*
X415117Y247167D01*
X415492Y247333D01*
X415992Y247417D01*
X416283Y247583D01*
X416408Y247875D01*
X416325Y248167D01*
X416117Y248375D01*
X415825Y248500D01*
X415533D01*
X415242Y248417D01*
X414992Y248208D01*
G01X413433Y246000D02*
Y248500D01*
X412392D01*
X412058Y248375D01*
X411850Y248208D01*
X411767Y247875D01*
X411850Y247542D01*
X412100Y247333D01*
X412392Y247208D01*
X413433D01*
G01X412392D02*
X411767Y246000D01*
G01X409583D02*
X409500Y246542D01*
X409375Y247000D01*
X409208Y247417D01*
X409000Y247875D01*
X408667Y248500D01*
X410333D01*
G01X406400D02*
X406733Y248417D01*
X406983Y248208D01*
X407150Y247958D01*
X407275Y247625D01*
X407317Y247250D01*
X407275Y246875D01*
X407150Y246542D01*
X406983Y246292D01*
X406733Y246083D01*
X406400Y246000D01*
X406067Y246083D01*
X405817Y246292D01*
X405650Y246542D01*
X405525Y246875D01*
X405483Y247250D01*
X405525Y247625D01*
X405650Y247958D01*
X405817Y248208D01*
X406067Y248417D01*
X406400Y248500D01*
G01X404217Y246375D02*
X403967Y246167D01*
X403675Y246042D01*
X403300Y246000D01*
X402925Y246083D01*
X402633Y246250D01*
X402425Y246542D01*
X402383Y246875D01*
X402467Y247208D01*
X402675Y247417D01*
X402967Y247583D01*
X403258Y247625D01*
X403550Y247583D01*
X403925Y247417D01*
X403800Y248500D01*
X402675D01*
G01X401438Y302175D02*
X401230Y302508D01*
X401105Y302883D01*
Y303217D01*
X401230Y303550D01*
X401438Y303800D01*
X401730Y303925D01*
X402022Y303842D01*
X402272Y303633D01*
X402438Y303258D01*
X402522Y302758D01*
X402688Y302467D01*
X402980Y302342D01*
X403272Y302425D01*
X403480Y302633D01*
X403605Y302925D01*
Y303217D01*
X403522Y303508D01*
X403313Y303758D01*
G01X403397Y307067D02*
X403522Y306817D01*
X403605Y306525D01*
Y306192D01*
X403480Y305817D01*
X403272Y305525D01*
X403022Y305317D01*
X402605Y305150D01*
X402230Y305108D01*
X401855Y305192D01*
X401605Y305317D01*
X401355Y305567D01*
X401188Y305858D01*
X401105Y306150D01*
Y306442D01*
X401188Y306733D01*
X401313Y306983D01*
X401480Y307192D01*
G01X401105Y309250D02*
X403605D01*
X403105Y308750D01*
G01X401105D02*
Y309750D01*
G01X403188Y311558D02*
X403438Y311808D01*
X403563Y312100D01*
X403605Y312433D01*
X403522Y312850D01*
X403313Y313142D01*
X403063Y313225D01*
X402813Y313183D01*
X402605Y313017D01*
X402188Y312183D01*
X401897Y311808D01*
X401480Y311558D01*
X401105Y311475D01*
Y313225D01*
G01X401605Y314533D02*
X401313Y314783D01*
X401147Y315117D01*
X401105Y315492D01*
X401147Y315825D01*
X401355Y316158D01*
X401605Y316367D01*
X401855Y316408D01*
X402147Y316325D01*
X402355Y316033D01*
X402438Y315742D01*
Y315367D01*
G01Y315742D02*
X402563Y315992D01*
X402772Y316200D01*
X403022Y316283D01*
X403272Y316200D01*
X403480Y315992D01*
X403605Y315617D01*
X403563Y315242D01*
X403397Y314867D01*
G01X403188Y317758D02*
X403438Y318008D01*
X403563Y318300D01*
X403605Y318633D01*
X403522Y319050D01*
X403313Y319342D01*
X403063Y319425D01*
X402813Y319383D01*
X402605Y319217D01*
X402188Y318383D01*
X401897Y318008D01*
X401480Y317758D01*
X401105Y317675D01*
Y319425D01*
G01X406388Y304925D02*
X406180Y305258D01*
X406055Y305633D01*
Y305967D01*
X406180Y306300D01*
X406388Y306550D01*
X406680Y306675D01*
X406972Y306592D01*
X407222Y306383D01*
X407388Y306008D01*
X407472Y305508D01*
X407638Y305217D01*
X407930Y305092D01*
X408222Y305175D01*
X408430Y305383D01*
X408555Y305675D01*
Y305967D01*
X408472Y306258D01*
X408263Y306508D01*
G01X406055Y308067D02*
X408555D01*
Y309108D01*
X408430Y309442D01*
X408263Y309650D01*
X407930Y309733D01*
X407597Y309650D01*
X407388Y309400D01*
X407263Y309108D01*
Y308067D01*
G01Y309108D02*
X406055Y309733D01*
G01Y311917D02*
X406597Y312000D01*
X407055Y312125D01*
X407472Y312292D01*
X407930Y312500D01*
X408555Y312833D01*
Y311167D01*
G01X406347Y314392D02*
X406138Y314683D01*
X406055Y315017D01*
X406138Y315350D01*
X406388Y315642D01*
X406763Y315850D01*
X407138Y315933D01*
X407597D01*
X407972Y315850D01*
X408305Y315642D01*
X408472Y315392D01*
X408555Y315100D01*
X408472Y314767D01*
X408305Y314517D01*
X408055Y314350D01*
X407722Y314267D01*
X407430Y314350D01*
X407138Y314558D01*
X406972Y314808D01*
X406930Y315100D01*
X407013Y315433D01*
X407222Y315683D01*
X407597Y315933D01*
G01X406055Y318700D02*
X408555D01*
X406763Y317158D01*
Y319242D01*
G01X428680Y331833D02*
X428347Y331625D01*
X427972Y331500D01*
X427638D01*
X427305Y331625D01*
X427055Y331833D01*
X426930Y332125D01*
X427013Y332417D01*
X427222Y332667D01*
X427597Y332833D01*
X428097Y332917D01*
X428388Y333083D01*
X428513Y333375D01*
X428430Y333667D01*
X428222Y333875D01*
X427930Y334000D01*
X427638D01*
X427347Y333917D01*
X427097Y333708D01*
G01X424705Y334000D02*
Y331500D01*
G01X425663Y334000D02*
X423747D01*
G01X422438Y331500D02*
Y334000D01*
X421438D01*
X421105Y333875D01*
X420855Y333583D01*
X420772Y333250D01*
X420855Y332917D01*
X421063Y332667D01*
X421438Y332542D01*
X422438D01*
G01X418505Y331500D02*
Y334000D01*
X419005Y333500D01*
G01Y331500D02*
X418005D01*
G01X415405Y334000D02*
X415738Y333917D01*
X415988Y333708D01*
X416155Y333458D01*
X416280Y333125D01*
X416322Y332750D01*
X416280Y332375D01*
X416155Y332042D01*
X415988Y331792D01*
X415738Y331583D01*
X415405Y331500D01*
X415072Y331583D01*
X414822Y331792D01*
X414655Y332042D01*
X414530Y332375D01*
X414488Y332750D01*
X414530Y333125D01*
X414655Y333458D01*
X414822Y333708D01*
X415072Y333917D01*
X415405Y334000D01*
G01X412305Y331500D02*
Y334000D01*
X412805Y333500D01*
G01Y331500D02*
X411805D01*
G01X404555Y328700D02*
X408555D01*
Y321300D01*
G01X429680Y349833D02*
X429347Y349625D01*
X428972Y349500D01*
X428638D01*
X428305Y349625D01*
X428055Y349833D01*
X427930Y350125D01*
X428013Y350417D01*
X428222Y350667D01*
X428597Y350833D01*
X429097Y350917D01*
X429388Y351083D01*
X429513Y351375D01*
X429430Y351667D01*
X429222Y351875D01*
X428930Y352000D01*
X428638D01*
X428347Y351917D01*
X428097Y351708D01*
G01X424788Y351792D02*
X425038Y351917D01*
X425330Y352000D01*
X425663D01*
X426038Y351875D01*
X426330Y351667D01*
X426538Y351417D01*
X426705Y351000D01*
X426747Y350625D01*
X426663Y350250D01*
X426538Y350000D01*
X426288Y349750D01*
X425997Y349583D01*
X425705Y349500D01*
X425413D01*
X425122Y349583D01*
X424872Y349708D01*
X424663Y349875D01*
G01X422605Y349500D02*
Y352000D01*
X423105Y351500D01*
G01Y349500D02*
X422105D01*
G01X420297Y351583D02*
X420047Y351833D01*
X419755Y351958D01*
X419422Y352000D01*
X419005Y351917D01*
X418713Y351708D01*
X418630Y351458D01*
X418672Y351208D01*
X418838Y351000D01*
X419672Y350583D01*
X420047Y350292D01*
X420297Y349875D01*
X420380Y349500D01*
X418630D01*
G01X417197Y351583D02*
X416947Y351833D01*
X416655Y351958D01*
X416322Y352000D01*
X415905Y351917D01*
X415613Y351708D01*
X415530Y351458D01*
X415572Y351208D01*
X415738Y351000D01*
X416572Y350583D01*
X416947Y350292D01*
X417197Y349875D01*
X417280Y349500D01*
X415530D01*
G01X414222Y349875D02*
X413972Y349667D01*
X413680Y349542D01*
X413305Y349500D01*
X412930Y349583D01*
X412638Y349750D01*
X412430Y350042D01*
X412388Y350375D01*
X412472Y350708D01*
X412680Y350917D01*
X412972Y351083D01*
X413263Y351125D01*
X413555Y351083D01*
X413930Y350917D01*
X413805Y352000D01*
X412680D01*
G01X424680Y366333D02*
X424347Y366125D01*
X423972Y366000D01*
X423638D01*
X423305Y366125D01*
X423055Y366333D01*
X422930Y366625D01*
X423013Y366917D01*
X423222Y367167D01*
X423597Y367333D01*
X424097Y367417D01*
X424388Y367583D01*
X424513Y367875D01*
X424430Y368167D01*
X424222Y368375D01*
X423930Y368500D01*
X423638D01*
X423347Y368417D01*
X423097Y368208D01*
G01X419788Y368292D02*
X420038Y368417D01*
X420330Y368500D01*
X420663D01*
X421038Y368375D01*
X421330Y368167D01*
X421538Y367917D01*
X421705Y367500D01*
X421747Y367125D01*
X421663Y366750D01*
X421538Y366500D01*
X421288Y366250D01*
X420997Y366083D01*
X420705Y366000D01*
X420413D01*
X420122Y366083D01*
X419872Y366208D01*
X419663Y366375D01*
G01X417605Y366000D02*
Y368500D01*
X418105Y368000D01*
G01Y366000D02*
X417105D01*
G01X415297Y368083D02*
X415047Y368333D01*
X414755Y368458D01*
X414422Y368500D01*
X414005Y368417D01*
X413713Y368208D01*
X413630Y367958D01*
X413672Y367708D01*
X413838Y367500D01*
X414672Y367083D01*
X415047Y366792D01*
X415297Y366375D01*
X415380Y366000D01*
X413630D01*
G01X411405D02*
Y368500D01*
X411905Y368000D01*
G01Y366000D02*
X410905D01*
G01X409222Y366500D02*
X408972Y366208D01*
X408638Y366042D01*
X408263Y366000D01*
X407930Y366042D01*
X407597Y366250D01*
X407388Y366500D01*
X407347Y366750D01*
X407430Y367042D01*
X407722Y367250D01*
X408013Y367333D01*
X408388D01*
G01X408013D02*
X407763Y367458D01*
X407555Y367667D01*
X407472Y367917D01*
X407555Y368167D01*
X407763Y368375D01*
X408138Y368500D01*
X408513Y368458D01*
X408888Y368292D01*
G01X405388Y383425D02*
X405180Y383758D01*
X405055Y384133D01*
Y384467D01*
X405180Y384800D01*
X405388Y385050D01*
X405680Y385175D01*
X405972Y385092D01*
X406222Y384883D01*
X406388Y384508D01*
X406472Y384008D01*
X406638Y383717D01*
X406930Y383592D01*
X407222Y383675D01*
X407430Y383883D01*
X407555Y384175D01*
Y384467D01*
X407472Y384758D01*
X407263Y385008D01*
G01X407555Y387400D02*
X405055D01*
G01X407555Y386442D02*
Y388358D01*
G01X405055Y389667D02*
X407555D01*
Y390667D01*
X407430Y391000D01*
X407138Y391250D01*
X406805Y391333D01*
X406472Y391250D01*
X406222Y391042D01*
X406097Y390667D01*
Y389667D01*
G01X405055Y393600D02*
X405097Y393892D01*
X405222Y394225D01*
X405430Y394433D01*
X405722Y394517D01*
X406013Y394433D01*
X406263Y394183D01*
X406388Y393808D01*
Y393392D01*
X406472Y393142D01*
X406680Y392933D01*
X406972Y392850D01*
X407263Y392975D01*
X407472Y393267D01*
X407555Y393600D01*
X407472Y393933D01*
X407263Y394225D01*
X406972Y394350D01*
X406680Y394267D01*
X406472Y394058D01*
X406388Y393808D01*
Y393392D01*
X406263Y393017D01*
X406013Y392767D01*
X405722Y392683D01*
X405430Y392767D01*
X405222Y392975D01*
X405097Y393308D01*
X405055Y393600D01*
G01X407138Y395908D02*
X407388Y396158D01*
X407513Y396450D01*
X407555Y396783D01*
X407472Y397200D01*
X407263Y397492D01*
X407013Y397575D01*
X406763Y397533D01*
X406555Y397367D01*
X406138Y396533D01*
X405847Y396158D01*
X405430Y395908D01*
X405055Y395825D01*
Y397575D01*
G01X400388Y386425D02*
X400180Y386758D01*
X400055Y387133D01*
Y387467D01*
X400180Y387800D01*
X400388Y388050D01*
X400680Y388175D01*
X400972Y388092D01*
X401222Y387883D01*
X401388Y387508D01*
X401472Y387008D01*
X401638Y386717D01*
X401930Y386592D01*
X402222Y386675D01*
X402430Y386883D01*
X402555Y387175D01*
Y387467D01*
X402472Y387758D01*
X402263Y388008D01*
G01X402555Y390400D02*
X400055D01*
G01X402555Y389442D02*
Y391358D01*
G01X400055Y392667D02*
X402555D01*
Y393667D01*
X402430Y394000D01*
X402138Y394250D01*
X401805Y394333D01*
X401472Y394250D01*
X401222Y394042D01*
X401097Y393667D01*
Y392667D01*
G01X400055Y396600D02*
X400097Y396892D01*
X400222Y397225D01*
X400430Y397433D01*
X400722Y397517D01*
X401013Y397433D01*
X401263Y397183D01*
X401388Y396808D01*
Y396392D01*
X401472Y396142D01*
X401680Y395933D01*
X401972Y395850D01*
X402263Y395975D01*
X402472Y396267D01*
X402555Y396600D01*
X402472Y396933D01*
X402263Y397225D01*
X401972Y397350D01*
X401680Y397267D01*
X401472Y397058D01*
X401388Y396808D01*
Y396392D01*
X401263Y396017D01*
X401013Y395767D01*
X400722Y395683D01*
X400430Y395767D01*
X400222Y395975D01*
X400097Y396308D01*
X400055Y396600D01*
G01X401097Y398908D02*
X401388Y399200D01*
X401555Y399450D01*
X401638Y399783D01*
X401555Y400075D01*
X401388Y400283D01*
X401138Y400450D01*
X400847Y400492D01*
X400597Y400450D01*
X400347Y400283D01*
X400138Y400033D01*
X400055Y399742D01*
X400138Y399408D01*
X400388Y399117D01*
X400763Y398950D01*
X401180Y398908D01*
X401722Y398992D01*
X402013Y399117D01*
X402305Y399325D01*
X402513Y399617D01*
X402555Y399908D01*
X402472Y400200D01*
X402263Y400408D01*
G01X411630Y406333D02*
X411297Y406125D01*
X410922Y406000D01*
X410588D01*
X410255Y406125D01*
X410005Y406333D01*
X409880Y406625D01*
X409963Y406917D01*
X410172Y407167D01*
X410547Y407333D01*
X411047Y407417D01*
X411338Y407583D01*
X411463Y407875D01*
X411380Y408167D01*
X411172Y408375D01*
X410880Y408500D01*
X410588D01*
X410297Y408417D01*
X410047Y408208D01*
G01X407655Y408500D02*
Y406000D01*
G01X408613Y408500D02*
X406697D01*
G01X405388Y406000D02*
Y408500D01*
X404388D01*
X404055Y408375D01*
X403805Y408083D01*
X403722Y407750D01*
X403805Y407417D01*
X404013Y407167D01*
X404388Y407042D01*
X405388D01*
G01X402163Y406292D02*
X401872Y406083D01*
X401538Y406000D01*
X401205Y406083D01*
X400913Y406333D01*
X400705Y406708D01*
X400622Y407083D01*
Y407542D01*
X400705Y407917D01*
X400913Y408250D01*
X401163Y408417D01*
X401455Y408500D01*
X401788Y408417D01*
X402038Y408250D01*
X402205Y408000D01*
X402288Y407667D01*
X402205Y407375D01*
X401997Y407083D01*
X401747Y406917D01*
X401455Y406875D01*
X401122Y406958D01*
X400872Y407167D01*
X400622Y407542D01*
G01X398355Y408500D02*
X398688Y408417D01*
X398938Y408208D01*
X399105Y407958D01*
X399230Y407625D01*
X399272Y407250D01*
X399230Y406875D01*
X399105Y406542D01*
X398938Y406292D01*
X398688Y406083D01*
X398355Y406000D01*
X398022Y406083D01*
X397772Y406292D01*
X397605Y406542D01*
X397480Y406875D01*
X397438Y407250D01*
X397480Y407625D01*
X397605Y407958D01*
X397772Y408208D01*
X398022Y408417D01*
X398355Y408500D01*
G01X416630Y431833D02*
X416297Y431625D01*
X415922Y431500D01*
X415588D01*
X415255Y431625D01*
X415005Y431833D01*
X414880Y432125D01*
X414963Y432417D01*
X415172Y432667D01*
X415547Y432833D01*
X416047Y432917D01*
X416338Y433083D01*
X416463Y433375D01*
X416380Y433667D01*
X416172Y433875D01*
X415880Y434000D01*
X415588D01*
X415297Y433917D01*
X415047Y433708D01*
G01X413488Y431500D02*
Y434000D01*
X412447D01*
X412113Y433875D01*
X411905Y433708D01*
X411822Y433375D01*
X411905Y433042D01*
X412155Y432833D01*
X412447Y432708D01*
X413488D01*
G01X412447D02*
X411822Y431500D01*
G01X409638D02*
X409555Y432042D01*
X409430Y432500D01*
X409263Y432917D01*
X409055Y433375D01*
X408722Y434000D01*
X410388D01*
G01X405955Y431500D02*
Y434000D01*
X407497Y432208D01*
X405413D01*
G01X404147Y432542D02*
X403855Y432833D01*
X403605Y433000D01*
X403272Y433083D01*
X402980Y433000D01*
X402772Y432833D01*
X402605Y432583D01*
X402563Y432292D01*
X402605Y432042D01*
X402772Y431792D01*
X403022Y431583D01*
X403313Y431500D01*
X403647Y431583D01*
X403938Y431833D01*
X404105Y432208D01*
X404147Y432625D01*
X404063Y433167D01*
X403938Y433458D01*
X403730Y433750D01*
X403438Y433958D01*
X403147Y434000D01*
X402855Y433917D01*
X402647Y433708D01*
G01X401555Y429300D02*
X397555D01*
Y436700D01*
G01X419680Y441833D02*
X419347Y441625D01*
X418972Y441500D01*
X418638D01*
X418305Y441625D01*
X418055Y441833D01*
X417930Y442125D01*
X418013Y442417D01*
X418222Y442667D01*
X418597Y442833D01*
X419097Y442917D01*
X419388Y443083D01*
X419513Y443375D01*
X419430Y443667D01*
X419222Y443875D01*
X418930Y444000D01*
X418638D01*
X418347Y443917D01*
X418097Y443708D01*
G01X414788Y443792D02*
X415038Y443917D01*
X415330Y444000D01*
X415663D01*
X416038Y443875D01*
X416330Y443667D01*
X416538Y443417D01*
X416705Y443000D01*
X416747Y442625D01*
X416663Y442250D01*
X416538Y442000D01*
X416288Y441750D01*
X415997Y441583D01*
X415705Y441500D01*
X415413D01*
X415122Y441583D01*
X414872Y441708D01*
X414663Y441875D01*
G01X412605Y441500D02*
Y444000D01*
X413105Y443500D01*
G01Y441500D02*
X412105D01*
G01X410297Y443583D02*
X410047Y443833D01*
X409755Y443958D01*
X409422Y444000D01*
X409005Y443917D01*
X408713Y443708D01*
X408630Y443458D01*
X408672Y443208D01*
X408838Y443000D01*
X409672Y442583D01*
X410047Y442292D01*
X410297Y441875D01*
X410380Y441500D01*
X408630D01*
G01X407197Y443583D02*
X406947Y443833D01*
X406655Y443958D01*
X406322Y444000D01*
X405905Y443917D01*
X405613Y443708D01*
X405530Y443458D01*
X405572Y443208D01*
X405738Y443000D01*
X406572Y442583D01*
X406947Y442292D01*
X407197Y441875D01*
X407280Y441500D01*
X405530D01*
G01X402805D02*
Y444000D01*
X404347Y442208D01*
X402263D01*
G01X415853Y827833D02*
X415520Y827625D01*
X415145Y827500D01*
X414811D01*
X414478Y827625D01*
X414228Y827833D01*
X414103Y828125D01*
X414186Y828417D01*
X414395Y828667D01*
X414770Y828833D01*
X415270Y828917D01*
X415561Y829083D01*
X415686Y829375D01*
X415603Y829667D01*
X415395Y829875D01*
X415103Y830000D01*
X414811D01*
X414520Y829917D01*
X414270Y829708D01*
G01X412711Y827500D02*
Y830000D01*
X411670D01*
X411336Y829875D01*
X411128Y829708D01*
X411045Y829375D01*
X411128Y829042D01*
X411378Y828833D01*
X411670Y828708D01*
X412711D01*
G01X411670D02*
X411045Y827500D01*
G01X409486Y827792D02*
X409195Y827583D01*
X408861Y827500D01*
X408528Y827583D01*
X408236Y827833D01*
X408028Y828208D01*
X407945Y828583D01*
Y829042D01*
X408028Y829417D01*
X408236Y829750D01*
X408486Y829917D01*
X408778Y830000D01*
X409111Y829917D01*
X409361Y829750D01*
X409528Y829500D01*
X409611Y829167D01*
X409528Y828875D01*
X409320Y828583D01*
X409070Y828417D01*
X408778Y828375D01*
X408445Y828458D01*
X408195Y828667D01*
X407945Y829042D01*
G01X405678Y830000D02*
X406011Y829917D01*
X406261Y829708D01*
X406428Y829458D01*
X406553Y829125D01*
X406595Y828750D01*
X406553Y828375D01*
X406428Y828042D01*
X406261Y827792D01*
X406011Y827583D01*
X405678Y827500D01*
X405345Y827583D01*
X405095Y827792D01*
X404928Y828042D01*
X404803Y828375D01*
X404761Y828750D01*
X404803Y829125D01*
X404928Y829458D01*
X405095Y829708D01*
X405345Y829917D01*
X405678Y830000D01*
G01X402578Y827500D02*
X402286Y827542D01*
X401953Y827667D01*
X401745Y827875D01*
X401661Y828167D01*
X401745Y828458D01*
X401995Y828708D01*
X402370Y828833D01*
X402786D01*
X403036Y828917D01*
X403245Y829125D01*
X403328Y829417D01*
X403203Y829708D01*
X402911Y829917D01*
X402578Y830000D01*
X402245Y829917D01*
X401953Y829708D01*
X401828Y829417D01*
X401911Y829125D01*
X402120Y828917D01*
X402370Y828833D01*
X402786D01*
X403161Y828708D01*
X403411Y828458D01*
X403495Y828167D01*
X403411Y827875D01*
X403203Y827667D01*
X402870Y827542D01*
X402578Y827500D01*
G01X417403Y823833D02*
X417070Y823625D01*
X416695Y823500D01*
X416361D01*
X416028Y823625D01*
X415778Y823833D01*
X415653Y824125D01*
X415736Y824417D01*
X415945Y824667D01*
X416320Y824833D01*
X416820Y824917D01*
X417111Y825083D01*
X417236Y825375D01*
X417153Y825667D01*
X416945Y825875D01*
X416653Y826000D01*
X416361D01*
X416070Y825917D01*
X415820Y825708D01*
G01X412511Y825792D02*
X412761Y825917D01*
X413053Y826000D01*
X413386D01*
X413761Y825875D01*
X414053Y825667D01*
X414261Y825417D01*
X414428Y825000D01*
X414470Y824625D01*
X414386Y824250D01*
X414261Y824000D01*
X414011Y823750D01*
X413720Y823583D01*
X413428Y823500D01*
X413136D01*
X412845Y823583D01*
X412595Y823708D01*
X412386Y823875D01*
G01X410328Y823500D02*
Y826000D01*
X410828Y825500D01*
G01Y823500D02*
X409828D01*
G01X408020Y825583D02*
X407770Y825833D01*
X407478Y825958D01*
X407145Y826000D01*
X406728Y825917D01*
X406436Y825708D01*
X406353Y825458D01*
X406395Y825208D01*
X406561Y825000D01*
X407395Y824583D01*
X407770Y824292D01*
X408020Y823875D01*
X408103Y823500D01*
X406353D01*
G01X404128D02*
X403836Y823542D01*
X403503Y823667D01*
X403295Y823875D01*
X403211Y824167D01*
X403295Y824458D01*
X403545Y824708D01*
X403920Y824833D01*
X404336D01*
X404586Y824917D01*
X404795Y825125D01*
X404878Y825417D01*
X404753Y825708D01*
X404461Y825917D01*
X404128Y826000D01*
X403795Y825917D01*
X403503Y825708D01*
X403378Y825417D01*
X403461Y825125D01*
X403670Y824917D01*
X403920Y824833D01*
X404336D01*
X404711Y824708D01*
X404961Y824458D01*
X405045Y824167D01*
X404961Y823875D01*
X404753Y823667D01*
X404420Y823542D01*
X404128Y823500D01*
G01X401736Y823792D02*
X401445Y823583D01*
X401111Y823500D01*
X400778Y823583D01*
X400486Y823833D01*
X400278Y824208D01*
X400195Y824583D01*
Y825042D01*
X400278Y825417D01*
X400486Y825750D01*
X400736Y825917D01*
X401028Y826000D01*
X401361Y825917D01*
X401611Y825750D01*
X401778Y825500D01*
X401861Y825167D01*
X401778Y824875D01*
X401570Y824583D01*
X401320Y824417D01*
X401028Y824375D01*
X400695Y824458D01*
X400445Y824667D01*
X400195Y825042D01*
G01X415853Y845833D02*
X415520Y845625D01*
X415145Y845500D01*
X414811D01*
X414478Y845625D01*
X414228Y845833D01*
X414103Y846125D01*
X414186Y846417D01*
X414395Y846667D01*
X414770Y846833D01*
X415270Y846917D01*
X415561Y847083D01*
X415686Y847375D01*
X415603Y847667D01*
X415395Y847875D01*
X415103Y848000D01*
X414811D01*
X414520Y847917D01*
X414270Y847708D01*
G01X412711Y845500D02*
Y848000D01*
X411670D01*
X411336Y847875D01*
X411128Y847708D01*
X411045Y847375D01*
X411128Y847042D01*
X411378Y846833D01*
X411670Y846708D01*
X412711D01*
G01X411670D02*
X411045Y845500D01*
G01X409486Y845792D02*
X409195Y845583D01*
X408861Y845500D01*
X408528Y845583D01*
X408236Y845833D01*
X408028Y846208D01*
X407945Y846583D01*
Y847042D01*
X408028Y847417D01*
X408236Y847750D01*
X408486Y847917D01*
X408778Y848000D01*
X409111Y847917D01*
X409361Y847750D01*
X409528Y847500D01*
X409611Y847167D01*
X409528Y846875D01*
X409320Y846583D01*
X409070Y846417D01*
X408778Y846375D01*
X408445Y846458D01*
X408195Y846667D01*
X407945Y847042D01*
G01X405678Y848000D02*
X406011Y847917D01*
X406261Y847708D01*
X406428Y847458D01*
X406553Y847125D01*
X406595Y846750D01*
X406553Y846375D01*
X406428Y846042D01*
X406261Y845792D01*
X406011Y845583D01*
X405678Y845500D01*
X405345Y845583D01*
X405095Y845792D01*
X404928Y846042D01*
X404803Y846375D01*
X404761Y846750D01*
X404803Y847125D01*
X404928Y847458D01*
X405095Y847708D01*
X405345Y847917D01*
X405678Y848000D01*
G01X402578D02*
X402911Y847917D01*
X403161Y847708D01*
X403328Y847458D01*
X403453Y847125D01*
X403495Y846750D01*
X403453Y846375D01*
X403328Y846042D01*
X403161Y845792D01*
X402911Y845583D01*
X402578Y845500D01*
X402245Y845583D01*
X401995Y845792D01*
X401828Y846042D01*
X401703Y846375D01*
X401661Y846750D01*
X401703Y847125D01*
X401828Y847458D01*
X401995Y847708D01*
X402245Y847917D01*
X402578Y848000D01*
G01X415853Y836833D02*
X415520Y836625D01*
X415145Y836500D01*
X414811D01*
X414478Y836625D01*
X414228Y836833D01*
X414103Y837125D01*
X414186Y837417D01*
X414395Y837667D01*
X414770Y837833D01*
X415270Y837917D01*
X415561Y838083D01*
X415686Y838375D01*
X415603Y838667D01*
X415395Y838875D01*
X415103Y839000D01*
X414811D01*
X414520Y838917D01*
X414270Y838708D01*
G01X412711Y836500D02*
Y839000D01*
X411670D01*
X411336Y838875D01*
X411128Y838708D01*
X411045Y838375D01*
X411128Y838042D01*
X411378Y837833D01*
X411670Y837708D01*
X412711D01*
G01X411670D02*
X411045Y836500D01*
G01X409486Y836792D02*
X409195Y836583D01*
X408861Y836500D01*
X408528Y836583D01*
X408236Y836833D01*
X408028Y837208D01*
X407945Y837583D01*
Y838042D01*
X408028Y838417D01*
X408236Y838750D01*
X408486Y838917D01*
X408778Y839000D01*
X409111Y838917D01*
X409361Y838750D01*
X409528Y838500D01*
X409611Y838167D01*
X409528Y837875D01*
X409320Y837583D01*
X409070Y837417D01*
X408778Y837375D01*
X408445Y837458D01*
X408195Y837667D01*
X407945Y838042D01*
G01X405678Y839000D02*
X406011Y838917D01*
X406261Y838708D01*
X406428Y838458D01*
X406553Y838125D01*
X406595Y837750D01*
X406553Y837375D01*
X406428Y837042D01*
X406261Y836792D01*
X406011Y836583D01*
X405678Y836500D01*
X405345Y836583D01*
X405095Y836792D01*
X404928Y837042D01*
X404803Y837375D01*
X404761Y837750D01*
X404803Y838125D01*
X404928Y838458D01*
X405095Y838708D01*
X405345Y838917D01*
X405678Y839000D01*
G01X403370Y838583D02*
X403120Y838833D01*
X402828Y838958D01*
X402495Y839000D01*
X402078Y838917D01*
X401786Y838708D01*
X401703Y838458D01*
X401745Y838208D01*
X401911Y838000D01*
X402745Y837583D01*
X403120Y837292D01*
X403370Y836875D01*
X403453Y836500D01*
X401703D01*
G01X415853Y841333D02*
X415520Y841125D01*
X415145Y841000D01*
X414811D01*
X414478Y841125D01*
X414228Y841333D01*
X414103Y841625D01*
X414186Y841917D01*
X414395Y842167D01*
X414770Y842333D01*
X415270Y842417D01*
X415561Y842583D01*
X415686Y842875D01*
X415603Y843167D01*
X415395Y843375D01*
X415103Y843500D01*
X414811D01*
X414520Y843417D01*
X414270Y843208D01*
G01X412711Y841000D02*
Y843500D01*
X411670D01*
X411336Y843375D01*
X411128Y843208D01*
X411045Y842875D01*
X411128Y842542D01*
X411378Y842333D01*
X411670Y842208D01*
X412711D01*
G01X411670D02*
X411045Y841000D01*
G01X409486Y841292D02*
X409195Y841083D01*
X408861Y841000D01*
X408528Y841083D01*
X408236Y841333D01*
X408028Y841708D01*
X407945Y842083D01*
Y842542D01*
X408028Y842917D01*
X408236Y843250D01*
X408486Y843417D01*
X408778Y843500D01*
X409111Y843417D01*
X409361Y843250D01*
X409528Y843000D01*
X409611Y842667D01*
X409528Y842375D01*
X409320Y842083D01*
X409070Y841917D01*
X408778Y841875D01*
X408445Y841958D01*
X408195Y842167D01*
X407945Y842542D01*
G01X405678Y843500D02*
X406011Y843417D01*
X406261Y843208D01*
X406428Y842958D01*
X406553Y842625D01*
X406595Y842250D01*
X406553Y841875D01*
X406428Y841542D01*
X406261Y841292D01*
X406011Y841083D01*
X405678Y841000D01*
X405345Y841083D01*
X405095Y841292D01*
X404928Y841542D01*
X404803Y841875D01*
X404761Y842250D01*
X404803Y842625D01*
X404928Y842958D01*
X405095Y843208D01*
X405345Y843417D01*
X405678Y843500D01*
G01X403370Y842042D02*
X403078Y842333D01*
X402828Y842500D01*
X402495Y842583D01*
X402203Y842500D01*
X401995Y842333D01*
X401828Y842083D01*
X401786Y841792D01*
X401828Y841542D01*
X401995Y841292D01*
X402245Y841083D01*
X402536Y841000D01*
X402870Y841083D01*
X403161Y841333D01*
X403328Y841708D01*
X403370Y842125D01*
X403286Y842667D01*
X403161Y842958D01*
X402953Y843250D01*
X402661Y843458D01*
X402370Y843500D01*
X402078Y843417D01*
X401870Y843208D01*
G01X415853Y832333D02*
X415520Y832125D01*
X415145Y832000D01*
X414811D01*
X414478Y832125D01*
X414228Y832333D01*
X414103Y832625D01*
X414186Y832917D01*
X414395Y833167D01*
X414770Y833333D01*
X415270Y833417D01*
X415561Y833583D01*
X415686Y833875D01*
X415603Y834167D01*
X415395Y834375D01*
X415103Y834500D01*
X414811D01*
X414520Y834417D01*
X414270Y834208D01*
G01X412711Y832000D02*
Y834500D01*
X411670D01*
X411336Y834375D01*
X411128Y834208D01*
X411045Y833875D01*
X411128Y833542D01*
X411378Y833333D01*
X411670Y833208D01*
X412711D01*
G01X411670D02*
X411045Y832000D01*
G01X409486Y832292D02*
X409195Y832083D01*
X408861Y832000D01*
X408528Y832083D01*
X408236Y832333D01*
X408028Y832708D01*
X407945Y833083D01*
Y833542D01*
X408028Y833917D01*
X408236Y834250D01*
X408486Y834417D01*
X408778Y834500D01*
X409111Y834417D01*
X409361Y834250D01*
X409528Y834000D01*
X409611Y833667D01*
X409528Y833375D01*
X409320Y833083D01*
X409070Y832917D01*
X408778Y832875D01*
X408445Y832958D01*
X408195Y833167D01*
X407945Y833542D01*
G01X405678Y834500D02*
X406011Y834417D01*
X406261Y834208D01*
X406428Y833958D01*
X406553Y833625D01*
X406595Y833250D01*
X406553Y832875D01*
X406428Y832542D01*
X406261Y832292D01*
X406011Y832083D01*
X405678Y832000D01*
X405345Y832083D01*
X405095Y832292D01*
X404928Y832542D01*
X404803Y832875D01*
X404761Y833250D01*
X404803Y833625D01*
X404928Y833958D01*
X405095Y834208D01*
X405345Y834417D01*
X405678Y834500D01*
G01X402661Y832000D02*
X402578Y832542D01*
X402453Y833000D01*
X402286Y833417D01*
X402078Y833875D01*
X401745Y834500D01*
X403411D01*
G01X415853Y850333D02*
X415520Y850125D01*
X415145Y850000D01*
X414811D01*
X414478Y850125D01*
X414228Y850333D01*
X414103Y850625D01*
X414186Y850917D01*
X414395Y851167D01*
X414770Y851333D01*
X415270Y851417D01*
X415561Y851583D01*
X415686Y851875D01*
X415603Y852167D01*
X415395Y852375D01*
X415103Y852500D01*
X414811D01*
X414520Y852417D01*
X414270Y852208D01*
G01X412711Y850000D02*
Y852500D01*
X411670D01*
X411336Y852375D01*
X411128Y852208D01*
X411045Y851875D01*
X411128Y851542D01*
X411378Y851333D01*
X411670Y851208D01*
X412711D01*
G01X411670D02*
X411045Y850000D01*
G01X409486Y850292D02*
X409195Y850083D01*
X408861Y850000D01*
X408528Y850083D01*
X408236Y850333D01*
X408028Y850708D01*
X407945Y851083D01*
Y851542D01*
X408028Y851917D01*
X408236Y852250D01*
X408486Y852417D01*
X408778Y852500D01*
X409111Y852417D01*
X409361Y852250D01*
X409528Y852000D01*
X409611Y851667D01*
X409528Y851375D01*
X409320Y851083D01*
X409070Y850917D01*
X408778Y850875D01*
X408445Y850958D01*
X408195Y851167D01*
X407945Y851542D01*
G01X405678Y852500D02*
X406011Y852417D01*
X406261Y852208D01*
X406428Y851958D01*
X406553Y851625D01*
X406595Y851250D01*
X406553Y850875D01*
X406428Y850542D01*
X406261Y850292D01*
X406011Y850083D01*
X405678Y850000D01*
X405345Y850083D01*
X405095Y850292D01*
X404928Y850542D01*
X404803Y850875D01*
X404761Y851250D01*
X404803Y851625D01*
X404928Y851958D01*
X405095Y852208D01*
X405345Y852417D01*
X405678Y852500D01*
G01X402578Y850000D02*
Y852500D01*
X403078Y852000D01*
G01Y850000D02*
X402078D01*
G01X415853Y859333D02*
X415520Y859125D01*
X415145Y859000D01*
X414811D01*
X414478Y859125D01*
X414228Y859333D01*
X414103Y859625D01*
X414186Y859917D01*
X414395Y860167D01*
X414770Y860333D01*
X415270Y860417D01*
X415561Y860583D01*
X415686Y860875D01*
X415603Y861167D01*
X415395Y861375D01*
X415103Y861500D01*
X414811D01*
X414520Y861417D01*
X414270Y861208D01*
G01X412711Y859000D02*
Y861500D01*
X411670D01*
X411336Y861375D01*
X411128Y861208D01*
X411045Y860875D01*
X411128Y860542D01*
X411378Y860333D01*
X411670Y860208D01*
X412711D01*
G01X411670D02*
X411045Y859000D01*
G01X409486Y859292D02*
X409195Y859083D01*
X408861Y859000D01*
X408528Y859083D01*
X408236Y859333D01*
X408028Y859708D01*
X407945Y860083D01*
Y860542D01*
X408028Y860917D01*
X408236Y861250D01*
X408486Y861417D01*
X408778Y861500D01*
X409111Y861417D01*
X409361Y861250D01*
X409528Y861000D01*
X409611Y860667D01*
X409528Y860375D01*
X409320Y860083D01*
X409070Y859917D01*
X408778Y859875D01*
X408445Y859958D01*
X408195Y860167D01*
X407945Y860542D01*
G01X405678Y859000D02*
Y861500D01*
X406178Y861000D01*
G01Y859000D02*
X405178D01*
G01X403370Y861083D02*
X403120Y861333D01*
X402828Y861458D01*
X402495Y861500D01*
X402078Y861417D01*
X401786Y861208D01*
X401703Y860958D01*
X401745Y860708D01*
X401911Y860500D01*
X402745Y860083D01*
X403120Y859792D01*
X403370Y859375D01*
X403453Y859000D01*
X401703D01*
G01X415853Y854833D02*
X415520Y854625D01*
X415145Y854500D01*
X414811D01*
X414478Y854625D01*
X414228Y854833D01*
X414103Y855125D01*
X414186Y855417D01*
X414395Y855667D01*
X414770Y855833D01*
X415270Y855917D01*
X415561Y856083D01*
X415686Y856375D01*
X415603Y856667D01*
X415395Y856875D01*
X415103Y857000D01*
X414811D01*
X414520Y856917D01*
X414270Y856708D01*
G01X412711Y854500D02*
Y857000D01*
X411670D01*
X411336Y856875D01*
X411128Y856708D01*
X411045Y856375D01*
X411128Y856042D01*
X411378Y855833D01*
X411670Y855708D01*
X412711D01*
G01X411670D02*
X411045Y854500D01*
G01X409486Y854792D02*
X409195Y854583D01*
X408861Y854500D01*
X408528Y854583D01*
X408236Y854833D01*
X408028Y855208D01*
X407945Y855583D01*
Y856042D01*
X408028Y856417D01*
X408236Y856750D01*
X408486Y856917D01*
X408778Y857000D01*
X409111Y856917D01*
X409361Y856750D01*
X409528Y856500D01*
X409611Y856167D01*
X409528Y855875D01*
X409320Y855583D01*
X409070Y855417D01*
X408778Y855375D01*
X408445Y855458D01*
X408195Y855667D01*
X407945Y856042D01*
G01X405678Y854500D02*
Y857000D01*
X406178Y856500D01*
G01Y854500D02*
X405178D01*
G01X403495Y855000D02*
X403245Y854708D01*
X402911Y854542D01*
X402536Y854500D01*
X402203Y854542D01*
X401870Y854750D01*
X401661Y855000D01*
X401620Y855250D01*
X401703Y855542D01*
X401995Y855750D01*
X402286Y855833D01*
X402661D01*
G01X402286D02*
X402036Y855958D01*
X401828Y856167D01*
X401745Y856417D01*
X401828Y856667D01*
X402036Y856875D01*
X402411Y857000D01*
X402786Y856958D01*
X403161Y856792D01*
G01X417303Y863333D02*
X416970Y863125D01*
X416595Y863000D01*
X416261D01*
X415928Y863125D01*
X415678Y863333D01*
X415553Y863625D01*
X415636Y863917D01*
X415845Y864167D01*
X416220Y864333D01*
X416720Y864417D01*
X417011Y864583D01*
X417136Y864875D01*
X417053Y865167D01*
X416845Y865375D01*
X416553Y865500D01*
X416261D01*
X415970Y865417D01*
X415720Y865208D01*
G01X412411Y865292D02*
X412661Y865417D01*
X412953Y865500D01*
X413286D01*
X413661Y865375D01*
X413953Y865167D01*
X414161Y864917D01*
X414328Y864500D01*
X414370Y864125D01*
X414286Y863750D01*
X414161Y863500D01*
X413911Y863250D01*
X413620Y863083D01*
X413328Y863000D01*
X413036D01*
X412745Y863083D01*
X412495Y863208D01*
X412286Y863375D01*
G01X410228Y863000D02*
Y865500D01*
X410728Y865000D01*
G01Y863000D02*
X409728D01*
G01X407920Y865083D02*
X407670Y865333D01*
X407378Y865458D01*
X407045Y865500D01*
X406628Y865417D01*
X406336Y865208D01*
X406253Y864958D01*
X406295Y864708D01*
X406461Y864500D01*
X407295Y864083D01*
X407670Y863792D01*
X407920Y863375D01*
X408003Y863000D01*
X406253D01*
G01X404736Y863292D02*
X404445Y863083D01*
X404111Y863000D01*
X403778Y863083D01*
X403486Y863333D01*
X403278Y863708D01*
X403195Y864083D01*
Y864542D01*
X403278Y864917D01*
X403486Y865250D01*
X403736Y865417D01*
X404028Y865500D01*
X404361Y865417D01*
X404611Y865250D01*
X404778Y865000D01*
X404861Y864667D01*
X404778Y864375D01*
X404570Y864083D01*
X404320Y863917D01*
X404028Y863875D01*
X403695Y863958D01*
X403445Y864167D01*
X403195Y864542D01*
G01X401845Y863500D02*
X401595Y863208D01*
X401261Y863042D01*
X400886Y863000D01*
X400553Y863042D01*
X400220Y863250D01*
X400011Y863500D01*
X399970Y863750D01*
X400053Y864042D01*
X400345Y864250D01*
X400636Y864333D01*
X401011D01*
G01X400636D02*
X400386Y864458D01*
X400178Y864667D01*
X400095Y864917D01*
X400178Y865167D01*
X400386Y865375D01*
X400761Y865500D01*
X401136Y865458D01*
X401511Y865292D01*
G01X409200Y891500D02*
Y887500D01*
X401800D01*
G01X409200Y895500D02*
Y891500D01*
X401800D01*
G01X409200Y907500D02*
Y903500D01*
X401800D01*
G01X422983Y910000D02*
Y912500D01*
X421942D01*
X421608Y912375D01*
X421400Y912208D01*
X421317Y911875D01*
X421400Y911542D01*
X421650Y911333D01*
X421942Y911208D01*
X422983D01*
G01X421942D02*
X421317Y910000D01*
G01X419842Y911042D02*
X419550Y911333D01*
X419300Y911500D01*
X418967Y911583D01*
X418675Y911500D01*
X418467Y911333D01*
X418300Y911083D01*
X418258Y910792D01*
X418300Y910542D01*
X418467Y910292D01*
X418717Y910083D01*
X419008Y910000D01*
X419342Y910083D01*
X419633Y910333D01*
X419800Y910708D01*
X419842Y911125D01*
X419758Y911667D01*
X419633Y911958D01*
X419425Y912250D01*
X419133Y912458D01*
X418842Y912500D01*
X418550Y912417D01*
X418342Y912208D01*
G01X416742Y911042D02*
X416450Y911333D01*
X416200Y911500D01*
X415867Y911583D01*
X415575Y911500D01*
X415367Y911333D01*
X415200Y911083D01*
X415158Y910792D01*
X415200Y910542D01*
X415367Y910292D01*
X415617Y910083D01*
X415908Y910000D01*
X416242Y910083D01*
X416533Y910333D01*
X416700Y910708D01*
X416742Y911125D01*
X416658Y911667D01*
X416533Y911958D01*
X416325Y912250D01*
X416033Y912458D01*
X415742Y912500D01*
X415450Y912417D01*
X415242Y912208D01*
G01X413767Y910500D02*
X413517Y910208D01*
X413183Y910042D01*
X412808Y910000D01*
X412475Y910042D01*
X412142Y910250D01*
X411933Y910500D01*
X411892Y910750D01*
X411975Y911042D01*
X412267Y911250D01*
X412558Y911333D01*
X412933D01*
G01X412558D02*
X412308Y911458D01*
X412100Y911667D01*
X412017Y911917D01*
X412100Y912167D01*
X412308Y912375D01*
X412683Y912500D01*
X413058Y912458D01*
X413433Y912292D01*
G01X409200Y899500D02*
Y895500D01*
X401800D01*
G01X409200Y911500D02*
Y907500D01*
X401800D01*
G01X409200Y903500D02*
Y899500D01*
X401800D01*
G01X422983Y902000D02*
Y904500D01*
X421942D01*
X421608Y904375D01*
X421400Y904208D01*
X421317Y903875D01*
X421400Y903542D01*
X421650Y903333D01*
X421942Y903208D01*
X422983D01*
G01X421942D02*
X421317Y902000D01*
G01X419842Y903042D02*
X419550Y903333D01*
X419300Y903500D01*
X418967Y903583D01*
X418675Y903500D01*
X418467Y903333D01*
X418300Y903083D01*
X418258Y902792D01*
X418300Y902542D01*
X418467Y902292D01*
X418717Y902083D01*
X419008Y902000D01*
X419342Y902083D01*
X419633Y902333D01*
X419800Y902708D01*
X419842Y903125D01*
X419758Y903667D01*
X419633Y903958D01*
X419425Y904250D01*
X419133Y904458D01*
X418842Y904500D01*
X418550Y904417D01*
X418342Y904208D01*
G01X416742Y903042D02*
X416450Y903333D01*
X416200Y903500D01*
X415867Y903583D01*
X415575Y903500D01*
X415367Y903333D01*
X415200Y903083D01*
X415158Y902792D01*
X415200Y902542D01*
X415367Y902292D01*
X415617Y902083D01*
X415908Y902000D01*
X416242Y902083D01*
X416533Y902333D01*
X416700Y902708D01*
X416742Y903125D01*
X416658Y903667D01*
X416533Y903958D01*
X416325Y904250D01*
X416033Y904458D01*
X415742Y904500D01*
X415450Y904417D01*
X415242Y904208D01*
G01X413642Y903042D02*
X413350Y903333D01*
X413100Y903500D01*
X412767Y903583D01*
X412475Y903500D01*
X412267Y903333D01*
X412100Y903083D01*
X412058Y902792D01*
X412100Y902542D01*
X412267Y902292D01*
X412517Y902083D01*
X412808Y902000D01*
X413142Y902083D01*
X413433Y902333D01*
X413600Y902708D01*
X413642Y903125D01*
X413558Y903667D01*
X413433Y903958D01*
X413225Y904250D01*
X412933Y904458D01*
X412642Y904500D01*
X412350Y904417D01*
X412142Y904208D01*
G01X422983Y906000D02*
Y908500D01*
X421942D01*
X421608Y908375D01*
X421400Y908208D01*
X421317Y907875D01*
X421400Y907542D01*
X421650Y907333D01*
X421942Y907208D01*
X422983D01*
G01X421942D02*
X421317Y906000D01*
G01X419842Y907042D02*
X419550Y907333D01*
X419300Y907500D01*
X418967Y907583D01*
X418675Y907500D01*
X418467Y907333D01*
X418300Y907083D01*
X418258Y906792D01*
X418300Y906542D01*
X418467Y906292D01*
X418717Y906083D01*
X419008Y906000D01*
X419342Y906083D01*
X419633Y906333D01*
X419800Y906708D01*
X419842Y907125D01*
X419758Y907667D01*
X419633Y907958D01*
X419425Y908250D01*
X419133Y908458D01*
X418842Y908500D01*
X418550Y908417D01*
X418342Y908208D01*
G01X416742Y907042D02*
X416450Y907333D01*
X416200Y907500D01*
X415867Y907583D01*
X415575Y907500D01*
X415367Y907333D01*
X415200Y907083D01*
X415158Y906792D01*
X415200Y906542D01*
X415367Y906292D01*
X415617Y906083D01*
X415908Y906000D01*
X416242Y906083D01*
X416533Y906333D01*
X416700Y906708D01*
X416742Y907125D01*
X416658Y907667D01*
X416533Y907958D01*
X416325Y908250D01*
X416033Y908458D01*
X415742Y908500D01*
X415450Y908417D01*
X415242Y908208D01*
G01X412850Y906000D02*
X412558Y906042D01*
X412225Y906167D01*
X412017Y906375D01*
X411933Y906667D01*
X412017Y906958D01*
X412267Y907208D01*
X412642Y907333D01*
X413058D01*
X413308Y907417D01*
X413517Y907625D01*
X413600Y907917D01*
X413475Y908208D01*
X413183Y908417D01*
X412850Y908500D01*
X412517Y908417D01*
X412225Y908208D01*
X412100Y907917D01*
X412183Y907625D01*
X412392Y907417D01*
X412642Y907333D01*
X413058D01*
X413433Y907208D01*
X413683Y906958D01*
X413767Y906667D01*
X413683Y906375D01*
X413475Y906167D01*
X413142Y906042D01*
X412850Y906000D01*
G01X422983Y918000D02*
Y920500D01*
X421942D01*
X421608Y920375D01*
X421400Y920208D01*
X421317Y919875D01*
X421400Y919542D01*
X421650Y919333D01*
X421942Y919208D01*
X422983D01*
G01X421942D02*
X421317Y918000D01*
G01X419967Y918375D02*
X419717Y918167D01*
X419425Y918042D01*
X419050Y918000D01*
X418675Y918083D01*
X418383Y918250D01*
X418175Y918542D01*
X418133Y918875D01*
X418217Y919208D01*
X418425Y919417D01*
X418717Y919583D01*
X419008Y919625D01*
X419300Y919583D01*
X419675Y919417D01*
X419550Y920500D01*
X418425D01*
G01X416658Y918292D02*
X416367Y918083D01*
X416033Y918000D01*
X415700Y918083D01*
X415408Y918333D01*
X415200Y918708D01*
X415117Y919083D01*
Y919542D01*
X415200Y919917D01*
X415408Y920250D01*
X415658Y920417D01*
X415950Y920500D01*
X416283Y920417D01*
X416533Y920250D01*
X416700Y920000D01*
X416783Y919667D01*
X416700Y919375D01*
X416492Y919083D01*
X416242Y918917D01*
X415950Y918875D01*
X415617Y918958D01*
X415367Y919167D01*
X415117Y919542D01*
G01X412350Y918000D02*
Y920500D01*
X413892Y918708D01*
X411808D01*
G01X422983Y922000D02*
Y924500D01*
X421942D01*
X421608Y924375D01*
X421400Y924208D01*
X421317Y923875D01*
X421400Y923542D01*
X421650Y923333D01*
X421942Y923208D01*
X422983D01*
G01X421942D02*
X421317Y922000D01*
G01X419842Y923042D02*
X419550Y923333D01*
X419300Y923500D01*
X418967Y923583D01*
X418675Y923500D01*
X418467Y923333D01*
X418300Y923083D01*
X418258Y922792D01*
X418300Y922542D01*
X418467Y922292D01*
X418717Y922083D01*
X419008Y922000D01*
X419342Y922083D01*
X419633Y922333D01*
X419800Y922708D01*
X419842Y923125D01*
X419758Y923667D01*
X419633Y923958D01*
X419425Y924250D01*
X419133Y924458D01*
X418842Y924500D01*
X418550Y924417D01*
X418342Y924208D01*
G01X416742Y923042D02*
X416450Y923333D01*
X416200Y923500D01*
X415867Y923583D01*
X415575Y923500D01*
X415367Y923333D01*
X415200Y923083D01*
X415158Y922792D01*
X415200Y922542D01*
X415367Y922292D01*
X415617Y922083D01*
X415908Y922000D01*
X416242Y922083D01*
X416533Y922333D01*
X416700Y922708D01*
X416742Y923125D01*
X416658Y923667D01*
X416533Y923958D01*
X416325Y924250D01*
X416033Y924458D01*
X415742Y924500D01*
X415450Y924417D01*
X415242Y924208D01*
G01X412350Y922000D02*
Y924500D01*
X413892Y922708D01*
X411808D01*
G01X422983Y914000D02*
Y916500D01*
X421942D01*
X421608Y916375D01*
X421400Y916208D01*
X421317Y915875D01*
X421400Y915542D01*
X421650Y915333D01*
X421942Y915208D01*
X422983D01*
G01X421942D02*
X421317Y914000D01*
G01X419842Y915042D02*
X419550Y915333D01*
X419300Y915500D01*
X418967Y915583D01*
X418675Y915500D01*
X418467Y915333D01*
X418300Y915083D01*
X418258Y914792D01*
X418300Y914542D01*
X418467Y914292D01*
X418717Y914083D01*
X419008Y914000D01*
X419342Y914083D01*
X419633Y914333D01*
X419800Y914708D01*
X419842Y915125D01*
X419758Y915667D01*
X419633Y915958D01*
X419425Y916250D01*
X419133Y916458D01*
X418842Y916500D01*
X418550Y916417D01*
X418342Y916208D01*
G01X416742Y915042D02*
X416450Y915333D01*
X416200Y915500D01*
X415867Y915583D01*
X415575Y915500D01*
X415367Y915333D01*
X415200Y915083D01*
X415158Y914792D01*
X415200Y914542D01*
X415367Y914292D01*
X415617Y914083D01*
X415908Y914000D01*
X416242Y914083D01*
X416533Y914333D01*
X416700Y914708D01*
X416742Y915125D01*
X416658Y915667D01*
X416533Y915958D01*
X416325Y916250D01*
X416033Y916458D01*
X415742Y916500D01*
X415450Y916417D01*
X415242Y916208D01*
G01X413767Y914375D02*
X413517Y914167D01*
X413225Y914042D01*
X412850Y914000D01*
X412475Y914083D01*
X412183Y914250D01*
X411975Y914542D01*
X411933Y914875D01*
X412017Y915208D01*
X412225Y915417D01*
X412517Y915583D01*
X412808Y915625D01*
X413100Y915583D01*
X413475Y915417D01*
X413350Y916500D01*
X412225D01*
G01X403000Y946200D02*
X407000D01*
Y938800D01*
G01Y946200D02*
X411000D01*
Y938800D01*
G01X399000Y946200D02*
X403000D01*
Y938800D01*
G01X411000Y946200D02*
X415000D01*
Y938800D01*
G01X424762Y35875D02*
X424554Y36208D01*
X424429Y36583D01*
Y36917D01*
X424554Y37250D01*
X424762Y37500D01*
X425054Y37625D01*
X425346Y37542D01*
X425596Y37333D01*
X425762Y36958D01*
X425846Y36458D01*
X426012Y36167D01*
X426304Y36042D01*
X426596Y36125D01*
X426804Y36333D01*
X426929Y36625D01*
Y36917D01*
X426846Y37208D01*
X426637Y37458D01*
G01X426929Y39850D02*
X424429D01*
G01X426929Y38892D02*
Y40808D01*
G01X424429Y42117D02*
X426929D01*
Y43117D01*
X426804Y43450D01*
X426512Y43700D01*
X426179Y43783D01*
X425846Y43700D01*
X425596Y43492D01*
X425471Y43117D01*
Y42117D01*
G01X424429Y46050D02*
X426929D01*
X426429Y45550D01*
G01X424429D02*
Y46550D01*
G01Y49150D02*
X426929D01*
X426429Y48650D01*
G01X424429D02*
Y49650D01*
G01X424804Y51333D02*
X424596Y51583D01*
X424471Y51875D01*
X424429Y52250D01*
X424512Y52625D01*
X424679Y52917D01*
X424971Y53125D01*
X425304Y53167D01*
X425637Y53083D01*
X425846Y52875D01*
X426012Y52583D01*
X426054Y52292D01*
X426012Y52000D01*
X425846Y51625D01*
X426929Y51750D01*
Y52875D01*
G01X414262Y104925D02*
X414054Y105258D01*
X413929Y105633D01*
Y105967D01*
X414054Y106300D01*
X414262Y106550D01*
X414554Y106675D01*
X414846Y106592D01*
X415096Y106383D01*
X415262Y106008D01*
X415346Y105508D01*
X415512Y105217D01*
X415804Y105092D01*
X416096Y105175D01*
X416304Y105383D01*
X416429Y105675D01*
Y105967D01*
X416346Y106258D01*
X416137Y106508D01*
G01X416221Y109817D02*
X416346Y109567D01*
X416429Y109275D01*
Y108942D01*
X416304Y108567D01*
X416096Y108275D01*
X415846Y108067D01*
X415429Y107900D01*
X415054Y107858D01*
X414679Y107942D01*
X414429Y108067D01*
X414179Y108317D01*
X414012Y108608D01*
X413929Y108900D01*
Y109192D01*
X414012Y109483D01*
X414137Y109733D01*
X414304Y109942D01*
G01X413929Y112000D02*
X413971Y112292D01*
X414096Y112625D01*
X414304Y112833D01*
X414596Y112917D01*
X414887Y112833D01*
X415137Y112583D01*
X415262Y112208D01*
Y111792D01*
X415346Y111542D01*
X415554Y111333D01*
X415846Y111250D01*
X416137Y111375D01*
X416346Y111667D01*
X416429Y112000D01*
X416346Y112333D01*
X416137Y112625D01*
X415846Y112750D01*
X415554Y112667D01*
X415346Y112458D01*
X415262Y112208D01*
Y111792D01*
X415137Y111417D01*
X414887Y111167D01*
X414596Y111083D01*
X414304Y111167D01*
X414096Y111375D01*
X413971Y111708D01*
X413929Y112000D01*
G01Y115017D02*
X414471Y115100D01*
X414929Y115225D01*
X415346Y115392D01*
X415804Y115600D01*
X416429Y115933D01*
Y114267D01*
G01X414971Y117408D02*
X415262Y117700D01*
X415429Y117950D01*
X415512Y118283D01*
X415429Y118575D01*
X415262Y118783D01*
X415012Y118950D01*
X414721Y118992D01*
X414471Y118950D01*
X414221Y118783D01*
X414012Y118533D01*
X413929Y118242D01*
X414012Y117908D01*
X414262Y117617D01*
X414637Y117450D01*
X415054Y117408D01*
X415596Y117492D01*
X415887Y117617D01*
X416179Y117825D01*
X416387Y118117D01*
X416429Y118408D01*
X416346Y118700D01*
X416137Y118908D01*
G01X427940Y149600D02*
X423940D01*
Y157000D01*
G01X427940D02*
X431940D01*
Y149600D01*
G01X437033Y249500D02*
Y252000D01*
X436033D01*
X435700Y251875D01*
X435450Y251583D01*
X435367Y251250D01*
X435450Y250917D01*
X435658Y250667D01*
X436033Y250542D01*
X437033D01*
G01X433933Y249500D02*
Y252000D01*
X432892D01*
X432558Y251875D01*
X432350Y251708D01*
X432267Y251375D01*
X432350Y251042D01*
X432600Y250833D01*
X432892Y250708D01*
X433933D01*
G01X432892D02*
X432267Y249500D01*
G01X430000D02*
Y252000D01*
X430500Y251500D01*
G01Y249500D02*
X429500D01*
G01X426900D02*
X426608Y249542D01*
X426275Y249667D01*
X426067Y249875D01*
X425983Y250167D01*
X426067Y250458D01*
X426317Y250708D01*
X426692Y250833D01*
X427108D01*
X427358Y250917D01*
X427567Y251125D01*
X427650Y251417D01*
X427525Y251708D01*
X427233Y251917D01*
X426900Y252000D01*
X426567Y251917D01*
X426275Y251708D01*
X426150Y251417D01*
X426233Y251125D01*
X426442Y250917D01*
X426692Y250833D01*
X427108D01*
X427483Y250708D01*
X427733Y250458D01*
X427817Y250167D01*
X427733Y249875D01*
X427525Y249667D01*
X427192Y249542D01*
X426900Y249500D01*
G01X424592Y251583D02*
X424342Y251833D01*
X424050Y251958D01*
X423717Y252000D01*
X423300Y251917D01*
X423008Y251708D01*
X422925Y251458D01*
X422967Y251208D01*
X423133Y251000D01*
X423967Y250583D01*
X424342Y250292D01*
X424592Y249875D01*
X424675Y249500D01*
X422925D01*
G01X432200Y243000D02*
Y239000D01*
X424800D01*
G01X437033Y253500D02*
Y256000D01*
X436033D01*
X435700Y255875D01*
X435450Y255583D01*
X435367Y255250D01*
X435450Y254917D01*
X435658Y254667D01*
X436033Y254542D01*
X437033D01*
G01X433933Y253500D02*
Y256000D01*
X432892D01*
X432558Y255875D01*
X432350Y255708D01*
X432267Y255375D01*
X432350Y255042D01*
X432600Y254833D01*
X432892Y254708D01*
X433933D01*
G01X432892D02*
X432267Y253500D01*
G01X430000D02*
Y256000D01*
X430500Y255500D01*
G01Y253500D02*
X429500D01*
G01X427608Y253792D02*
X427317Y253583D01*
X426983Y253500D01*
X426650Y253583D01*
X426358Y253833D01*
X426150Y254208D01*
X426067Y254583D01*
Y255042D01*
X426150Y255417D01*
X426358Y255750D01*
X426608Y255917D01*
X426900Y256000D01*
X427233Y255917D01*
X427483Y255750D01*
X427650Y255500D01*
X427733Y255167D01*
X427650Y254875D01*
X427442Y254583D01*
X427192Y254417D01*
X426900Y254375D01*
X426567Y254458D01*
X426317Y254667D01*
X426067Y255042D01*
G01X423800Y253500D02*
Y256000D01*
X424300Y255500D01*
G01Y253500D02*
X423300D01*
G01X432200Y247000D02*
Y243000D01*
X424800D01*
G01X428833Y272425D02*
X428625Y272758D01*
X428500Y273133D01*
Y273467D01*
X428625Y273800D01*
X428833Y274050D01*
X429125Y274175D01*
X429417Y274092D01*
X429667Y273883D01*
X429833Y273508D01*
X429917Y273008D01*
X430083Y272717D01*
X430375Y272592D01*
X430667Y272675D01*
X430875Y272883D01*
X431000Y273175D01*
Y273467D01*
X430917Y273758D01*
X430708Y274008D01*
G01X428500Y275567D02*
X431000D01*
Y276608D01*
X430875Y276942D01*
X430708Y277150D01*
X430375Y277233D01*
X430042Y277150D01*
X429833Y276900D01*
X429708Y276608D01*
Y275567D01*
G01Y276608D02*
X428500Y277233D01*
G01Y279417D02*
X429042Y279500D01*
X429500Y279625D01*
X429917Y279792D01*
X430375Y280000D01*
X431000Y280333D01*
Y278667D01*
G01X429000Y281683D02*
X428708Y281933D01*
X428542Y282267D01*
X428500Y282642D01*
X428542Y282975D01*
X428750Y283308D01*
X429000Y283517D01*
X429250Y283558D01*
X429542Y283475D01*
X429750Y283183D01*
X429833Y282892D01*
Y282517D01*
G01Y282892D02*
X429958Y283142D01*
X430167Y283350D01*
X430417Y283433D01*
X430667Y283350D01*
X430875Y283142D01*
X431000Y282767D01*
X430958Y282392D01*
X430792Y282017D01*
G01X428500Y285700D02*
X431000D01*
X430500Y285200D01*
G01X428500D02*
Y286200D01*
G01X414388Y302925D02*
X414180Y303258D01*
X414055Y303633D01*
Y303967D01*
X414180Y304300D01*
X414388Y304550D01*
X414680Y304675D01*
X414972Y304592D01*
X415222Y304383D01*
X415388Y304008D01*
X415472Y303508D01*
X415638Y303217D01*
X415930Y303092D01*
X416222Y303175D01*
X416430Y303383D01*
X416555Y303675D01*
Y303967D01*
X416472Y304258D01*
X416263Y304508D01*
G01X414055Y306067D02*
X416555D01*
Y307108D01*
X416430Y307442D01*
X416263Y307650D01*
X415930Y307733D01*
X415597Y307650D01*
X415388Y307400D01*
X415263Y307108D01*
Y306067D01*
G01Y307108D02*
X414055Y307733D01*
G01Y309917D02*
X414597Y310000D01*
X415055Y310125D01*
X415472Y310292D01*
X415930Y310500D01*
X416555Y310833D01*
Y309167D01*
G01X415097Y312308D02*
X415388Y312600D01*
X415555Y312850D01*
X415638Y313183D01*
X415555Y313475D01*
X415388Y313683D01*
X415138Y313850D01*
X414847Y313892D01*
X414597Y313850D01*
X414347Y313683D01*
X414138Y313433D01*
X414055Y313142D01*
X414138Y312808D01*
X414388Y312517D01*
X414763Y312350D01*
X415180Y312308D01*
X415722Y312392D01*
X416013Y312517D01*
X416305Y312725D01*
X416513Y313017D01*
X416555Y313308D01*
X416472Y313600D01*
X416263Y313808D01*
G01X414055Y316200D02*
X414097Y316492D01*
X414222Y316825D01*
X414430Y317033D01*
X414722Y317117D01*
X415013Y317033D01*
X415263Y316783D01*
X415388Y316408D01*
Y315992D01*
X415472Y315742D01*
X415680Y315533D01*
X415972Y315450D01*
X416263Y315575D01*
X416472Y315867D01*
X416555Y316200D01*
X416472Y316533D01*
X416263Y316825D01*
X415972Y316950D01*
X415680Y316867D01*
X415472Y316658D01*
X415388Y316408D01*
Y315992D01*
X415263Y315617D01*
X415013Y315367D01*
X414722Y315283D01*
X414430Y315367D01*
X414222Y315575D01*
X414097Y315908D01*
X414055Y316200D01*
G01X424356Y293708D02*
X424148Y294041D01*
X424023Y294416D01*
Y294750D01*
X424148Y295083D01*
X424356Y295333D01*
X424648Y295458D01*
X424940Y295375D01*
X425190Y295166D01*
X425356Y294791D01*
X425440Y294291D01*
X425606Y294000D01*
X425898Y293875D01*
X426190Y293958D01*
X426398Y294166D01*
X426523Y294458D01*
Y294750D01*
X426440Y295041D01*
X426231Y295291D01*
G01X424023Y296850D02*
X426523D01*
Y297891D01*
X426398Y298225D01*
X426231Y298433D01*
X425898Y298516D01*
X425565Y298433D01*
X425356Y298183D01*
X425231Y297891D01*
Y296850D01*
G01Y297891D02*
X424023Y298516D01*
G01Y300700D02*
X424565Y300783D01*
X425023Y300908D01*
X425440Y301075D01*
X425898Y301283D01*
X426523Y301616D01*
Y299950D01*
G01X425065Y303091D02*
X425356Y303383D01*
X425523Y303633D01*
X425606Y303966D01*
X425523Y304258D01*
X425356Y304466D01*
X425106Y304633D01*
X424815Y304675D01*
X424565Y304633D01*
X424315Y304466D01*
X424106Y304216D01*
X424023Y303925D01*
X424106Y303591D01*
X424356Y303300D01*
X424731Y303133D01*
X425148Y303091D01*
X425690Y303175D01*
X425981Y303300D01*
X426273Y303508D01*
X426481Y303800D01*
X426523Y304091D01*
X426440Y304383D01*
X426231Y304591D01*
G01X424315Y306275D02*
X424106Y306566D01*
X424023Y306900D01*
X424106Y307233D01*
X424356Y307525D01*
X424731Y307733D01*
X425106Y307816D01*
X425565D01*
X425940Y307733D01*
X426273Y307525D01*
X426440Y307275D01*
X426523Y306983D01*
X426440Y306650D01*
X426273Y306400D01*
X426023Y306233D01*
X425690Y306150D01*
X425398Y306233D01*
X425106Y306441D01*
X424940Y306691D01*
X424898Y306983D01*
X424981Y307316D01*
X425190Y307566D01*
X425565Y307816D01*
G01X419388Y293925D02*
X419180Y294258D01*
X419055Y294633D01*
Y294967D01*
X419180Y295300D01*
X419388Y295550D01*
X419680Y295675D01*
X419972Y295592D01*
X420222Y295383D01*
X420388Y295008D01*
X420472Y294508D01*
X420638Y294217D01*
X420930Y294092D01*
X421222Y294175D01*
X421430Y294383D01*
X421555Y294675D01*
Y294967D01*
X421472Y295258D01*
X421263Y295508D01*
G01X419055Y297067D02*
X421555D01*
Y298108D01*
X421430Y298442D01*
X421263Y298650D01*
X420930Y298733D01*
X420597Y298650D01*
X420388Y298400D01*
X420263Y298108D01*
Y297067D01*
G01Y298108D02*
X419055Y298733D01*
G01Y300917D02*
X419597Y301000D01*
X420055Y301125D01*
X420472Y301292D01*
X420930Y301500D01*
X421555Y301833D01*
Y300167D01*
G01X419055Y304017D02*
X419597Y304100D01*
X420055Y304225D01*
X420472Y304392D01*
X420930Y304600D01*
X421555Y304933D01*
Y303267D01*
G01Y307200D02*
X421472Y306867D01*
X421263Y306617D01*
X421013Y306450D01*
X420680Y306325D01*
X420305Y306283D01*
X419930Y306325D01*
X419597Y306450D01*
X419347Y306617D01*
X419138Y306867D01*
X419055Y307200D01*
X419138Y307533D01*
X419347Y307783D01*
X419597Y307950D01*
X419930Y308075D01*
X420305Y308117D01*
X420680Y308075D01*
X421013Y307950D01*
X421263Y307783D01*
X421472Y307533D01*
X421555Y307200D01*
G01X429075Y289833D02*
X428742Y289625D01*
X428367Y289500D01*
X428033D01*
X427700Y289625D01*
X427450Y289833D01*
X427325Y290125D01*
X427408Y290417D01*
X427617Y290667D01*
X427992Y290833D01*
X428492Y290917D01*
X428783Y291083D01*
X428908Y291375D01*
X428825Y291667D01*
X428617Y291875D01*
X428325Y292000D01*
X428033D01*
X427742Y291917D01*
X427492Y291708D01*
G01X425933Y289500D02*
Y292000D01*
X424892D01*
X424558Y291875D01*
X424350Y291708D01*
X424267Y291375D01*
X424350Y291042D01*
X424600Y290833D01*
X424892Y290708D01*
X425933D01*
G01X424892D02*
X424267Y289500D01*
G01X422083D02*
X422000Y290042D01*
X421875Y290500D01*
X421708Y290917D01*
X421500Y291375D01*
X421167Y292000D01*
X422833D01*
G01X418983Y289500D02*
X418900Y290042D01*
X418775Y290500D01*
X418608Y290917D01*
X418400Y291375D01*
X418067Y292000D01*
X419733D01*
G01X416717Y290000D02*
X416467Y289708D01*
X416133Y289542D01*
X415758Y289500D01*
X415425Y289542D01*
X415092Y289750D01*
X414883Y290000D01*
X414842Y290250D01*
X414925Y290542D01*
X415217Y290750D01*
X415508Y290833D01*
X415883D01*
G01X415508D02*
X415258Y290958D01*
X415050Y291167D01*
X414967Y291417D01*
X415050Y291667D01*
X415258Y291875D01*
X415633Y292000D01*
X416008Y291958D01*
X416383Y291792D01*
G01X430700Y316500D02*
Y312500D01*
X423300D01*
G01X429630Y336333D02*
X429297Y336125D01*
X428922Y336000D01*
X428588D01*
X428255Y336125D01*
X428005Y336333D01*
X427880Y336625D01*
X427963Y336917D01*
X428172Y337167D01*
X428547Y337333D01*
X429047Y337417D01*
X429338Y337583D01*
X429463Y337875D01*
X429380Y338167D01*
X429172Y338375D01*
X428880Y338500D01*
X428588D01*
X428297Y338417D01*
X428047Y338208D01*
G01X425655Y338500D02*
Y336000D01*
G01X426613Y338500D02*
X424697D01*
G01X423388Y336000D02*
Y338500D01*
X422388D01*
X422055Y338375D01*
X421805Y338083D01*
X421722Y337750D01*
X421805Y337417D01*
X422013Y337167D01*
X422388Y337042D01*
X423388D01*
G01X420372Y336375D02*
X420122Y336167D01*
X419830Y336042D01*
X419455Y336000D01*
X419080Y336083D01*
X418788Y336250D01*
X418580Y336542D01*
X418538Y336875D01*
X418622Y337208D01*
X418830Y337417D01*
X419122Y337583D01*
X419413Y337625D01*
X419705Y337583D01*
X420080Y337417D01*
X419955Y338500D01*
X418830D01*
G01X417147Y337042D02*
X416855Y337333D01*
X416605Y337500D01*
X416272Y337583D01*
X415980Y337500D01*
X415772Y337333D01*
X415605Y337083D01*
X415563Y336792D01*
X415605Y336542D01*
X415772Y336292D01*
X416022Y336083D01*
X416313Y336000D01*
X416647Y336083D01*
X416938Y336333D01*
X417105Y336708D01*
X417147Y337125D01*
X417063Y337667D01*
X416938Y337958D01*
X416730Y338250D01*
X416438Y338458D01*
X416147Y338500D01*
X415855Y338417D01*
X415647Y338208D01*
G01X420223Y328283D02*
Y324283D01*
X412823D01*
G01X428523Y321583D02*
X424523D01*
Y328983D01*
G01X432180Y340833D02*
X431847Y340625D01*
X431472Y340500D01*
X431138D01*
X430805Y340625D01*
X430555Y340833D01*
X430430Y341125D01*
X430513Y341417D01*
X430722Y341667D01*
X431097Y341833D01*
X431597Y341917D01*
X431888Y342083D01*
X432013Y342375D01*
X431930Y342667D01*
X431722Y342875D01*
X431430Y343000D01*
X431138D01*
X430847Y342917D01*
X430597Y342708D01*
G01X428205Y343000D02*
Y340500D01*
G01X429163Y343000D02*
X427247D01*
G01X425938Y340500D02*
Y343000D01*
X424938D01*
X424605Y342875D01*
X424355Y342583D01*
X424272Y342250D01*
X424355Y341917D01*
X424563Y341667D01*
X424938Y341542D01*
X425938D01*
G01X422005Y340500D02*
Y343000D01*
X422505Y342500D01*
G01Y340500D02*
X421505D01*
G01X419822Y340875D02*
X419572Y340667D01*
X419280Y340542D01*
X418905Y340500D01*
X418530Y340583D01*
X418238Y340750D01*
X418030Y341042D01*
X417988Y341375D01*
X418072Y341708D01*
X418280Y341917D01*
X418572Y342083D01*
X418863Y342125D01*
X419155Y342083D01*
X419530Y341917D01*
X419405Y343000D01*
X418280D01*
G01X415888Y340500D02*
X415805Y341042D01*
X415680Y341500D01*
X415513Y341917D01*
X415305Y342375D01*
X414972Y343000D01*
X416638D01*
G01X477000Y372500D02*
X478500D01*
Y377000D01*
X456500D01*
Y375500D01*
X442500D01*
Y376500D01*
X428000D01*
Y356000D01*
X455500D01*
Y369500D01*
X459500D01*
G01X434280Y383233D02*
X433947Y383025D01*
X433572Y382900D01*
X433238D01*
X432905Y383025D01*
X432655Y383233D01*
X432530Y383525D01*
X432613Y383817D01*
X432822Y384067D01*
X433197Y384233D01*
X433697Y384317D01*
X433988Y384483D01*
X434113Y384775D01*
X434030Y385067D01*
X433822Y385275D01*
X433530Y385400D01*
X433238D01*
X432947Y385317D01*
X432697Y385108D01*
G01X429388Y385192D02*
X429638Y385317D01*
X429930Y385400D01*
X430263D01*
X430638Y385275D01*
X430930Y385067D01*
X431138Y384817D01*
X431305Y384400D01*
X431347Y384025D01*
X431263Y383650D01*
X431138Y383400D01*
X430888Y383150D01*
X430597Y382983D01*
X430305Y382900D01*
X430013D01*
X429722Y382983D01*
X429472Y383108D01*
X429263Y383275D01*
G01X427205Y382900D02*
Y385400D01*
X427705Y384900D01*
G01Y382900D02*
X426705D01*
G01X424897Y384983D02*
X424647Y385233D01*
X424355Y385358D01*
X424022Y385400D01*
X423605Y385317D01*
X423313Y385108D01*
X423230Y384858D01*
X423272Y384608D01*
X423438Y384400D01*
X424272Y383983D01*
X424647Y383692D01*
X424897Y383275D01*
X424980Y382900D01*
X423230D01*
G01X421922Y383275D02*
X421672Y383067D01*
X421380Y382942D01*
X421005Y382900D01*
X420630Y382983D01*
X420338Y383150D01*
X420130Y383442D01*
X420088Y383775D01*
X420172Y384108D01*
X420380Y384317D01*
X420672Y384483D01*
X420963Y384525D01*
X421255Y384483D01*
X421630Y384317D01*
X421505Y385400D01*
X420380D01*
G01X418822Y383275D02*
X418572Y383067D01*
X418280Y382942D01*
X417905Y382900D01*
X417530Y382983D01*
X417238Y383150D01*
X417030Y383442D01*
X416988Y383775D01*
X417072Y384108D01*
X417280Y384317D01*
X417572Y384483D01*
X417863Y384525D01*
X418155Y384483D01*
X418530Y384317D01*
X418405Y385400D01*
X417280D01*
G01X442575Y378333D02*
X442242Y378125D01*
X441867Y378000D01*
X441533D01*
X441200Y378125D01*
X440950Y378333D01*
X440825Y378625D01*
X440908Y378917D01*
X441117Y379167D01*
X441492Y379333D01*
X441992Y379417D01*
X442283Y379583D01*
X442408Y379875D01*
X442325Y380167D01*
X442117Y380375D01*
X441825Y380500D01*
X441533D01*
X441242Y380417D01*
X440992Y380208D01*
G01X438600Y380500D02*
Y378000D01*
G01X439558Y380500D02*
X437642D01*
G01X436333Y378000D02*
Y380500D01*
X435333D01*
X435000Y380375D01*
X434750Y380083D01*
X434667Y379750D01*
X434750Y379417D01*
X434958Y379167D01*
X435333Y379042D01*
X436333D01*
G01X432400Y378000D02*
X432108Y378042D01*
X431775Y378167D01*
X431567Y378375D01*
X431483Y378667D01*
X431567Y378958D01*
X431817Y379208D01*
X432192Y379333D01*
X432608D01*
X432858Y379417D01*
X433067Y379625D01*
X433150Y379917D01*
X433025Y380208D01*
X432733Y380417D01*
X432400Y380500D01*
X432067Y380417D01*
X431775Y380208D01*
X431650Y379917D01*
X431733Y379625D01*
X431942Y379417D01*
X432192Y379333D01*
X432608D01*
X432983Y379208D01*
X433233Y378958D01*
X433317Y378667D01*
X433233Y378375D01*
X433025Y378167D01*
X432692Y378042D01*
X432400Y378000D01*
G01X430217Y378500D02*
X429967Y378208D01*
X429633Y378042D01*
X429258Y378000D01*
X428925Y378042D01*
X428592Y378250D01*
X428383Y378500D01*
X428342Y378750D01*
X428425Y379042D01*
X428717Y379250D01*
X429008Y379333D01*
X429383D01*
G01X429008D02*
X428758Y379458D01*
X428550Y379667D01*
X428467Y379917D01*
X428550Y380167D01*
X428758Y380375D01*
X429133Y380500D01*
X429508Y380458D01*
X429883Y380292D01*
G01X434180Y387833D02*
X433847Y387625D01*
X433472Y387500D01*
X433138D01*
X432805Y387625D01*
X432555Y387833D01*
X432430Y388125D01*
X432513Y388417D01*
X432722Y388667D01*
X433097Y388833D01*
X433597Y388917D01*
X433888Y389083D01*
X434013Y389375D01*
X433930Y389667D01*
X433722Y389875D01*
X433430Y390000D01*
X433138D01*
X432847Y389917D01*
X432597Y389708D01*
G01X429288Y389792D02*
X429538Y389917D01*
X429830Y390000D01*
X430163D01*
X430538Y389875D01*
X430830Y389667D01*
X431038Y389417D01*
X431205Y389000D01*
X431247Y388625D01*
X431163Y388250D01*
X431038Y388000D01*
X430788Y387750D01*
X430497Y387583D01*
X430205Y387500D01*
X429913D01*
X429622Y387583D01*
X429372Y387708D01*
X429163Y387875D01*
G01X427105Y387500D02*
Y390000D01*
X427605Y389500D01*
G01Y387500D02*
X426605D01*
G01X424797Y389583D02*
X424547Y389833D01*
X424255Y389958D01*
X423922Y390000D01*
X423505Y389917D01*
X423213Y389708D01*
X423130Y389458D01*
X423172Y389208D01*
X423338Y389000D01*
X424172Y388583D01*
X424547Y388292D01*
X424797Y387875D01*
X424880Y387500D01*
X423130D01*
G01X421822Y387875D02*
X421572Y387667D01*
X421280Y387542D01*
X420905Y387500D01*
X420530Y387583D01*
X420238Y387750D01*
X420030Y388042D01*
X419988Y388375D01*
X420072Y388708D01*
X420280Y388917D01*
X420572Y389083D01*
X420863Y389125D01*
X421155Y389083D01*
X421530Y388917D01*
X421405Y390000D01*
X420280D01*
G01X417305Y387500D02*
Y390000D01*
X418847Y388208D01*
X416763D01*
G01X423611Y786925D02*
X423403Y787258D01*
X423278Y787633D01*
Y787967D01*
X423403Y788300D01*
X423611Y788550D01*
X423903Y788675D01*
X424195Y788592D01*
X424445Y788383D01*
X424611Y788008D01*
X424695Y787508D01*
X424861Y787217D01*
X425153Y787092D01*
X425445Y787175D01*
X425653Y787383D01*
X425778Y787675D01*
Y787967D01*
X425695Y788258D01*
X425486Y788508D01*
G01X423278Y790067D02*
X425778D01*
Y791108D01*
X425653Y791442D01*
X425486Y791650D01*
X425153Y791733D01*
X424820Y791650D01*
X424611Y791400D01*
X424486Y791108D01*
Y790067D01*
G01Y791108D02*
X423278Y791733D01*
G01Y794000D02*
X423320Y794292D01*
X423445Y794625D01*
X423653Y794833D01*
X423945Y794917D01*
X424236Y794833D01*
X424486Y794583D01*
X424611Y794208D01*
Y793792D01*
X424695Y793542D01*
X424903Y793333D01*
X425195Y793250D01*
X425486Y793375D01*
X425695Y793667D01*
X425778Y794000D01*
X425695Y794333D01*
X425486Y794625D01*
X425195Y794750D01*
X424903Y794667D01*
X424695Y794458D01*
X424611Y794208D01*
Y793792D01*
X424486Y793417D01*
X424236Y793167D01*
X423945Y793083D01*
X423653Y793167D01*
X423445Y793375D01*
X423320Y793708D01*
X423278Y794000D01*
G01X423570Y796392D02*
X423361Y796683D01*
X423278Y797017D01*
X423361Y797350D01*
X423611Y797642D01*
X423986Y797850D01*
X424361Y797933D01*
X424820D01*
X425195Y797850D01*
X425528Y797642D01*
X425695Y797392D01*
X425778Y797100D01*
X425695Y796767D01*
X425528Y796517D01*
X425278Y796350D01*
X424945Y796267D01*
X424653Y796350D01*
X424361Y796558D01*
X424195Y796808D01*
X424153Y797100D01*
X424236Y797433D01*
X424445Y797683D01*
X424820Y797933D01*
G01X423570Y799492D02*
X423361Y799783D01*
X423278Y800117D01*
X423361Y800450D01*
X423611Y800742D01*
X423986Y800950D01*
X424361Y801033D01*
X424820D01*
X425195Y800950D01*
X425528Y800742D01*
X425695Y800492D01*
X425778Y800200D01*
X425695Y799867D01*
X425528Y799617D01*
X425278Y799450D01*
X424945Y799367D01*
X424653Y799450D01*
X424361Y799658D01*
X424195Y799908D01*
X424153Y800200D01*
X424236Y800533D01*
X424445Y800783D01*
X424820Y801033D01*
G01X419111Y802425D02*
X418903Y802758D01*
X418778Y803133D01*
Y803467D01*
X418903Y803800D01*
X419111Y804050D01*
X419403Y804175D01*
X419695Y804092D01*
X419945Y803883D01*
X420111Y803508D01*
X420195Y803008D01*
X420361Y802717D01*
X420653Y802592D01*
X420945Y802675D01*
X421153Y802883D01*
X421278Y803175D01*
Y803467D01*
X421195Y803758D01*
X420986Y804008D01*
G01X418778Y805567D02*
X421278D01*
Y806608D01*
X421153Y806942D01*
X420986Y807150D01*
X420653Y807233D01*
X420320Y807150D01*
X420111Y806900D01*
X419986Y806608D01*
Y805567D01*
G01Y806608D02*
X418778Y807233D01*
G01Y809500D02*
X418820Y809792D01*
X418945Y810125D01*
X419153Y810333D01*
X419445Y810417D01*
X419736Y810333D01*
X419986Y810083D01*
X420111Y809708D01*
Y809292D01*
X420195Y809042D01*
X420403Y808833D01*
X420695Y808750D01*
X420986Y808875D01*
X421195Y809167D01*
X421278Y809500D01*
X421195Y809833D01*
X420986Y810125D01*
X420695Y810250D01*
X420403Y810167D01*
X420195Y809958D01*
X420111Y809708D01*
Y809292D01*
X419986Y808917D01*
X419736Y808667D01*
X419445Y808583D01*
X419153Y808667D01*
X418945Y808875D01*
X418820Y809208D01*
X418778Y809500D01*
G01X419070Y811892D02*
X418861Y812183D01*
X418778Y812517D01*
X418861Y812850D01*
X419111Y813142D01*
X419486Y813350D01*
X419861Y813433D01*
X420320D01*
X420695Y813350D01*
X421028Y813142D01*
X421195Y812892D01*
X421278Y812600D01*
X421195Y812267D01*
X421028Y812017D01*
X420778Y811850D01*
X420445Y811767D01*
X420153Y811850D01*
X419861Y812058D01*
X419695Y812308D01*
X419653Y812600D01*
X419736Y812933D01*
X419945Y813183D01*
X420320Y813433D01*
G01X419278Y814783D02*
X418986Y815033D01*
X418820Y815367D01*
X418778Y815742D01*
X418820Y816075D01*
X419028Y816408D01*
X419278Y816617D01*
X419528Y816658D01*
X419820Y816575D01*
X420028Y816283D01*
X420111Y815992D01*
Y815617D01*
G01Y815992D02*
X420236Y816242D01*
X420445Y816450D01*
X420695Y816533D01*
X420945Y816450D01*
X421153Y816242D01*
X421278Y815867D01*
X421236Y815492D01*
X421070Y815117D01*
G01X415011Y802425D02*
X414803Y802758D01*
X414678Y803133D01*
Y803467D01*
X414803Y803800D01*
X415011Y804050D01*
X415303Y804175D01*
X415595Y804092D01*
X415845Y803883D01*
X416011Y803508D01*
X416095Y803008D01*
X416261Y802717D01*
X416553Y802592D01*
X416845Y802675D01*
X417053Y802883D01*
X417178Y803175D01*
Y803467D01*
X417095Y803758D01*
X416886Y804008D01*
G01X414678Y805567D02*
X417178D01*
Y806608D01*
X417053Y806942D01*
X416886Y807150D01*
X416553Y807233D01*
X416220Y807150D01*
X416011Y806900D01*
X415886Y806608D01*
Y805567D01*
G01Y806608D02*
X414678Y807233D01*
G01Y809500D02*
X414720Y809792D01*
X414845Y810125D01*
X415053Y810333D01*
X415345Y810417D01*
X415636Y810333D01*
X415886Y810083D01*
X416011Y809708D01*
Y809292D01*
X416095Y809042D01*
X416303Y808833D01*
X416595Y808750D01*
X416886Y808875D01*
X417095Y809167D01*
X417178Y809500D01*
X417095Y809833D01*
X416886Y810125D01*
X416595Y810250D01*
X416303Y810167D01*
X416095Y809958D01*
X416011Y809708D01*
Y809292D01*
X415886Y808917D01*
X415636Y808667D01*
X415345Y808583D01*
X415053Y808667D01*
X414845Y808875D01*
X414720Y809208D01*
X414678Y809500D01*
G01X414970Y811892D02*
X414761Y812183D01*
X414678Y812517D01*
X414761Y812850D01*
X415011Y813142D01*
X415386Y813350D01*
X415761Y813433D01*
X416220D01*
X416595Y813350D01*
X416928Y813142D01*
X417095Y812892D01*
X417178Y812600D01*
X417095Y812267D01*
X416928Y812017D01*
X416678Y811850D01*
X416345Y811767D01*
X416053Y811850D01*
X415761Y812058D01*
X415595Y812308D01*
X415553Y812600D01*
X415636Y812933D01*
X415845Y813183D01*
X416220Y813433D01*
G01X414678Y815617D02*
X415220Y815700D01*
X415678Y815825D01*
X416095Y815992D01*
X416553Y816200D01*
X417178Y816533D01*
Y814867D01*
G01X423278Y814200D02*
X427278D01*
Y806800D01*
G01Y803300D02*
X423278D01*
Y810700D01*
G01X428978Y830500D02*
Y826500D01*
X421578D01*
G01X428978Y848500D02*
Y844500D01*
X421578D01*
G01X428978Y839500D02*
Y835500D01*
X421578D01*
G01X428978Y844000D02*
Y840000D01*
X421578D01*
G01X428978Y835000D02*
Y831000D01*
X421578D01*
G01X428978Y853000D02*
Y849000D01*
X421578D01*
G01X428978Y862000D02*
Y858000D01*
X421578D01*
G01X428978Y857500D02*
Y853500D01*
X421578D01*
G01X425011Y869925D02*
X424803Y870258D01*
X424678Y870633D01*
Y870967D01*
X424803Y871300D01*
X425011Y871550D01*
X425303Y871675D01*
X425595Y871592D01*
X425845Y871383D01*
X426011Y871008D01*
X426095Y870508D01*
X426261Y870217D01*
X426553Y870092D01*
X426845Y870175D01*
X427053Y870383D01*
X427178Y870675D01*
Y870967D01*
X427095Y871258D01*
X426886Y871508D01*
G01X424678Y873067D02*
X427178D01*
Y874108D01*
X427053Y874442D01*
X426886Y874650D01*
X426553Y874733D01*
X426220Y874650D01*
X426011Y874400D01*
X425886Y874108D01*
Y873067D01*
G01Y874108D02*
X424678Y874733D01*
G01Y877000D02*
X424720Y877292D01*
X424845Y877625D01*
X425053Y877833D01*
X425345Y877917D01*
X425636Y877833D01*
X425886Y877583D01*
X426011Y877208D01*
Y876792D01*
X426095Y876542D01*
X426303Y876333D01*
X426595Y876250D01*
X426886Y876375D01*
X427095Y876667D01*
X427178Y877000D01*
X427095Y877333D01*
X426886Y877625D01*
X426595Y877750D01*
X426303Y877667D01*
X426095Y877458D01*
X426011Y877208D01*
Y876792D01*
X425886Y876417D01*
X425636Y876167D01*
X425345Y876083D01*
X425053Y876167D01*
X424845Y876375D01*
X424720Y876708D01*
X424678Y877000D01*
G01X424970Y879392D02*
X424761Y879683D01*
X424678Y880017D01*
X424761Y880350D01*
X425011Y880642D01*
X425386Y880850D01*
X425761Y880933D01*
X426220D01*
X426595Y880850D01*
X426928Y880642D01*
X427095Y880392D01*
X427178Y880100D01*
X427095Y879767D01*
X426928Y879517D01*
X426678Y879350D01*
X426345Y879267D01*
X426053Y879350D01*
X425761Y879558D01*
X425595Y879808D01*
X425553Y880100D01*
X425636Y880433D01*
X425845Y880683D01*
X426220Y880933D01*
G01X425720Y882408D02*
X426011Y882700D01*
X426178Y882950D01*
X426261Y883283D01*
X426178Y883575D01*
X426011Y883783D01*
X425761Y883950D01*
X425470Y883992D01*
X425220Y883950D01*
X424970Y883783D01*
X424761Y883533D01*
X424678Y883242D01*
X424761Y882908D01*
X425011Y882617D01*
X425386Y882450D01*
X425803Y882408D01*
X426345Y882492D01*
X426636Y882617D01*
X426928Y882825D01*
X427136Y883117D01*
X427178Y883408D01*
X427095Y883700D01*
X426886Y883908D01*
G01X429611Y885425D02*
X429403Y885758D01*
X429278Y886133D01*
Y886467D01*
X429403Y886800D01*
X429611Y887050D01*
X429903Y887175D01*
X430195Y887092D01*
X430445Y886883D01*
X430611Y886508D01*
X430695Y886008D01*
X430861Y885717D01*
X431153Y885592D01*
X431445Y885675D01*
X431653Y885883D01*
X431778Y886175D01*
Y886467D01*
X431695Y886758D01*
X431486Y887008D01*
G01X429278Y888567D02*
X431778D01*
Y889608D01*
X431653Y889942D01*
X431486Y890150D01*
X431153Y890233D01*
X430820Y890150D01*
X430611Y889900D01*
X430486Y889608D01*
Y888567D01*
G01Y889608D02*
X429278Y890233D01*
G01Y892500D02*
X429320Y892792D01*
X429445Y893125D01*
X429653Y893333D01*
X429945Y893417D01*
X430236Y893333D01*
X430486Y893083D01*
X430611Y892708D01*
Y892292D01*
X430695Y892042D01*
X430903Y891833D01*
X431195Y891750D01*
X431486Y891875D01*
X431695Y892167D01*
X431778Y892500D01*
X431695Y892833D01*
X431486Y893125D01*
X431195Y893250D01*
X430903Y893167D01*
X430695Y892958D01*
X430611Y892708D01*
Y892292D01*
X430486Y891917D01*
X430236Y891667D01*
X429945Y891583D01*
X429653Y891667D01*
X429445Y891875D01*
X429320Y892208D01*
X429278Y892500D01*
G01X429570Y894892D02*
X429361Y895183D01*
X429278Y895517D01*
X429361Y895850D01*
X429611Y896142D01*
X429986Y896350D01*
X430361Y896433D01*
X430820D01*
X431195Y896350D01*
X431528Y896142D01*
X431695Y895892D01*
X431778Y895600D01*
X431695Y895267D01*
X431528Y895017D01*
X431278Y894850D01*
X430945Y894767D01*
X430653Y894850D01*
X430361Y895058D01*
X430195Y895308D01*
X430153Y895600D01*
X430236Y895933D01*
X430445Y896183D01*
X430820Y896433D01*
G01X429278Y898700D02*
X429320Y898992D01*
X429445Y899325D01*
X429653Y899533D01*
X429945Y899617D01*
X430236Y899533D01*
X430486Y899283D01*
X430611Y898908D01*
Y898492D01*
X430695Y898242D01*
X430903Y898033D01*
X431195Y897950D01*
X431486Y898075D01*
X431695Y898367D01*
X431778Y898700D01*
X431695Y899033D01*
X431486Y899325D01*
X431195Y899450D01*
X430903Y899367D01*
X430695Y899158D01*
X430611Y898908D01*
Y898492D01*
X430486Y898117D01*
X430236Y897867D01*
X429945Y897783D01*
X429653Y897867D01*
X429445Y898075D01*
X429320Y898408D01*
X429278Y898700D01*
G01X421833Y934925D02*
X421625Y935258D01*
X421500Y935633D01*
Y935967D01*
X421625Y936300D01*
X421833Y936550D01*
X422125Y936675D01*
X422417Y936592D01*
X422667Y936383D01*
X422833Y936008D01*
X422917Y935508D01*
X423083Y935217D01*
X423375Y935092D01*
X423667Y935175D01*
X423875Y935383D01*
X424000Y935675D01*
Y935967D01*
X423917Y936258D01*
X423708Y936508D01*
G01X421500Y938067D02*
X424000D01*
Y939108D01*
X423875Y939442D01*
X423708Y939650D01*
X423375Y939733D01*
X423042Y939650D01*
X422833Y939400D01*
X422708Y939108D01*
Y938067D01*
G01Y939108D02*
X421500Y939733D01*
G01Y942000D02*
X421542Y942292D01*
X421667Y942625D01*
X421875Y942833D01*
X422167Y942917D01*
X422458Y942833D01*
X422708Y942583D01*
X422833Y942208D01*
Y941792D01*
X422917Y941542D01*
X423125Y941333D01*
X423417Y941250D01*
X423708Y941375D01*
X423917Y941667D01*
X424000Y942000D01*
X423917Y942333D01*
X423708Y942625D01*
X423417Y942750D01*
X423125Y942667D01*
X422917Y942458D01*
X422833Y942208D01*
Y941792D01*
X422708Y941417D01*
X422458Y941167D01*
X422167Y941083D01*
X421875Y941167D01*
X421667Y941375D01*
X421542Y941708D01*
X421500Y942000D01*
G01Y945600D02*
X424000D01*
X422208Y944058D01*
Y946142D01*
G01X422000Y947283D02*
X421708Y947533D01*
X421542Y947867D01*
X421500Y948242D01*
X421542Y948575D01*
X421750Y948908D01*
X422000Y949117D01*
X422250Y949158D01*
X422542Y949075D01*
X422750Y948783D01*
X422833Y948492D01*
Y948117D01*
G01Y948492D02*
X422958Y948742D01*
X423167Y948950D01*
X423417Y949033D01*
X423667Y948950D01*
X423875Y948742D01*
X424000Y948367D01*
X423958Y947992D01*
X423792Y947617D01*
G01X425833Y934925D02*
X425625Y935258D01*
X425500Y935633D01*
Y935967D01*
X425625Y936300D01*
X425833Y936550D01*
X426125Y936675D01*
X426417Y936592D01*
X426667Y936383D01*
X426833Y936008D01*
X426917Y935508D01*
X427083Y935217D01*
X427375Y935092D01*
X427667Y935175D01*
X427875Y935383D01*
X428000Y935675D01*
Y935967D01*
X427917Y936258D01*
X427708Y936508D01*
G01X425500Y938067D02*
X428000D01*
Y939108D01*
X427875Y939442D01*
X427708Y939650D01*
X427375Y939733D01*
X427042Y939650D01*
X426833Y939400D01*
X426708Y939108D01*
Y938067D01*
G01Y939108D02*
X425500Y939733D01*
G01Y942000D02*
X425542Y942292D01*
X425667Y942625D01*
X425875Y942833D01*
X426167Y942917D01*
X426458Y942833D01*
X426708Y942583D01*
X426833Y942208D01*
Y941792D01*
X426917Y941542D01*
X427125Y941333D01*
X427417Y941250D01*
X427708Y941375D01*
X427917Y941667D01*
X428000Y942000D01*
X427917Y942333D01*
X427708Y942625D01*
X427417Y942750D01*
X427125Y942667D01*
X426917Y942458D01*
X426833Y942208D01*
Y941792D01*
X426708Y941417D01*
X426458Y941167D01*
X426167Y941083D01*
X425875Y941167D01*
X425667Y941375D01*
X425542Y941708D01*
X425500Y942000D01*
G01Y945600D02*
X428000D01*
X426208Y944058D01*
Y946142D01*
G01X425500Y948700D02*
X428000D01*
X426208Y947158D01*
Y949242D01*
G01X415000Y946200D02*
X419000D01*
Y938800D01*
G01X449475Y24333D02*
X449142Y24125D01*
X448767Y24000D01*
X448433D01*
X448100Y24125D01*
X447850Y24333D01*
X447725Y24625D01*
X447808Y24917D01*
X448017Y25167D01*
X448392Y25333D01*
X448892Y25417D01*
X449183Y25583D01*
X449308Y25875D01*
X449225Y26167D01*
X449017Y26375D01*
X448725Y26500D01*
X448433D01*
X448142Y26417D01*
X447892Y26208D01*
G01X445500Y24000D02*
X445833Y24042D01*
X446125Y24208D01*
X446375Y24458D01*
X446542Y24750D01*
X446625Y25083D01*
Y25417D01*
X446542Y25750D01*
X446375Y26042D01*
X446125Y26292D01*
X445833Y26458D01*
X445500Y26500D01*
X445167Y26458D01*
X444875Y26292D01*
X444625Y26042D01*
X444458Y25750D01*
X444375Y25417D01*
Y25083D01*
X444458Y24750D01*
X444625Y24458D01*
X444875Y24208D01*
X445167Y24042D01*
X445500Y24000D01*
G01X445167Y24667D02*
X444667Y24000D01*
G01X443192Y26083D02*
X442942Y26333D01*
X442650Y26458D01*
X442317Y26500D01*
X441900Y26417D01*
X441608Y26208D01*
X441525Y25958D01*
X441567Y25708D01*
X441733Y25500D01*
X442567Y25083D01*
X442942Y24792D01*
X443192Y24375D01*
X443275Y24000D01*
X441525D01*
G01X440373Y40425D02*
X440165Y40758D01*
X440040Y41133D01*
Y41467D01*
X440165Y41800D01*
X440373Y42050D01*
X440665Y42175D01*
X440957Y42092D01*
X441207Y41883D01*
X441373Y41508D01*
X441457Y41008D01*
X441623Y40717D01*
X441915Y40592D01*
X442207Y40675D01*
X442415Y40883D01*
X442540Y41175D01*
Y41467D01*
X442457Y41758D01*
X442248Y42008D01*
G01X442540Y44400D02*
X440040D01*
G01X442540Y43442D02*
Y45358D01*
G01X440040Y46667D02*
X442540D01*
Y47667D01*
X442415Y48000D01*
X442123Y48250D01*
X441790Y48333D01*
X441457Y48250D01*
X441207Y48042D01*
X441082Y47667D01*
Y46667D01*
G01X440415Y49683D02*
X440207Y49933D01*
X440082Y50225D01*
X440040Y50600D01*
X440123Y50975D01*
X440290Y51267D01*
X440582Y51475D01*
X440915Y51517D01*
X441248Y51433D01*
X441457Y51225D01*
X441623Y50933D01*
X441665Y50642D01*
X441623Y50350D01*
X441457Y49975D01*
X442540Y50100D01*
Y51225D01*
G01X440040Y53700D02*
X442540D01*
X442040Y53200D01*
G01X440040D02*
Y54200D01*
G01X429762Y39925D02*
X429554Y40258D01*
X429429Y40633D01*
Y40967D01*
X429554Y41300D01*
X429762Y41550D01*
X430054Y41675D01*
X430346Y41592D01*
X430596Y41383D01*
X430762Y41008D01*
X430846Y40508D01*
X431012Y40217D01*
X431304Y40092D01*
X431596Y40175D01*
X431804Y40383D01*
X431929Y40675D01*
Y40967D01*
X431846Y41258D01*
X431637Y41508D01*
G01X431929Y43900D02*
X429429D01*
G01X431929Y42942D02*
Y44858D01*
G01X429429Y46167D02*
X431929D01*
Y47167D01*
X431804Y47500D01*
X431512Y47750D01*
X431179Y47833D01*
X430846Y47750D01*
X430596Y47542D01*
X430471Y47167D01*
Y46167D01*
G01X429804Y49183D02*
X429596Y49433D01*
X429471Y49725D01*
X429429Y50100D01*
X429512Y50475D01*
X429679Y50767D01*
X429971Y50975D01*
X430304Y51017D01*
X430637Y50933D01*
X430846Y50725D01*
X431012Y50433D01*
X431054Y50142D01*
X431012Y49850D01*
X430846Y49475D01*
X431929Y49600D01*
Y50725D01*
G01X431512Y52408D02*
X431762Y52658D01*
X431887Y52950D01*
X431929Y53283D01*
X431846Y53700D01*
X431637Y53992D01*
X431387Y54075D01*
X431137Y54033D01*
X430929Y53867D01*
X430512Y53033D01*
X430221Y52658D01*
X429804Y52408D01*
X429429Y52325D01*
Y54075D01*
G01X444262Y40425D02*
X444054Y40758D01*
X443929Y41133D01*
Y41467D01*
X444054Y41800D01*
X444262Y42050D01*
X444554Y42175D01*
X444846Y42092D01*
X445096Y41883D01*
X445262Y41508D01*
X445346Y41008D01*
X445512Y40717D01*
X445804Y40592D01*
X446096Y40675D01*
X446304Y40883D01*
X446429Y41175D01*
Y41467D01*
X446346Y41758D01*
X446137Y42008D01*
G01X446429Y44400D02*
X443929D01*
G01X446429Y43442D02*
Y45358D01*
G01X443929Y46667D02*
X446429D01*
Y47667D01*
X446304Y48000D01*
X446012Y48250D01*
X445679Y48333D01*
X445346Y48250D01*
X445096Y48042D01*
X444971Y47667D01*
Y46667D01*
G01X443929Y50517D02*
X444471Y50600D01*
X444929Y50725D01*
X445346Y50892D01*
X445804Y51100D01*
X446429Y51433D01*
Y49767D01*
G01X443929Y53700D02*
X443971Y53992D01*
X444096Y54325D01*
X444304Y54533D01*
X444596Y54617D01*
X444887Y54533D01*
X445137Y54283D01*
X445262Y53908D01*
Y53492D01*
X445346Y53242D01*
X445554Y53033D01*
X445846Y52950D01*
X446137Y53075D01*
X446346Y53367D01*
X446429Y53700D01*
X446346Y54033D01*
X446137Y54325D01*
X445846Y54450D01*
X445554Y54367D01*
X445346Y54158D01*
X445262Y53908D01*
Y53492D01*
X445137Y53117D01*
X444887Y52867D01*
X444596Y52783D01*
X444304Y52867D01*
X444096Y53075D01*
X443971Y53408D01*
X443929Y53700D01*
G01X434373Y40375D02*
X434165Y40708D01*
X434040Y41083D01*
Y41417D01*
X434165Y41750D01*
X434373Y42000D01*
X434665Y42125D01*
X434957Y42042D01*
X435207Y41833D01*
X435373Y41458D01*
X435457Y40958D01*
X435623Y40667D01*
X435915Y40542D01*
X436207Y40625D01*
X436415Y40833D01*
X436540Y41125D01*
Y41417D01*
X436457Y41708D01*
X436248Y41958D01*
G01X436540Y44350D02*
X434040D01*
G01X436540Y43392D02*
Y45308D01*
G01X434040Y46617D02*
X436540D01*
Y47617D01*
X436415Y47950D01*
X436123Y48200D01*
X435790Y48283D01*
X435457Y48200D01*
X435207Y47992D01*
X435082Y47617D01*
Y46617D01*
G01X434040Y50550D02*
X436540D01*
X436040Y50050D01*
G01X434040D02*
Y51050D01*
G01X434540Y52733D02*
X434248Y52983D01*
X434082Y53317D01*
X434040Y53692D01*
X434082Y54025D01*
X434290Y54358D01*
X434540Y54567D01*
X434790Y54608D01*
X435082Y54525D01*
X435290Y54233D01*
X435373Y53942D01*
Y53567D01*
G01Y53942D02*
X435498Y54192D01*
X435707Y54400D01*
X435957Y54483D01*
X436207Y54400D01*
X436415Y54192D01*
X436540Y53817D01*
X436498Y53442D01*
X436332Y53067D01*
G01X436540Y56750D02*
X436457Y56417D01*
X436248Y56167D01*
X435998Y56000D01*
X435665Y55875D01*
X435290Y55833D01*
X434915Y55875D01*
X434582Y56000D01*
X434332Y56167D01*
X434123Y56417D01*
X434040Y56750D01*
X434123Y57083D01*
X434332Y57333D01*
X434582Y57500D01*
X434915Y57625D01*
X435290Y57667D01*
X435665Y57625D01*
X435998Y57500D01*
X436248Y57333D01*
X436457Y57083D01*
X436540Y56750D01*
G01X451504Y32333D02*
X451171Y32125D01*
X450796Y32000D01*
X450462D01*
X450129Y32125D01*
X449879Y32333D01*
X449754Y32625D01*
X449837Y32917D01*
X450046Y33167D01*
X450421Y33333D01*
X450921Y33417D01*
X451212Y33583D01*
X451337Y33875D01*
X451254Y34167D01*
X451046Y34375D01*
X450754Y34500D01*
X450462D01*
X450171Y34417D01*
X449921Y34208D01*
G01X448362Y32000D02*
Y34500D01*
X447321D01*
X446987Y34375D01*
X446779Y34208D01*
X446696Y33875D01*
X446779Y33542D01*
X447029Y33333D01*
X447321Y33208D01*
X448362D01*
G01X447321D02*
X446696Y32000D01*
G01X445221Y33042D02*
X444929Y33333D01*
X444679Y33500D01*
X444346Y33583D01*
X444054Y33500D01*
X443846Y33333D01*
X443679Y33083D01*
X443637Y32792D01*
X443679Y32542D01*
X443846Y32292D01*
X444096Y32083D01*
X444387Y32000D01*
X444721Y32083D01*
X445012Y32333D01*
X445179Y32708D01*
X445221Y33125D01*
X445137Y33667D01*
X445012Y33958D01*
X444804Y34250D01*
X444512Y34458D01*
X444221Y34500D01*
X443929Y34417D01*
X443721Y34208D01*
G01X442246Y32375D02*
X441996Y32167D01*
X441704Y32042D01*
X441329Y32000D01*
X440954Y32083D01*
X440662Y32250D01*
X440454Y32542D01*
X440412Y32875D01*
X440496Y33208D01*
X440704Y33417D01*
X440996Y33583D01*
X441287Y33625D01*
X441579Y33583D01*
X441954Y33417D01*
X441829Y34500D01*
X440704D01*
G01X439021Y33042D02*
X438729Y33333D01*
X438479Y33500D01*
X438146Y33583D01*
X437854Y33500D01*
X437646Y33333D01*
X437479Y33083D01*
X437437Y32792D01*
X437479Y32542D01*
X437646Y32292D01*
X437896Y32083D01*
X438187Y32000D01*
X438521Y32083D01*
X438812Y32333D01*
X438979Y32708D01*
X439021Y33125D01*
X438937Y33667D01*
X438812Y33958D01*
X438604Y34250D01*
X438312Y34458D01*
X438021Y34500D01*
X437729Y34417D01*
X437521Y34208D01*
G01X431951Y59625D02*
X431743Y59958D01*
X431618Y60333D01*
Y60667D01*
X431743Y61000D01*
X431951Y61250D01*
X432243Y61375D01*
X432535Y61292D01*
X432785Y61083D01*
X432951Y60708D01*
X433035Y60208D01*
X433201Y59917D01*
X433493Y59792D01*
X433785Y59875D01*
X433993Y60083D01*
X434118Y60375D01*
Y60667D01*
X434035Y60958D01*
X433826Y61208D01*
G01X434118Y63600D02*
X431618D01*
G01X434118Y62642D02*
Y64558D01*
G01X431618Y65867D02*
X434118D01*
Y66867D01*
X433993Y67200D01*
X433701Y67450D01*
X433368Y67533D01*
X433035Y67450D01*
X432785Y67242D01*
X432660Y66867D01*
Y65867D01*
G01X431618Y70300D02*
X434118D01*
X432326Y68758D01*
Y70842D01*
G01X431618Y73400D02*
X434118D01*
X432326Y71858D01*
Y73942D01*
G01X436762Y59925D02*
X436554Y60258D01*
X436429Y60633D01*
Y60967D01*
X436554Y61300D01*
X436762Y61550D01*
X437054Y61675D01*
X437346Y61592D01*
X437596Y61383D01*
X437762Y61008D01*
X437846Y60508D01*
X438012Y60217D01*
X438304Y60092D01*
X438596Y60175D01*
X438804Y60383D01*
X438929Y60675D01*
Y60967D01*
X438846Y61258D01*
X438637Y61508D01*
G01X438929Y63900D02*
X436429D01*
G01X438929Y62942D02*
Y64858D01*
G01X436429Y66167D02*
X438929D01*
Y67167D01*
X438804Y67500D01*
X438512Y67750D01*
X438179Y67833D01*
X437846Y67750D01*
X437596Y67542D01*
X437471Y67167D01*
Y66167D01*
G01X436429Y70600D02*
X438929D01*
X437137Y69058D01*
Y71142D01*
G01X437471Y72408D02*
X437762Y72700D01*
X437929Y72950D01*
X438012Y73283D01*
X437929Y73575D01*
X437762Y73783D01*
X437512Y73950D01*
X437221Y73992D01*
X436971Y73950D01*
X436721Y73783D01*
X436512Y73533D01*
X436429Y73242D01*
X436512Y72908D01*
X436762Y72617D01*
X437137Y72450D01*
X437554Y72408D01*
X438096Y72492D01*
X438387Y72617D01*
X438679Y72825D01*
X438887Y73117D01*
X438929Y73408D01*
X438846Y73700D01*
X438637Y73908D01*
G01X440762Y59925D02*
X440554Y60258D01*
X440429Y60633D01*
Y60967D01*
X440554Y61300D01*
X440762Y61550D01*
X441054Y61675D01*
X441346Y61592D01*
X441596Y61383D01*
X441762Y61008D01*
X441846Y60508D01*
X442012Y60217D01*
X442304Y60092D01*
X442596Y60175D01*
X442804Y60383D01*
X442929Y60675D01*
Y60967D01*
X442846Y61258D01*
X442637Y61508D01*
G01X442929Y63900D02*
X440429D01*
G01X442929Y62942D02*
Y64858D01*
G01X440429Y66167D02*
X442929D01*
Y67167D01*
X442804Y67500D01*
X442512Y67750D01*
X442179Y67833D01*
X441846Y67750D01*
X441596Y67542D01*
X441471Y67167D01*
Y66167D01*
G01X440721Y69392D02*
X440512Y69683D01*
X440429Y70017D01*
X440512Y70350D01*
X440762Y70642D01*
X441137Y70850D01*
X441512Y70933D01*
X441971D01*
X442346Y70850D01*
X442679Y70642D01*
X442846Y70392D01*
X442929Y70100D01*
X442846Y69767D01*
X442679Y69517D01*
X442429Y69350D01*
X442096Y69267D01*
X441804Y69350D01*
X441512Y69558D01*
X441346Y69808D01*
X441304Y70100D01*
X441387Y70433D01*
X441596Y70683D01*
X441971Y70933D01*
G01X442512Y72408D02*
X442762Y72658D01*
X442887Y72950D01*
X442929Y73283D01*
X442846Y73700D01*
X442637Y73992D01*
X442387Y74075D01*
X442137Y74033D01*
X441929Y73867D01*
X441512Y73033D01*
X441221Y72658D01*
X440804Y72408D01*
X440429Y72325D01*
Y74075D01*
G01X432262Y77425D02*
X432054Y77758D01*
X431929Y78133D01*
Y78467D01*
X432054Y78800D01*
X432262Y79050D01*
X432554Y79175D01*
X432846Y79092D01*
X433096Y78883D01*
X433262Y78508D01*
X433346Y78008D01*
X433512Y77717D01*
X433804Y77592D01*
X434096Y77675D01*
X434304Y77883D01*
X434429Y78175D01*
Y78467D01*
X434346Y78758D01*
X434137Y79008D01*
G01X434221Y82317D02*
X434346Y82067D01*
X434429Y81775D01*
Y81442D01*
X434304Y81067D01*
X434096Y80775D01*
X433846Y80567D01*
X433429Y80400D01*
X433054Y80358D01*
X432679Y80442D01*
X432429Y80567D01*
X432179Y80817D01*
X432012Y81108D01*
X431929Y81400D01*
Y81692D01*
X432012Y81983D01*
X432137Y82233D01*
X432304Y82442D01*
G01X432221Y83792D02*
X432012Y84083D01*
X431929Y84417D01*
X432012Y84750D01*
X432262Y85042D01*
X432637Y85250D01*
X433012Y85333D01*
X433471D01*
X433846Y85250D01*
X434179Y85042D01*
X434346Y84792D01*
X434429Y84500D01*
X434346Y84167D01*
X434179Y83917D01*
X433929Y83750D01*
X433596Y83667D01*
X433304Y83750D01*
X433012Y83958D01*
X432846Y84208D01*
X432804Y84500D01*
X432887Y84833D01*
X433096Y85083D01*
X433471Y85333D01*
G01X432304Y86683D02*
X432096Y86933D01*
X431971Y87225D01*
X431929Y87600D01*
X432012Y87975D01*
X432179Y88267D01*
X432471Y88475D01*
X432804Y88517D01*
X433137Y88433D01*
X433346Y88225D01*
X433512Y87933D01*
X433554Y87642D01*
X433512Y87350D01*
X433346Y86975D01*
X434429Y87100D01*
Y88225D01*
G01X431929Y90700D02*
X434429D01*
X433929Y90200D01*
G01X431929D02*
Y91200D01*
G01X436373Y77425D02*
X436165Y77758D01*
X436040Y78133D01*
Y78467D01*
X436165Y78800D01*
X436373Y79050D01*
X436665Y79175D01*
X436957Y79092D01*
X437207Y78883D01*
X437373Y78508D01*
X437457Y78008D01*
X437623Y77717D01*
X437915Y77592D01*
X438207Y77675D01*
X438415Y77883D01*
X438540Y78175D01*
Y78467D01*
X438457Y78758D01*
X438248Y79008D01*
G01X438540Y81400D02*
X436040D01*
G01X438540Y80442D02*
Y82358D01*
G01X436040Y83667D02*
X438540D01*
Y84667D01*
X438415Y85000D01*
X438123Y85250D01*
X437790Y85333D01*
X437457Y85250D01*
X437207Y85042D01*
X437082Y84667D01*
Y83667D01*
G01X438123Y86808D02*
X438373Y87058D01*
X438498Y87350D01*
X438540Y87683D01*
X438457Y88100D01*
X438248Y88392D01*
X437998Y88475D01*
X437748Y88433D01*
X437540Y88267D01*
X437123Y87433D01*
X436832Y87058D01*
X436415Y86808D01*
X436040Y86725D01*
Y88475D01*
G01Y90617D02*
X436582Y90700D01*
X437040Y90825D01*
X437457Y90992D01*
X437915Y91200D01*
X438540Y91533D01*
Y89867D01*
G01X440262Y77425D02*
X440054Y77758D01*
X439929Y78133D01*
Y78467D01*
X440054Y78800D01*
X440262Y79050D01*
X440554Y79175D01*
X440846Y79092D01*
X441096Y78883D01*
X441262Y78508D01*
X441346Y78008D01*
X441512Y77717D01*
X441804Y77592D01*
X442096Y77675D01*
X442304Y77883D01*
X442429Y78175D01*
Y78467D01*
X442346Y78758D01*
X442137Y79008D01*
G01X442429Y81400D02*
X439929D01*
G01X442429Y80442D02*
Y82358D01*
G01X439929Y83667D02*
X442429D01*
Y84667D01*
X442304Y85000D01*
X442012Y85250D01*
X441679Y85333D01*
X441346Y85250D01*
X441096Y85042D01*
X440971Y84667D01*
Y83667D01*
G01X439929Y87517D02*
X440471Y87600D01*
X440929Y87725D01*
X441346Y87892D01*
X441804Y88100D01*
X442429Y88433D01*
Y86767D01*
G01X439929Y90617D02*
X440471Y90700D01*
X440929Y90825D01*
X441346Y90992D01*
X441804Y91200D01*
X442429Y91533D01*
Y89867D01*
G01X444373Y77375D02*
X444165Y77708D01*
X444040Y78083D01*
Y78417D01*
X444165Y78750D01*
X444373Y79000D01*
X444665Y79125D01*
X444957Y79042D01*
X445207Y78833D01*
X445373Y78458D01*
X445457Y77958D01*
X445623Y77667D01*
X445915Y77542D01*
X446207Y77625D01*
X446415Y77833D01*
X446540Y78125D01*
Y78417D01*
X446457Y78708D01*
X446248Y78958D01*
G01X446540Y81350D02*
X444040D01*
G01X446540Y80392D02*
Y82308D01*
G01X444040Y83617D02*
X446540D01*
Y84617D01*
X446415Y84950D01*
X446123Y85200D01*
X445790Y85283D01*
X445457Y85200D01*
X445207Y84992D01*
X445082Y84617D01*
Y83617D01*
G01X444040Y87550D02*
X446540D01*
X446040Y87050D01*
G01X444040D02*
Y88050D01*
G01X444540Y89733D02*
X444248Y89983D01*
X444082Y90317D01*
X444040Y90692D01*
X444082Y91025D01*
X444290Y91358D01*
X444540Y91567D01*
X444790Y91608D01*
X445082Y91525D01*
X445290Y91233D01*
X445373Y90942D01*
Y90567D01*
G01Y90942D02*
X445498Y91192D01*
X445707Y91400D01*
X445957Y91483D01*
X446207Y91400D01*
X446415Y91192D01*
X446540Y90817D01*
X446498Y90442D01*
X446332Y90067D01*
G01X444040Y94250D02*
X446540D01*
X444748Y92708D01*
Y94792D01*
G01X442429Y97300D02*
X444429D01*
G01X442429Y110700D02*
Y97300D01*
G01X444429D02*
Y110700D01*
G01D02*
X442429D01*
G01X435729Y111500D02*
Y115500D01*
X443129D01*
G01X448740Y120000D02*
Y116000D01*
X441340D01*
G01X451629Y115500D02*
Y111500D01*
X444229D01*
G01X471000Y136500D02*
Y133500D01*
X455500D01*
Y137500D01*
X447000D01*
Y136500D01*
X440500D01*
G01X439083Y147701D02*
Y143701D01*
X431683D01*
G01X442500Y163000D02*
X445000D01*
Y171000D01*
G01X451000Y187000D02*
X444500D01*
Y174500D01*
G01X442000Y212000D02*
X529500D01*
Y206500D01*
X574500D01*
X570000Y211000D01*
Y202000D01*
X574500Y206500D01*
G01X451125Y233833D02*
X450792Y233625D01*
X450417Y233500D01*
X450083D01*
X449750Y233625D01*
X449500Y233833D01*
X449375Y234125D01*
X449458Y234417D01*
X449667Y234667D01*
X450042Y234833D01*
X450542Y234917D01*
X450833Y235083D01*
X450958Y235375D01*
X450875Y235667D01*
X450667Y235875D01*
X450375Y236000D01*
X450083D01*
X449792Y235917D01*
X449542Y235708D01*
G01X446233Y235792D02*
X446483Y235917D01*
X446775Y236000D01*
X447108D01*
X447483Y235875D01*
X447775Y235667D01*
X447983Y235417D01*
X448150Y235000D01*
X448192Y234625D01*
X448108Y234250D01*
X447983Y234000D01*
X447733Y233750D01*
X447442Y233583D01*
X447150Y233500D01*
X446858D01*
X446567Y233583D01*
X446317Y233708D01*
X446108Y233875D01*
G01X444050Y233500D02*
Y236000D01*
X444550Y235500D01*
G01Y233500D02*
X443550D01*
G01X440950Y236000D02*
X441283Y235917D01*
X441533Y235708D01*
X441700Y235458D01*
X441825Y235125D01*
X441867Y234750D01*
X441825Y234375D01*
X441700Y234042D01*
X441533Y233792D01*
X441283Y233583D01*
X440950Y233500D01*
X440617Y233583D01*
X440367Y233792D01*
X440200Y234042D01*
X440075Y234375D01*
X440033Y234750D01*
X440075Y235125D01*
X440200Y235458D01*
X440367Y235708D01*
X440617Y235917D01*
X440950Y236000D01*
G01X437850D02*
X438183Y235917D01*
X438433Y235708D01*
X438600Y235458D01*
X438725Y235125D01*
X438767Y234750D01*
X438725Y234375D01*
X438600Y234042D01*
X438433Y233792D01*
X438183Y233583D01*
X437850Y233500D01*
X437517Y233583D01*
X437267Y233792D01*
X437100Y234042D01*
X436975Y234375D01*
X436933Y234750D01*
X436975Y235125D01*
X437100Y235458D01*
X437267Y235708D01*
X437517Y235917D01*
X437850Y236000D01*
G01X435667Y234000D02*
X435417Y233708D01*
X435083Y233542D01*
X434708Y233500D01*
X434375Y233542D01*
X434042Y233750D01*
X433833Y234000D01*
X433792Y234250D01*
X433875Y234542D01*
X434167Y234750D01*
X434458Y234833D01*
X434833D01*
G01X434458D02*
X434208Y234958D01*
X434000Y235167D01*
X433917Y235417D01*
X434000Y235667D01*
X434208Y235875D01*
X434583Y236000D01*
X434958Y235958D01*
X435333Y235792D01*
G01X450075Y269833D02*
X449742Y269625D01*
X449367Y269500D01*
X449033D01*
X448700Y269625D01*
X448450Y269833D01*
X448325Y270125D01*
X448408Y270417D01*
X448617Y270667D01*
X448992Y270833D01*
X449492Y270917D01*
X449783Y271083D01*
X449908Y271375D01*
X449825Y271667D01*
X449617Y271875D01*
X449325Y272000D01*
X449033D01*
X448742Y271917D01*
X448492Y271708D01*
G01X446933Y269500D02*
Y272000D01*
X445892D01*
X445558Y271875D01*
X445350Y271708D01*
X445267Y271375D01*
X445350Y271042D01*
X445600Y270833D01*
X445892Y270708D01*
X446933D01*
G01X445892D02*
X445267Y269500D01*
G01X443083D02*
X443000Y270042D01*
X442875Y270500D01*
X442708Y270917D01*
X442500Y271375D01*
X442167Y272000D01*
X443833D01*
G01X439900D02*
X440233Y271917D01*
X440483Y271708D01*
X440650Y271458D01*
X440775Y271125D01*
X440817Y270750D01*
X440775Y270375D01*
X440650Y270042D01*
X440483Y269792D01*
X440233Y269583D01*
X439900Y269500D01*
X439567Y269583D01*
X439317Y269792D01*
X439150Y270042D01*
X439025Y270375D01*
X438983Y270750D01*
X439025Y271125D01*
X439150Y271458D01*
X439317Y271708D01*
X439567Y271917D01*
X439900Y272000D01*
G01X436300Y269500D02*
Y272000D01*
X437842Y270208D01*
X435758D01*
G01X440388Y275375D02*
X440180Y275708D01*
X440055Y276083D01*
Y276417D01*
X440180Y276750D01*
X440388Y277000D01*
X440680Y277125D01*
X440972Y277042D01*
X441222Y276833D01*
X441388Y276458D01*
X441472Y275958D01*
X441638Y275667D01*
X441930Y275542D01*
X442222Y275625D01*
X442430Y275833D01*
X442555Y276125D01*
Y276417D01*
X442472Y276708D01*
X442263Y276958D01*
G01X442555Y279350D02*
X440055D01*
G01X442555Y278392D02*
Y280308D01*
G01X440055Y281617D02*
X442555D01*
Y282617D01*
X442430Y282950D01*
X442138Y283200D01*
X441805Y283283D01*
X441472Y283200D01*
X441222Y282992D01*
X441097Y282617D01*
Y281617D01*
G01X440055Y285550D02*
X442555D01*
X442055Y285050D01*
G01X440055D02*
Y286050D01*
G01X440430Y287733D02*
X440222Y287983D01*
X440097Y288275D01*
X440055Y288650D01*
X440138Y289025D01*
X440305Y289317D01*
X440597Y289525D01*
X440930Y289567D01*
X441263Y289483D01*
X441472Y289275D01*
X441638Y288983D01*
X441680Y288692D01*
X441638Y288400D01*
X441472Y288025D01*
X442555Y288150D01*
Y289275D01*
G01X440055Y292250D02*
X442555D01*
X440763Y290708D01*
Y292792D01*
G01X444888Y275425D02*
X444680Y275758D01*
X444555Y276133D01*
Y276467D01*
X444680Y276800D01*
X444888Y277050D01*
X445180Y277175D01*
X445472Y277092D01*
X445722Y276883D01*
X445888Y276508D01*
X445972Y276008D01*
X446138Y275717D01*
X446430Y275592D01*
X446722Y275675D01*
X446930Y275883D01*
X447055Y276175D01*
Y276467D01*
X446972Y276758D01*
X446763Y277008D01*
G01X447055Y279400D02*
X444555D01*
G01X447055Y278442D02*
Y280358D01*
G01X444555Y281667D02*
X447055D01*
Y282667D01*
X446930Y283000D01*
X446638Y283250D01*
X446305Y283333D01*
X445972Y283250D01*
X445722Y283042D01*
X445597Y282667D01*
Y281667D01*
G01Y284808D02*
X445888Y285100D01*
X446055Y285350D01*
X446138Y285683D01*
X446055Y285975D01*
X445888Y286183D01*
X445638Y286350D01*
X445347Y286392D01*
X445097Y286350D01*
X444847Y286183D01*
X444638Y285933D01*
X444555Y285642D01*
X444638Y285308D01*
X444888Y285017D01*
X445263Y284850D01*
X445680Y284808D01*
X446222Y284892D01*
X446513Y285017D01*
X446805Y285225D01*
X447013Y285517D01*
X447055Y285808D01*
X446972Y286100D01*
X446763Y286308D01*
G01X446638Y287908D02*
X446888Y288158D01*
X447013Y288450D01*
X447055Y288783D01*
X446972Y289200D01*
X446763Y289492D01*
X446513Y289575D01*
X446263Y289533D01*
X446055Y289367D01*
X445638Y288533D01*
X445347Y288158D01*
X444930Y287908D01*
X444555Y287825D01*
Y289575D01*
G01X437055Y282300D02*
X433055D01*
Y289700D01*
G01X432333Y302875D02*
X432125Y303208D01*
X432000Y303583D01*
Y303917D01*
X432125Y304250D01*
X432333Y304500D01*
X432625Y304625D01*
X432917Y304542D01*
X433167Y304333D01*
X433333Y303958D01*
X433417Y303458D01*
X433583Y303167D01*
X433875Y303042D01*
X434167Y303125D01*
X434375Y303333D01*
X434500Y303625D01*
Y303917D01*
X434417Y304208D01*
X434208Y304458D01*
G01X434292Y307767D02*
X434417Y307517D01*
X434500Y307225D01*
Y306892D01*
X434375Y306517D01*
X434167Y306225D01*
X433917Y306017D01*
X433500Y305850D01*
X433125Y305808D01*
X432750Y305892D01*
X432500Y306017D01*
X432250Y306267D01*
X432083Y306558D01*
X432000Y306850D01*
Y307142D01*
X432083Y307433D01*
X432208Y307683D01*
X432375Y307892D01*
G01X432000Y309950D02*
X434500D01*
X434000Y309450D01*
G01X432000D02*
Y310450D01*
G01X434083Y312258D02*
X434333Y312508D01*
X434458Y312800D01*
X434500Y313133D01*
X434417Y313550D01*
X434208Y313842D01*
X433958Y313925D01*
X433708Y313883D01*
X433500Y313717D01*
X433083Y312883D01*
X432792Y312508D01*
X432375Y312258D01*
X432000Y312175D01*
Y313925D01*
G01X434083Y315358D02*
X434333Y315608D01*
X434458Y315900D01*
X434500Y316233D01*
X434417Y316650D01*
X434208Y316942D01*
X433958Y317025D01*
X433708Y316983D01*
X433500Y316817D01*
X433083Y315983D01*
X432792Y315608D01*
X432375Y315358D01*
X432000Y315275D01*
Y317025D01*
G01X434083Y318458D02*
X434333Y318708D01*
X434458Y319000D01*
X434500Y319333D01*
X434417Y319750D01*
X434208Y320042D01*
X433958Y320125D01*
X433708Y320083D01*
X433500Y319917D01*
X433083Y319083D01*
X432792Y318708D01*
X432375Y318458D01*
X432000Y318375D01*
Y320125D01*
G01X442055Y300700D02*
X446055D01*
Y293300D01*
G01X436833Y297875D02*
X436625Y298208D01*
X436500Y298583D01*
Y298917D01*
X436625Y299250D01*
X436833Y299500D01*
X437125Y299625D01*
X437417Y299542D01*
X437667Y299333D01*
X437833Y298958D01*
X437917Y298458D01*
X438083Y298167D01*
X438375Y298042D01*
X438667Y298125D01*
X438875Y298333D01*
X439000Y298625D01*
Y298917D01*
X438917Y299208D01*
X438708Y299458D01*
G01X438792Y302767D02*
X438917Y302517D01*
X439000Y302225D01*
Y301892D01*
X438875Y301517D01*
X438667Y301225D01*
X438417Y301017D01*
X438000Y300850D01*
X437625Y300808D01*
X437250Y300892D01*
X437000Y301017D01*
X436750Y301267D01*
X436583Y301558D01*
X436500Y301850D01*
Y302142D01*
X436583Y302433D01*
X436708Y302683D01*
X436875Y302892D01*
G01X436500Y304950D02*
X439000D01*
X438500Y304450D01*
G01X436500D02*
Y305450D01*
G01X438583Y307258D02*
X438833Y307508D01*
X438958Y307800D01*
X439000Y308133D01*
X438917Y308550D01*
X438708Y308842D01*
X438458Y308925D01*
X438208Y308883D01*
X438000Y308717D01*
X437583Y307883D01*
X437292Y307508D01*
X436875Y307258D01*
X436500Y307175D01*
Y308925D01*
G01Y311150D02*
X439000D01*
X438500Y310650D01*
G01X436500D02*
Y311650D01*
G01X436875Y313333D02*
X436667Y313583D01*
X436542Y313875D01*
X436500Y314250D01*
X436583Y314625D01*
X436750Y314917D01*
X437042Y315125D01*
X437375Y315167D01*
X437708Y315083D01*
X437917Y314875D01*
X438083Y314583D01*
X438125Y314292D01*
X438083Y314000D01*
X437917Y313625D01*
X439000Y313750D01*
Y314875D01*
G01X459680Y305833D02*
X459347Y305625D01*
X458972Y305500D01*
X458638D01*
X458305Y305625D01*
X458055Y305833D01*
X457930Y306125D01*
X458013Y306417D01*
X458222Y306667D01*
X458597Y306833D01*
X459097Y306917D01*
X459388Y307083D01*
X459513Y307375D01*
X459430Y307667D01*
X459222Y307875D01*
X458930Y308000D01*
X458638D01*
X458347Y307917D01*
X458097Y307708D01*
G01X454788Y307792D02*
X455038Y307917D01*
X455330Y308000D01*
X455663D01*
X456038Y307875D01*
X456330Y307667D01*
X456538Y307417D01*
X456705Y307000D01*
X456747Y306625D01*
X456663Y306250D01*
X456538Y306000D01*
X456288Y305750D01*
X455997Y305583D01*
X455705Y305500D01*
X455413D01*
X455122Y305583D01*
X454872Y305708D01*
X454663Y305875D01*
G01X452605Y305500D02*
Y308000D01*
X453105Y307500D01*
G01Y305500D02*
X452105D01*
G01X450297Y307583D02*
X450047Y307833D01*
X449755Y307958D01*
X449422Y308000D01*
X449005Y307917D01*
X448713Y307708D01*
X448630Y307458D01*
X448672Y307208D01*
X448838Y307000D01*
X449672Y306583D01*
X450047Y306292D01*
X450297Y305875D01*
X450380Y305500D01*
X448630D01*
G01X447322Y306000D02*
X447072Y305708D01*
X446738Y305542D01*
X446363Y305500D01*
X446030Y305542D01*
X445697Y305750D01*
X445488Y306000D01*
X445447Y306250D01*
X445530Y306542D01*
X445822Y306750D01*
X446113Y306833D01*
X446488D01*
G01X446113D02*
X445863Y306958D01*
X445655Y307167D01*
X445572Y307417D01*
X445655Y307667D01*
X445863Y307875D01*
X446238Y308000D01*
X446613Y307958D01*
X446988Y307792D01*
G01X444222Y306000D02*
X443972Y305708D01*
X443638Y305542D01*
X443263Y305500D01*
X442930Y305542D01*
X442597Y305750D01*
X442388Y306000D01*
X442347Y306250D01*
X442430Y306542D01*
X442722Y306750D01*
X443013Y306833D01*
X443388D01*
G01X443013D02*
X442763Y306958D01*
X442555Y307167D01*
X442472Y307417D01*
X442555Y307667D01*
X442763Y307875D01*
X443138Y308000D01*
X443513Y307958D01*
X443888Y307792D01*
G01X460625Y333333D02*
X460292Y333125D01*
X459917Y333000D01*
X459583D01*
X459250Y333125D01*
X459000Y333333D01*
X458875Y333625D01*
X458958Y333917D01*
X459167Y334167D01*
X459542Y334333D01*
X460042Y334417D01*
X460333Y334583D01*
X460458Y334875D01*
X460375Y335167D01*
X460167Y335375D01*
X459875Y335500D01*
X459583D01*
X459292Y335417D01*
X459042Y335208D01*
G01X455733Y335292D02*
X455983Y335417D01*
X456275Y335500D01*
X456608D01*
X456983Y335375D01*
X457275Y335167D01*
X457483Y334917D01*
X457650Y334500D01*
X457692Y334125D01*
X457608Y333750D01*
X457483Y333500D01*
X457233Y333250D01*
X456942Y333083D01*
X456650Y333000D01*
X456358D01*
X456067Y333083D01*
X455817Y333208D01*
X455608Y333375D01*
G01X453550Y333000D02*
Y335500D01*
X454050Y335000D01*
G01Y333000D02*
X453050D01*
G01X451242Y335083D02*
X450992Y335333D01*
X450700Y335458D01*
X450367Y335500D01*
X449950Y335417D01*
X449658Y335208D01*
X449575Y334958D01*
X449617Y334708D01*
X449783Y334500D01*
X450617Y334083D01*
X450992Y333792D01*
X451242Y333375D01*
X451325Y333000D01*
X449575D01*
G01X448267Y333500D02*
X448017Y333208D01*
X447683Y333042D01*
X447308Y333000D01*
X446975Y333042D01*
X446642Y333250D01*
X446433Y333500D01*
X446392Y333750D01*
X446475Y334042D01*
X446767Y334250D01*
X447058Y334333D01*
X447433D01*
G01X447058D02*
X446808Y334458D01*
X446600Y334667D01*
X446517Y334917D01*
X446600Y335167D01*
X446808Y335375D01*
X447183Y335500D01*
X447558Y335458D01*
X447933Y335292D01*
G01X443750Y333000D02*
Y335500D01*
X445292Y333708D01*
X443208D01*
G01X439333Y329925D02*
X439125Y330258D01*
X439000Y330633D01*
Y330967D01*
X439125Y331300D01*
X439333Y331550D01*
X439625Y331675D01*
X439917Y331592D01*
X440167Y331383D01*
X440333Y331008D01*
X440417Y330508D01*
X440583Y330217D01*
X440875Y330092D01*
X441167Y330175D01*
X441375Y330383D01*
X441500Y330675D01*
Y330967D01*
X441417Y331258D01*
X441208Y331508D01*
G01X441500Y333900D02*
X439000D01*
G01X441500Y332942D02*
Y334858D01*
G01X439000Y336167D02*
X441500D01*
Y337167D01*
X441375Y337500D01*
X441083Y337750D01*
X440750Y337833D01*
X440417Y337750D01*
X440167Y337542D01*
X440042Y337167D01*
Y336167D01*
G01X439375Y339183D02*
X439167Y339433D01*
X439042Y339725D01*
X439000Y340100D01*
X439083Y340475D01*
X439250Y340767D01*
X439542Y340975D01*
X439875Y341017D01*
X440208Y340933D01*
X440417Y340725D01*
X440583Y340433D01*
X440625Y340142D01*
X440583Y339850D01*
X440417Y339475D01*
X441500Y339600D01*
Y340725D01*
G01X439000Y343117D02*
X439542Y343200D01*
X440000Y343325D01*
X440417Y343492D01*
X440875Y343700D01*
X441500Y344033D01*
Y342367D01*
G01X432523Y321583D02*
X428523D01*
Y328983D01*
G01X448575Y351833D02*
X448242Y351625D01*
X447867Y351500D01*
X447533D01*
X447200Y351625D01*
X446950Y351833D01*
X446825Y352125D01*
X446908Y352417D01*
X447117Y352667D01*
X447492Y352833D01*
X447992Y352917D01*
X448283Y353083D01*
X448408Y353375D01*
X448325Y353667D01*
X448117Y353875D01*
X447825Y354000D01*
X447533D01*
X447242Y353917D01*
X446992Y353708D01*
G01X444600Y354000D02*
Y351500D01*
G01X445558Y354000D02*
X443642D01*
G01X442333Y351500D02*
Y354000D01*
X441333D01*
X441000Y353875D01*
X440750Y353583D01*
X440667Y353250D01*
X440750Y352917D01*
X440958Y352667D01*
X441333Y352542D01*
X442333D01*
G01X439192D02*
X438900Y352833D01*
X438650Y353000D01*
X438317Y353083D01*
X438025Y353000D01*
X437817Y352833D01*
X437650Y352583D01*
X437608Y352292D01*
X437650Y352042D01*
X437817Y351792D01*
X438067Y351583D01*
X438358Y351500D01*
X438692Y351583D01*
X438983Y351833D01*
X439150Y352208D01*
X439192Y352625D01*
X439108Y353167D01*
X438983Y353458D01*
X438775Y353750D01*
X438483Y353958D01*
X438192Y354000D01*
X437900Y353917D01*
X437692Y353708D01*
G01X436008Y351792D02*
X435717Y351583D01*
X435383Y351500D01*
X435050Y351583D01*
X434758Y351833D01*
X434550Y352208D01*
X434467Y352583D01*
Y353042D01*
X434550Y353417D01*
X434758Y353750D01*
X435008Y353917D01*
X435300Y354000D01*
X435633Y353917D01*
X435883Y353750D01*
X436050Y353500D01*
X436133Y353167D01*
X436050Y352875D01*
X435842Y352583D01*
X435592Y352417D01*
X435300Y352375D01*
X434967Y352458D01*
X434717Y352667D01*
X434467Y353042D01*
G01X439088Y392375D02*
X438880Y392708D01*
X438755Y393083D01*
Y393417D01*
X438880Y393750D01*
X439088Y394000D01*
X439380Y394125D01*
X439672Y394042D01*
X439922Y393833D01*
X440088Y393458D01*
X440172Y392958D01*
X440338Y392667D01*
X440630Y392542D01*
X440922Y392625D01*
X441130Y392833D01*
X441255Y393125D01*
Y393417D01*
X441172Y393708D01*
X440963Y393958D01*
G01X441047Y397267D02*
X441172Y397017D01*
X441255Y396725D01*
Y396392D01*
X441130Y396017D01*
X440922Y395725D01*
X440672Y395517D01*
X440255Y395350D01*
X439880Y395308D01*
X439505Y395392D01*
X439255Y395517D01*
X439005Y395767D01*
X438838Y396058D01*
X438755Y396350D01*
Y396642D01*
X438838Y396933D01*
X438963Y397183D01*
X439130Y397392D01*
G01X438755Y399450D02*
X441255D01*
X440755Y398950D01*
G01X438755D02*
Y399950D01*
G01Y402550D02*
X441255D01*
X440755Y402050D01*
G01X438755D02*
Y403050D01*
G01X439255Y404733D02*
X438963Y404983D01*
X438797Y405317D01*
X438755Y405692D01*
X438797Y406025D01*
X439005Y406358D01*
X439255Y406567D01*
X439505Y406608D01*
X439797Y406525D01*
X440005Y406233D01*
X440088Y405942D01*
Y405567D01*
G01Y405942D02*
X440213Y406192D01*
X440422Y406400D01*
X440672Y406483D01*
X440922Y406400D01*
X441130Y406192D01*
X441255Y405817D01*
X441213Y405442D01*
X441047Y405067D01*
G01X439797Y407958D02*
X440088Y408250D01*
X440255Y408500D01*
X440338Y408833D01*
X440255Y409125D01*
X440088Y409333D01*
X439838Y409500D01*
X439547Y409542D01*
X439297Y409500D01*
X439047Y409333D01*
X438838Y409083D01*
X438755Y408792D01*
X438838Y408458D01*
X439088Y408167D01*
X439463Y408000D01*
X439880Y407958D01*
X440422Y408042D01*
X440713Y408167D01*
X441005Y408375D01*
X441213Y408667D01*
X441255Y408958D01*
X441172Y409250D01*
X440963Y409458D01*
G01X431188Y391975D02*
X430980Y392308D01*
X430855Y392683D01*
Y393017D01*
X430980Y393350D01*
X431188Y393600D01*
X431480Y393725D01*
X431772Y393642D01*
X432022Y393433D01*
X432188Y393058D01*
X432272Y392558D01*
X432438Y392267D01*
X432730Y392142D01*
X433022Y392225D01*
X433230Y392433D01*
X433355Y392725D01*
Y393017D01*
X433272Y393308D01*
X433063Y393558D01*
G01X433147Y396867D02*
X433272Y396617D01*
X433355Y396325D01*
Y395992D01*
X433230Y395617D01*
X433022Y395325D01*
X432772Y395117D01*
X432355Y394950D01*
X431980Y394908D01*
X431605Y394992D01*
X431355Y395117D01*
X431105Y395367D01*
X430938Y395658D01*
X430855Y395950D01*
Y396242D01*
X430938Y396533D01*
X431063Y396783D01*
X431230Y396992D01*
G01X430855Y399050D02*
X433355D01*
X432855Y398550D01*
G01X430855D02*
Y399550D01*
G01Y402150D02*
X433355D01*
X432855Y401650D01*
G01X430855D02*
Y402650D01*
G01X431355Y404333D02*
X431063Y404583D01*
X430897Y404917D01*
X430855Y405292D01*
X430897Y405625D01*
X431105Y405958D01*
X431355Y406167D01*
X431605Y406208D01*
X431897Y406125D01*
X432105Y405833D01*
X432188Y405542D01*
Y405167D01*
G01Y405542D02*
X432313Y405792D01*
X432522Y406000D01*
X432772Y406083D01*
X433022Y406000D01*
X433230Y405792D01*
X433355Y405417D01*
X433313Y405042D01*
X433147Y404667D01*
G01X431230Y407433D02*
X431022Y407683D01*
X430897Y407975D01*
X430855Y408350D01*
X430938Y408725D01*
X431105Y409017D01*
X431397Y409225D01*
X431730Y409267D01*
X432063Y409183D01*
X432272Y408975D01*
X432438Y408683D01*
X432480Y408392D01*
X432438Y408100D01*
X432272Y407725D01*
X433355Y407850D01*
Y408975D01*
G01X445888Y403875D02*
X445680Y404208D01*
X445555Y404583D01*
Y404917D01*
X445680Y405250D01*
X445888Y405500D01*
X446180Y405625D01*
X446472Y405542D01*
X446722Y405333D01*
X446888Y404958D01*
X446972Y404458D01*
X447138Y404167D01*
X447430Y404042D01*
X447722Y404125D01*
X447930Y404333D01*
X448055Y404625D01*
Y404917D01*
X447972Y405208D01*
X447763Y405458D01*
G01X447847Y408767D02*
X447972Y408517D01*
X448055Y408225D01*
Y407892D01*
X447930Y407517D01*
X447722Y407225D01*
X447472Y407017D01*
X447055Y406850D01*
X446680Y406808D01*
X446305Y406892D01*
X446055Y407017D01*
X445805Y407267D01*
X445638Y407558D01*
X445555Y407850D01*
Y408142D01*
X445638Y408433D01*
X445763Y408683D01*
X445930Y408892D01*
G01X445555Y410950D02*
X448055D01*
X447555Y410450D01*
G01X445555D02*
Y411450D01*
G01X447638Y413258D02*
X447888Y413508D01*
X448013Y413800D01*
X448055Y414133D01*
X447972Y414550D01*
X447763Y414842D01*
X447513Y414925D01*
X447263Y414883D01*
X447055Y414717D01*
X446638Y413883D01*
X446347Y413508D01*
X445930Y413258D01*
X445555Y413175D01*
Y414925D01*
G01Y417150D02*
X448055D01*
X447555Y416650D01*
G01X445555D02*
Y417650D01*
G01X446597Y419458D02*
X446888Y419750D01*
X447055Y420000D01*
X447138Y420333D01*
X447055Y420625D01*
X446888Y420833D01*
X446638Y421000D01*
X446347Y421042D01*
X446097Y421000D01*
X445847Y420833D01*
X445638Y420583D01*
X445555Y420292D01*
X445638Y419958D01*
X445888Y419667D01*
X446263Y419500D01*
X446680Y419458D01*
X447222Y419542D01*
X447513Y419667D01*
X447805Y419875D01*
X448013Y420167D01*
X448055Y420458D01*
X447972Y420750D01*
X447763Y420958D01*
G01X445888Y423375D02*
X445680Y423708D01*
X445555Y424083D01*
Y424417D01*
X445680Y424750D01*
X445888Y425000D01*
X446180Y425125D01*
X446472Y425042D01*
X446722Y424833D01*
X446888Y424458D01*
X446972Y423958D01*
X447138Y423667D01*
X447430Y423542D01*
X447722Y423625D01*
X447930Y423833D01*
X448055Y424125D01*
Y424417D01*
X447972Y424708D01*
X447763Y424958D01*
G01X447847Y428267D02*
X447972Y428017D01*
X448055Y427725D01*
Y427392D01*
X447930Y427017D01*
X447722Y426725D01*
X447472Y426517D01*
X447055Y426350D01*
X446680Y426308D01*
X446305Y426392D01*
X446055Y426517D01*
X445805Y426767D01*
X445638Y427058D01*
X445555Y427350D01*
Y427642D01*
X445638Y427933D01*
X445763Y428183D01*
X445930Y428392D01*
G01X445555Y430450D02*
X448055D01*
X447555Y429950D01*
G01X445555D02*
Y430950D01*
G01X447638Y432758D02*
X447888Y433008D01*
X448013Y433300D01*
X448055Y433633D01*
X447972Y434050D01*
X447763Y434342D01*
X447513Y434425D01*
X447263Y434383D01*
X447055Y434217D01*
X446638Y433383D01*
X446347Y433008D01*
X445930Y432758D01*
X445555Y432675D01*
Y434425D01*
G01X447638Y435858D02*
X447888Y436108D01*
X448013Y436400D01*
X448055Y436733D01*
X447972Y437150D01*
X447763Y437442D01*
X447513Y437525D01*
X447263Y437483D01*
X447055Y437317D01*
X446638Y436483D01*
X446347Y436108D01*
X445930Y435858D01*
X445555Y435775D01*
Y437525D01*
G01X448055Y439750D02*
X447972Y439417D01*
X447763Y439167D01*
X447513Y439000D01*
X447180Y438875D01*
X446805Y438833D01*
X446430Y438875D01*
X446097Y439000D01*
X445847Y439167D01*
X445638Y439417D01*
X445555Y439750D01*
X445638Y440083D01*
X445847Y440333D01*
X446097Y440500D01*
X446430Y440625D01*
X446805Y440667D01*
X447180Y440625D01*
X447513Y440500D01*
X447763Y440333D01*
X447972Y440083D01*
X448055Y439750D01*
G01X454180Y443333D02*
X453847Y443125D01*
X453472Y443000D01*
X453138D01*
X452805Y443125D01*
X452555Y443333D01*
X452430Y443625D01*
X452513Y443917D01*
X452722Y444167D01*
X453097Y444333D01*
X453597Y444417D01*
X453888Y444583D01*
X454013Y444875D01*
X453930Y445167D01*
X453722Y445375D01*
X453430Y445500D01*
X453138D01*
X452847Y445417D01*
X452597Y445208D01*
G01X449288Y445292D02*
X449538Y445417D01*
X449830Y445500D01*
X450163D01*
X450538Y445375D01*
X450830Y445167D01*
X451038Y444917D01*
X451205Y444500D01*
X451247Y444125D01*
X451163Y443750D01*
X451038Y443500D01*
X450788Y443250D01*
X450497Y443083D01*
X450205Y443000D01*
X449913D01*
X449622Y443083D01*
X449372Y443208D01*
X449163Y443375D01*
G01X447105Y443000D02*
Y445500D01*
X447605Y445000D01*
G01Y443000D02*
X446605D01*
G01X444005D02*
Y445500D01*
X444505Y445000D01*
G01Y443000D02*
X443505D01*
G01X441822Y443500D02*
X441572Y443208D01*
X441238Y443042D01*
X440863Y443000D01*
X440530Y443042D01*
X440197Y443250D01*
X439988Y443500D01*
X439947Y443750D01*
X440030Y444042D01*
X440322Y444250D01*
X440613Y444333D01*
X440988D01*
G01X440613D02*
X440363Y444458D01*
X440155Y444667D01*
X440072Y444917D01*
X440155Y445167D01*
X440363Y445375D01*
X440738Y445500D01*
X441113Y445458D01*
X441488Y445292D01*
G01X438513Y443292D02*
X438222Y443083D01*
X437888Y443000D01*
X437555Y443083D01*
X437263Y443333D01*
X437055Y443708D01*
X436972Y444083D01*
Y444542D01*
X437055Y444917D01*
X437263Y445250D01*
X437513Y445417D01*
X437805Y445500D01*
X438138Y445417D01*
X438388Y445250D01*
X438555Y445000D01*
X438638Y444667D01*
X438555Y444375D01*
X438347Y444083D01*
X438097Y443917D01*
X437805Y443875D01*
X437472Y443958D01*
X437222Y444167D01*
X436972Y444542D01*
G01X430111Y786925D02*
X429903Y787258D01*
X429778Y787633D01*
Y787967D01*
X429903Y788300D01*
X430111Y788550D01*
X430403Y788675D01*
X430695Y788592D01*
X430945Y788383D01*
X431111Y788008D01*
X431195Y787508D01*
X431361Y787217D01*
X431653Y787092D01*
X431945Y787175D01*
X432153Y787383D01*
X432278Y787675D01*
Y787967D01*
X432195Y788258D01*
X431986Y788508D01*
G01X429778Y790067D02*
X432278D01*
Y791108D01*
X432153Y791442D01*
X431986Y791650D01*
X431653Y791733D01*
X431320Y791650D01*
X431111Y791400D01*
X430986Y791108D01*
Y790067D01*
G01Y791108D02*
X429778Y791733D01*
G01Y794000D02*
X429820Y794292D01*
X429945Y794625D01*
X430153Y794833D01*
X430445Y794917D01*
X430736Y794833D01*
X430986Y794583D01*
X431111Y794208D01*
Y793792D01*
X431195Y793542D01*
X431403Y793333D01*
X431695Y793250D01*
X431986Y793375D01*
X432195Y793667D01*
X432278Y794000D01*
X432195Y794333D01*
X431986Y794625D01*
X431695Y794750D01*
X431403Y794667D01*
X431195Y794458D01*
X431111Y794208D01*
Y793792D01*
X430986Y793417D01*
X430736Y793167D01*
X430445Y793083D01*
X430153Y793167D01*
X429945Y793375D01*
X429820Y793708D01*
X429778Y794000D01*
G01X430070Y796392D02*
X429861Y796683D01*
X429778Y797017D01*
X429861Y797350D01*
X430111Y797642D01*
X430486Y797850D01*
X430861Y797933D01*
X431320D01*
X431695Y797850D01*
X432028Y797642D01*
X432195Y797392D01*
X432278Y797100D01*
X432195Y796767D01*
X432028Y796517D01*
X431778Y796350D01*
X431445Y796267D01*
X431153Y796350D01*
X430861Y796558D01*
X430695Y796808D01*
X430653Y797100D01*
X430736Y797433D01*
X430945Y797683D01*
X431320Y797933D01*
G01X430153Y799283D02*
X429945Y799533D01*
X429820Y799825D01*
X429778Y800200D01*
X429861Y800575D01*
X430028Y800867D01*
X430320Y801075D01*
X430653Y801117D01*
X430986Y801033D01*
X431195Y800825D01*
X431361Y800533D01*
X431403Y800242D01*
X431361Y799950D01*
X431195Y799575D01*
X432278Y799700D01*
Y800825D01*
G01X429778Y814200D02*
X433778D01*
Y806800D01*
G01Y803300D02*
X429778D01*
Y810700D01*
G01X444011Y795875D02*
X443803Y796208D01*
X443678Y796583D01*
Y796917D01*
X443803Y797250D01*
X444011Y797500D01*
X444303Y797625D01*
X444595Y797542D01*
X444845Y797333D01*
X445011Y796958D01*
X445095Y796458D01*
X445261Y796167D01*
X445553Y796042D01*
X445845Y796125D01*
X446053Y796333D01*
X446178Y796625D01*
Y796917D01*
X446095Y797208D01*
X445886Y797458D01*
G01X445970Y800767D02*
X446095Y800517D01*
X446178Y800225D01*
Y799892D01*
X446053Y799517D01*
X445845Y799225D01*
X445595Y799017D01*
X445178Y798850D01*
X444803Y798808D01*
X444428Y798892D01*
X444178Y799017D01*
X443928Y799267D01*
X443761Y799558D01*
X443678Y799850D01*
Y800142D01*
X443761Y800433D01*
X443886Y800683D01*
X444053Y800892D01*
G01X443678Y802950D02*
X446178D01*
X445678Y802450D01*
G01X443678D02*
Y803450D01*
G01X445761Y805258D02*
X446011Y805508D01*
X446136Y805800D01*
X446178Y806133D01*
X446095Y806550D01*
X445886Y806842D01*
X445636Y806925D01*
X445386Y806883D01*
X445178Y806717D01*
X444761Y805883D01*
X444470Y805508D01*
X444053Y805258D01*
X443678Y805175D01*
Y806925D01*
G01X443970Y808442D02*
X443761Y808733D01*
X443678Y809067D01*
X443761Y809400D01*
X444011Y809692D01*
X444386Y809900D01*
X444761Y809983D01*
X445220D01*
X445595Y809900D01*
X445928Y809692D01*
X446095Y809442D01*
X446178Y809150D01*
X446095Y808817D01*
X445928Y808567D01*
X445678Y808400D01*
X445345Y808317D01*
X445053Y808400D01*
X444761Y808608D01*
X444595Y808858D01*
X444553Y809150D01*
X444636Y809483D01*
X444845Y809733D01*
X445220Y809983D01*
G01X446178Y812250D02*
X446095Y811917D01*
X445886Y811667D01*
X445636Y811500D01*
X445303Y811375D01*
X444928Y811333D01*
X444553Y811375D01*
X444220Y811500D01*
X443970Y811667D01*
X443761Y811917D01*
X443678Y812250D01*
X443761Y812583D01*
X443970Y812833D01*
X444220Y813000D01*
X444553Y813125D01*
X444928Y813167D01*
X445303Y813125D01*
X445636Y813000D01*
X445886Y812833D01*
X446095Y812583D01*
X446178Y812250D01*
G01X438578Y835100D02*
X433578D01*
Y840100D01*
G01X443428Y834000D02*
Y836000D01*
G01X433578Y851900D02*
Y856900D01*
X438578D01*
G01X434478Y846950D02*
X431478D01*
G01X439778Y873800D02*
X435778D01*
Y881200D01*
G01X429278Y877700D02*
X433278D01*
Y870300D01*
G01Y873800D02*
X429278D01*
Y881200D01*
G01X445753Y866833D02*
X445420Y866625D01*
X445045Y866500D01*
X444711D01*
X444378Y866625D01*
X444128Y866833D01*
X444003Y867125D01*
X444086Y867417D01*
X444295Y867667D01*
X444670Y867833D01*
X445170Y867917D01*
X445461Y868083D01*
X445586Y868375D01*
X445503Y868667D01*
X445295Y868875D01*
X445003Y869000D01*
X444711D01*
X444420Y868917D01*
X444170Y868708D01*
G01X442611Y866500D02*
Y869000D01*
X441570D01*
X441236Y868875D01*
X441028Y868708D01*
X440945Y868375D01*
X441028Y868042D01*
X441278Y867833D01*
X441570Y867708D01*
X442611D01*
G01X441570D02*
X440945Y866500D01*
G01X439386Y866792D02*
X439095Y866583D01*
X438761Y866500D01*
X438428Y866583D01*
X438136Y866833D01*
X437928Y867208D01*
X437845Y867583D01*
Y868042D01*
X437928Y868417D01*
X438136Y868750D01*
X438386Y868917D01*
X438678Y869000D01*
X439011Y868917D01*
X439261Y868750D01*
X439428Y868500D01*
X439511Y868167D01*
X439428Y867875D01*
X439220Y867583D01*
X438970Y867417D01*
X438678Y867375D01*
X438345Y867458D01*
X438095Y867667D01*
X437845Y868042D01*
G01X435578Y869000D02*
X435911Y868917D01*
X436161Y868708D01*
X436328Y868458D01*
X436453Y868125D01*
X436495Y867750D01*
X436453Y867375D01*
X436328Y867042D01*
X436161Y866792D01*
X435911Y866583D01*
X435578Y866500D01*
X435245Y866583D01*
X434995Y866792D01*
X434828Y867042D01*
X434703Y867375D01*
X434661Y867750D01*
X434703Y868125D01*
X434828Y868458D01*
X434995Y868708D01*
X435245Y868917D01*
X435578Y869000D01*
G01X433395Y867000D02*
X433145Y866708D01*
X432811Y866542D01*
X432436Y866500D01*
X432103Y866542D01*
X431770Y866750D01*
X431561Y867000D01*
X431520Y867250D01*
X431603Y867542D01*
X431895Y867750D01*
X432186Y867833D01*
X432561D01*
G01X432186D02*
X431936Y867958D01*
X431728Y868167D01*
X431645Y868417D01*
X431728Y868667D01*
X431936Y868875D01*
X432311Y869000D01*
X432686Y868958D01*
X433061Y868792D01*
G01X435778Y877700D02*
X439778D01*
Y870300D01*
G01X436111Y885425D02*
X435903Y885758D01*
X435778Y886133D01*
Y886467D01*
X435903Y886800D01*
X436111Y887050D01*
X436403Y887175D01*
X436695Y887092D01*
X436945Y886883D01*
X437111Y886508D01*
X437195Y886008D01*
X437361Y885717D01*
X437653Y885592D01*
X437945Y885675D01*
X438153Y885883D01*
X438278Y886175D01*
Y886467D01*
X438195Y886758D01*
X437986Y887008D01*
G01X435778Y888567D02*
X438278D01*
Y889608D01*
X438153Y889942D01*
X437986Y890150D01*
X437653Y890233D01*
X437320Y890150D01*
X437111Y889900D01*
X436986Y889608D01*
Y888567D01*
G01Y889608D02*
X435778Y890233D01*
G01Y892500D02*
X435820Y892792D01*
X435945Y893125D01*
X436153Y893333D01*
X436445Y893417D01*
X436736Y893333D01*
X436986Y893083D01*
X437111Y892708D01*
Y892292D01*
X437195Y892042D01*
X437403Y891833D01*
X437695Y891750D01*
X437986Y891875D01*
X438195Y892167D01*
X438278Y892500D01*
X438195Y892833D01*
X437986Y893125D01*
X437695Y893250D01*
X437403Y893167D01*
X437195Y892958D01*
X437111Y892708D01*
Y892292D01*
X436986Y891917D01*
X436736Y891667D01*
X436445Y891583D01*
X436153Y891667D01*
X435945Y891875D01*
X435820Y892208D01*
X435778Y892500D01*
G01X436070Y894892D02*
X435861Y895183D01*
X435778Y895517D01*
X435861Y895850D01*
X436111Y896142D01*
X436486Y896350D01*
X436861Y896433D01*
X437320D01*
X437695Y896350D01*
X438028Y896142D01*
X438195Y895892D01*
X438278Y895600D01*
X438195Y895267D01*
X438028Y895017D01*
X437778Y894850D01*
X437445Y894767D01*
X437153Y894850D01*
X436861Y895058D01*
X436695Y895308D01*
X436653Y895600D01*
X436736Y895933D01*
X436945Y896183D01*
X437320Y896433D01*
G01X435778Y899200D02*
X438278D01*
X436486Y897658D01*
Y899742D01*
G01X433833Y934925D02*
X433625Y935258D01*
X433500Y935633D01*
Y935967D01*
X433625Y936300D01*
X433833Y936550D01*
X434125Y936675D01*
X434417Y936592D01*
X434667Y936383D01*
X434833Y936008D01*
X434917Y935508D01*
X435083Y935217D01*
X435375Y935092D01*
X435667Y935175D01*
X435875Y935383D01*
X436000Y935675D01*
Y935967D01*
X435917Y936258D01*
X435708Y936508D01*
G01X433500Y938067D02*
X436000D01*
Y939108D01*
X435875Y939442D01*
X435708Y939650D01*
X435375Y939733D01*
X435042Y939650D01*
X434833Y939400D01*
X434708Y939108D01*
Y938067D01*
G01Y939108D02*
X433500Y939733D01*
G01Y942000D02*
X433542Y942292D01*
X433667Y942625D01*
X433875Y942833D01*
X434167Y942917D01*
X434458Y942833D01*
X434708Y942583D01*
X434833Y942208D01*
Y941792D01*
X434917Y941542D01*
X435125Y941333D01*
X435417Y941250D01*
X435708Y941375D01*
X435917Y941667D01*
X436000Y942000D01*
X435917Y942333D01*
X435708Y942625D01*
X435417Y942750D01*
X435125Y942667D01*
X434917Y942458D01*
X434833Y942208D01*
Y941792D01*
X434708Y941417D01*
X434458Y941167D01*
X434167Y941083D01*
X433875Y941167D01*
X433667Y941375D01*
X433542Y941708D01*
X433500Y942000D01*
G01Y945600D02*
X436000D01*
X434208Y944058D01*
Y946142D01*
G01X434542Y947408D02*
X434833Y947700D01*
X435000Y947950D01*
X435083Y948283D01*
X435000Y948575D01*
X434833Y948783D01*
X434583Y948950D01*
X434292Y948992D01*
X434042Y948950D01*
X433792Y948783D01*
X433583Y948533D01*
X433500Y948242D01*
X433583Y947908D01*
X433833Y947617D01*
X434208Y947450D01*
X434625Y947408D01*
X435167Y947492D01*
X435458Y947617D01*
X435750Y947825D01*
X435958Y948117D01*
X436000Y948408D01*
X435917Y948700D01*
X435708Y948908D01*
G01X437833Y934925D02*
X437625Y935258D01*
X437500Y935633D01*
Y935967D01*
X437625Y936300D01*
X437833Y936550D01*
X438125Y936675D01*
X438417Y936592D01*
X438667Y936383D01*
X438833Y936008D01*
X438917Y935508D01*
X439083Y935217D01*
X439375Y935092D01*
X439667Y935175D01*
X439875Y935383D01*
X440000Y935675D01*
Y935967D01*
X439917Y936258D01*
X439708Y936508D01*
G01X437500Y938067D02*
X440000D01*
Y939108D01*
X439875Y939442D01*
X439708Y939650D01*
X439375Y939733D01*
X439042Y939650D01*
X438833Y939400D01*
X438708Y939108D01*
Y938067D01*
G01Y939108D02*
X437500Y939733D01*
G01X437792Y941292D02*
X437583Y941583D01*
X437500Y941917D01*
X437583Y942250D01*
X437833Y942542D01*
X438208Y942750D01*
X438583Y942833D01*
X439042D01*
X439417Y942750D01*
X439750Y942542D01*
X439917Y942292D01*
X440000Y942000D01*
X439917Y941667D01*
X439750Y941417D01*
X439500Y941250D01*
X439167Y941167D01*
X438875Y941250D01*
X438583Y941458D01*
X438417Y941708D01*
X438375Y942000D01*
X438458Y942333D01*
X438667Y942583D01*
X439042Y942833D01*
G01X437500Y945600D02*
X440000D01*
X438208Y944058D01*
Y946142D01*
G01X437875Y947283D02*
X437667Y947533D01*
X437542Y947825D01*
X437500Y948200D01*
X437583Y948575D01*
X437750Y948867D01*
X438042Y949075D01*
X438375Y949117D01*
X438708Y949033D01*
X438917Y948825D01*
X439083Y948533D01*
X439125Y948242D01*
X439083Y947950D01*
X438917Y947575D01*
X440000Y947700D01*
Y948825D01*
G01X441833Y934925D02*
X441625Y935258D01*
X441500Y935633D01*
Y935967D01*
X441625Y936300D01*
X441833Y936550D01*
X442125Y936675D01*
X442417Y936592D01*
X442667Y936383D01*
X442833Y936008D01*
X442917Y935508D01*
X443083Y935217D01*
X443375Y935092D01*
X443667Y935175D01*
X443875Y935383D01*
X444000Y935675D01*
Y935967D01*
X443917Y936258D01*
X443708Y936508D01*
G01X441500Y938067D02*
X444000D01*
Y939108D01*
X443875Y939442D01*
X443708Y939650D01*
X443375Y939733D01*
X443042Y939650D01*
X442833Y939400D01*
X442708Y939108D01*
Y938067D01*
G01Y939108D02*
X441500Y939733D01*
G01X441792Y941292D02*
X441583Y941583D01*
X441500Y941917D01*
X441583Y942250D01*
X441833Y942542D01*
X442208Y942750D01*
X442583Y942833D01*
X443042D01*
X443417Y942750D01*
X443750Y942542D01*
X443917Y942292D01*
X444000Y942000D01*
X443917Y941667D01*
X443750Y941417D01*
X443500Y941250D01*
X443167Y941167D01*
X442875Y941250D01*
X442583Y941458D01*
X442417Y941708D01*
X442375Y942000D01*
X442458Y942333D01*
X442667Y942583D01*
X443042Y942833D01*
G01X441500Y945600D02*
X444000D01*
X442208Y944058D01*
Y946142D01*
G01X442542Y947408D02*
X442833Y947700D01*
X443000Y947950D01*
X443083Y948283D01*
X443000Y948575D01*
X442833Y948783D01*
X442583Y948950D01*
X442292Y948992D01*
X442042Y948950D01*
X441792Y948783D01*
X441583Y948533D01*
X441500Y948242D01*
X441583Y947908D01*
X441833Y947617D01*
X442208Y947450D01*
X442625Y947408D01*
X443167Y947492D01*
X443458Y947617D01*
X443750Y947825D01*
X443958Y948117D01*
X444000Y948408D01*
X443917Y948700D01*
X443708Y948908D01*
G01X429833Y934925D02*
X429625Y935258D01*
X429500Y935633D01*
Y935967D01*
X429625Y936300D01*
X429833Y936550D01*
X430125Y936675D01*
X430417Y936592D01*
X430667Y936383D01*
X430833Y936008D01*
X430917Y935508D01*
X431083Y935217D01*
X431375Y935092D01*
X431667Y935175D01*
X431875Y935383D01*
X432000Y935675D01*
Y935967D01*
X431917Y936258D01*
X431708Y936508D01*
G01X429500Y938067D02*
X432000D01*
Y939108D01*
X431875Y939442D01*
X431708Y939650D01*
X431375Y939733D01*
X431042Y939650D01*
X430833Y939400D01*
X430708Y939108D01*
Y938067D01*
G01Y939108D02*
X429500Y939733D01*
G01Y942000D02*
X429542Y942292D01*
X429667Y942625D01*
X429875Y942833D01*
X430167Y942917D01*
X430458Y942833D01*
X430708Y942583D01*
X430833Y942208D01*
Y941792D01*
X430917Y941542D01*
X431125Y941333D01*
X431417Y941250D01*
X431708Y941375D01*
X431917Y941667D01*
X432000Y942000D01*
X431917Y942333D01*
X431708Y942625D01*
X431417Y942750D01*
X431125Y942667D01*
X430917Y942458D01*
X430833Y942208D01*
Y941792D01*
X430708Y941417D01*
X430458Y941167D01*
X430167Y941083D01*
X429875Y941167D01*
X429667Y941375D01*
X429542Y941708D01*
X429500Y942000D01*
G01Y945600D02*
X432000D01*
X430208Y944058D01*
Y946142D01*
G01X429875Y947283D02*
X429667Y947533D01*
X429542Y947825D01*
X429500Y948200D01*
X429583Y948575D01*
X429750Y948867D01*
X430042Y949075D01*
X430375Y949117D01*
X430708Y949033D01*
X430917Y948825D01*
X431083Y948533D01*
X431125Y948242D01*
X431083Y947950D01*
X430917Y947575D01*
X432000Y947700D01*
Y948825D01*
G01X445833Y934925D02*
X445625Y935258D01*
X445500Y935633D01*
Y935967D01*
X445625Y936300D01*
X445833Y936550D01*
X446125Y936675D01*
X446417Y936592D01*
X446667Y936383D01*
X446833Y936008D01*
X446917Y935508D01*
X447083Y935217D01*
X447375Y935092D01*
X447667Y935175D01*
X447875Y935383D01*
X448000Y935675D01*
Y935967D01*
X447917Y936258D01*
X447708Y936508D01*
G01X445500Y938067D02*
X448000D01*
Y939108D01*
X447875Y939442D01*
X447708Y939650D01*
X447375Y939733D01*
X447042Y939650D01*
X446833Y939400D01*
X446708Y939108D01*
Y938067D01*
G01Y939108D02*
X445500Y939733D01*
G01X445792Y941292D02*
X445583Y941583D01*
X445500Y941917D01*
X445583Y942250D01*
X445833Y942542D01*
X446208Y942750D01*
X446583Y942833D01*
X447042D01*
X447417Y942750D01*
X447750Y942542D01*
X447917Y942292D01*
X448000Y942000D01*
X447917Y941667D01*
X447750Y941417D01*
X447500Y941250D01*
X447167Y941167D01*
X446875Y941250D01*
X446583Y941458D01*
X446417Y941708D01*
X446375Y942000D01*
X446458Y942333D01*
X446667Y942583D01*
X447042Y942833D01*
G01X445500Y945600D02*
X448000D01*
X446208Y944058D01*
Y946142D01*
G01X445500Y948117D02*
X446042Y948200D01*
X446500Y948325D01*
X446917Y948492D01*
X447375Y948700D01*
X448000Y949033D01*
Y947367D01*
G01X475575Y24833D02*
X475242Y24625D01*
X474867Y24500D01*
X474533D01*
X474200Y24625D01*
X473950Y24833D01*
X473825Y25125D01*
X473908Y25417D01*
X474117Y25667D01*
X474492Y25833D01*
X474992Y25917D01*
X475283Y26083D01*
X475408Y26375D01*
X475325Y26667D01*
X475117Y26875D01*
X474825Y27000D01*
X474533D01*
X474242Y26917D01*
X473992Y26708D01*
G01X472433Y24500D02*
Y27000D01*
X471392D01*
X471058Y26875D01*
X470850Y26708D01*
X470767Y26375D01*
X470850Y26042D01*
X471100Y25833D01*
X471392Y25708D01*
X472433D01*
G01X471392D02*
X470767Y24500D01*
G01X469292Y25542D02*
X469000Y25833D01*
X468750Y26000D01*
X468417Y26083D01*
X468125Y26000D01*
X467917Y25833D01*
X467750Y25583D01*
X467708Y25292D01*
X467750Y25042D01*
X467917Y24792D01*
X468167Y24583D01*
X468458Y24500D01*
X468792Y24583D01*
X469083Y24833D01*
X469250Y25208D01*
X469292Y25625D01*
X469208Y26167D01*
X469083Y26458D01*
X468875Y26750D01*
X468583Y26958D01*
X468292Y27000D01*
X468000Y26917D01*
X467792Y26708D01*
G01X466317Y24875D02*
X466067Y24667D01*
X465775Y24542D01*
X465400Y24500D01*
X465025Y24583D01*
X464733Y24750D01*
X464525Y25042D01*
X464483Y25375D01*
X464567Y25708D01*
X464775Y25917D01*
X465067Y26083D01*
X465358Y26125D01*
X465650Y26083D01*
X466025Y25917D01*
X465900Y27000D01*
X464775D01*
G01X463092Y26583D02*
X462842Y26833D01*
X462550Y26958D01*
X462217Y27000D01*
X461800Y26917D01*
X461508Y26708D01*
X461425Y26458D01*
X461467Y26208D01*
X461633Y26000D01*
X462467Y25583D01*
X462842Y25292D01*
X463092Y24875D01*
X463175Y24500D01*
X461425D01*
G01X448262Y40375D02*
X448054Y40708D01*
X447929Y41083D01*
Y41417D01*
X448054Y41750D01*
X448262Y42000D01*
X448554Y42125D01*
X448846Y42042D01*
X449096Y41833D01*
X449262Y41458D01*
X449346Y40958D01*
X449512Y40667D01*
X449804Y40542D01*
X450096Y40625D01*
X450304Y40833D01*
X450429Y41125D01*
Y41417D01*
X450346Y41708D01*
X450137Y41958D01*
G01X450429Y44350D02*
X447929D01*
G01X450429Y43392D02*
Y45308D01*
G01X447929Y46617D02*
X450429D01*
Y47617D01*
X450304Y47950D01*
X450012Y48200D01*
X449679Y48283D01*
X449346Y48200D01*
X449096Y47992D01*
X448971Y47617D01*
Y46617D01*
G01X447929Y50550D02*
X450429D01*
X449929Y50050D01*
G01X447929D02*
Y51050D01*
G01X448429Y52733D02*
X448137Y52983D01*
X447971Y53317D01*
X447929Y53692D01*
X447971Y54025D01*
X448179Y54358D01*
X448429Y54567D01*
X448679Y54608D01*
X448971Y54525D01*
X449179Y54233D01*
X449262Y53942D01*
Y53567D01*
G01Y53942D02*
X449387Y54192D01*
X449596Y54400D01*
X449846Y54483D01*
X450096Y54400D01*
X450304Y54192D01*
X450429Y53817D01*
X450387Y53442D01*
X450221Y53067D01*
G01X448221Y56042D02*
X448012Y56333D01*
X447929Y56667D01*
X448012Y57000D01*
X448262Y57292D01*
X448637Y57500D01*
X449012Y57583D01*
X449471D01*
X449846Y57500D01*
X450179Y57292D01*
X450346Y57042D01*
X450429Y56750D01*
X450346Y56417D01*
X450179Y56167D01*
X449929Y56000D01*
X449596Y55917D01*
X449304Y56000D01*
X449012Y56208D01*
X448846Y56458D01*
X448804Y56750D01*
X448887Y57083D01*
X449096Y57333D01*
X449471Y57583D01*
G01X462004Y36333D02*
X461671Y36125D01*
X461296Y36000D01*
X460962D01*
X460629Y36125D01*
X460379Y36333D01*
X460254Y36625D01*
X460337Y36917D01*
X460546Y37167D01*
X460921Y37333D01*
X461421Y37417D01*
X461712Y37583D01*
X461837Y37875D01*
X461754Y38167D01*
X461546Y38375D01*
X461254Y38500D01*
X460962D01*
X460671Y38417D01*
X460421Y38208D01*
G01X458862Y36000D02*
Y38500D01*
X457821D01*
X457487Y38375D01*
X457279Y38208D01*
X457196Y37875D01*
X457279Y37542D01*
X457529Y37333D01*
X457821Y37208D01*
X458862D01*
G01X457821D02*
X457196Y36000D01*
G01X455721Y37042D02*
X455429Y37333D01*
X455179Y37500D01*
X454846Y37583D01*
X454554Y37500D01*
X454346Y37333D01*
X454179Y37083D01*
X454137Y36792D01*
X454179Y36542D01*
X454346Y36292D01*
X454596Y36083D01*
X454887Y36000D01*
X455221Y36083D01*
X455512Y36333D01*
X455679Y36708D01*
X455721Y37125D01*
X455637Y37667D01*
X455512Y37958D01*
X455304Y38250D01*
X455012Y38458D01*
X454721Y38500D01*
X454429Y38417D01*
X454221Y38208D01*
G01X451329Y36000D02*
Y38500D01*
X452871Y36708D01*
X450787D01*
G01X449646Y36375D02*
X449396Y36167D01*
X449104Y36042D01*
X448729Y36000D01*
X448354Y36083D01*
X448062Y36250D01*
X447854Y36542D01*
X447812Y36875D01*
X447896Y37208D01*
X448104Y37417D01*
X448396Y37583D01*
X448687Y37625D01*
X448979Y37583D01*
X449354Y37417D01*
X449229Y38500D01*
X448104D01*
G01X468504Y31833D02*
X468171Y31625D01*
X467796Y31500D01*
X467462D01*
X467129Y31625D01*
X466879Y31833D01*
X466754Y32125D01*
X466837Y32417D01*
X467046Y32667D01*
X467421Y32833D01*
X467921Y32917D01*
X468212Y33083D01*
X468337Y33375D01*
X468254Y33667D01*
X468046Y33875D01*
X467754Y34000D01*
X467462D01*
X467171Y33917D01*
X466921Y33708D01*
G01X465362Y31500D02*
Y34000D01*
X464321D01*
X463987Y33875D01*
X463779Y33708D01*
X463696Y33375D01*
X463779Y33042D01*
X464029Y32833D01*
X464321Y32708D01*
X465362D01*
G01X464321D02*
X463696Y31500D01*
G01X462221Y32542D02*
X461929Y32833D01*
X461679Y33000D01*
X461346Y33083D01*
X461054Y33000D01*
X460846Y32833D01*
X460679Y32583D01*
X460637Y32292D01*
X460679Y32042D01*
X460846Y31792D01*
X461096Y31583D01*
X461387Y31500D01*
X461721Y31583D01*
X462012Y31833D01*
X462179Y32208D01*
X462221Y32625D01*
X462137Y33167D01*
X462012Y33458D01*
X461804Y33750D01*
X461512Y33958D01*
X461221Y34000D01*
X460929Y33917D01*
X460721Y33708D01*
G01X459246Y31875D02*
X458996Y31667D01*
X458704Y31542D01*
X458329Y31500D01*
X457954Y31583D01*
X457662Y31750D01*
X457454Y32042D01*
X457412Y32375D01*
X457496Y32708D01*
X457704Y32917D01*
X457996Y33083D01*
X458287Y33125D01*
X458579Y33083D01*
X458954Y32917D01*
X458829Y34000D01*
X457704D01*
G01X454729Y31500D02*
Y34000D01*
X456271Y32208D01*
X454187D01*
G01X474504Y40833D02*
X474171Y40625D01*
X473796Y40500D01*
X473462D01*
X473129Y40625D01*
X472879Y40833D01*
X472754Y41125D01*
X472837Y41417D01*
X473046Y41667D01*
X473421Y41833D01*
X473921Y41917D01*
X474212Y42083D01*
X474337Y42375D01*
X474254Y42667D01*
X474046Y42875D01*
X473754Y43000D01*
X473462D01*
X473171Y42917D01*
X472921Y42708D01*
G01X469612Y42792D02*
X469862Y42917D01*
X470154Y43000D01*
X470487D01*
X470862Y42875D01*
X471154Y42667D01*
X471362Y42417D01*
X471529Y42000D01*
X471571Y41625D01*
X471487Y41250D01*
X471362Y41000D01*
X471112Y40750D01*
X470821Y40583D01*
X470529Y40500D01*
X470237D01*
X469946Y40583D01*
X469696Y40708D01*
X469487Y40875D01*
G01X468137Y40792D02*
X467846Y40583D01*
X467512Y40500D01*
X467179Y40583D01*
X466887Y40833D01*
X466679Y41208D01*
X466596Y41583D01*
Y42042D01*
X466679Y42417D01*
X466887Y42750D01*
X467137Y42917D01*
X467429Y43000D01*
X467762Y42917D01*
X468012Y42750D01*
X468179Y42500D01*
X468262Y42167D01*
X468179Y41875D01*
X467971Y41583D01*
X467721Y41417D01*
X467429Y41375D01*
X467096Y41458D01*
X466846Y41667D01*
X466596Y42042D01*
G01X464412Y40500D02*
X464329Y41042D01*
X464204Y41500D01*
X464037Y41917D01*
X463829Y42375D01*
X463496Y43000D01*
X465162D01*
G01X462021Y42583D02*
X461771Y42833D01*
X461479Y42958D01*
X461146Y43000D01*
X460729Y42917D01*
X460437Y42708D01*
X460354Y42458D01*
X460396Y42208D01*
X460562Y42000D01*
X461396Y41583D01*
X461771Y41292D01*
X462021Y40875D01*
X462104Y40500D01*
X460354D01*
G01X454262Y42925D02*
X454054Y43258D01*
X453929Y43633D01*
Y43967D01*
X454054Y44300D01*
X454262Y44550D01*
X454554Y44675D01*
X454846Y44592D01*
X455096Y44383D01*
X455262Y44008D01*
X455346Y43508D01*
X455512Y43217D01*
X455804Y43092D01*
X456096Y43175D01*
X456304Y43383D01*
X456429Y43675D01*
Y43967D01*
X456346Y44258D01*
X456137Y44508D01*
G01X456429Y46900D02*
X453929D01*
G01X456429Y45942D02*
Y47858D01*
G01X453929Y49167D02*
X456429D01*
Y50167D01*
X456304Y50500D01*
X456012Y50750D01*
X455679Y50833D01*
X455346Y50750D01*
X455096Y50542D01*
X454971Y50167D01*
Y49167D01*
G01X454221Y52392D02*
X454012Y52683D01*
X453929Y53017D01*
X454012Y53350D01*
X454262Y53642D01*
X454637Y53850D01*
X455012Y53933D01*
X455471D01*
X455846Y53850D01*
X456179Y53642D01*
X456346Y53392D01*
X456429Y53100D01*
X456346Y52767D01*
X456179Y52517D01*
X455929Y52350D01*
X455596Y52267D01*
X455304Y52350D01*
X455012Y52558D01*
X454846Y52808D01*
X454804Y53100D01*
X454887Y53433D01*
X455096Y53683D01*
X455471Y53933D01*
G01X453929Y56200D02*
X456429D01*
X455929Y55700D01*
G01X453929D02*
Y56700D01*
G01X458262Y56375D02*
X458054Y56708D01*
X457929Y57083D01*
Y57417D01*
X458054Y57750D01*
X458262Y58000D01*
X458554Y58125D01*
X458846Y58042D01*
X459096Y57833D01*
X459262Y57458D01*
X459346Y56958D01*
X459512Y56667D01*
X459804Y56542D01*
X460096Y56625D01*
X460304Y56833D01*
X460429Y57125D01*
Y57417D01*
X460346Y57708D01*
X460137Y57958D01*
G01X460429Y60350D02*
X457929D01*
G01X460429Y59392D02*
Y61308D01*
G01X457929Y62617D02*
X460429D01*
Y63617D01*
X460304Y63950D01*
X460012Y64200D01*
X459679Y64283D01*
X459346Y64200D01*
X459096Y63992D01*
X458971Y63617D01*
Y62617D01*
G01X457929Y66550D02*
X460429D01*
X459929Y66050D01*
G01X457929D02*
Y67050D01*
G01Y70150D02*
X460429D01*
X458637Y68608D01*
Y70692D01*
G01X460429Y72750D02*
X460346Y72417D01*
X460137Y72167D01*
X459887Y72000D01*
X459554Y71875D01*
X459179Y71833D01*
X458804Y71875D01*
X458471Y72000D01*
X458221Y72167D01*
X458012Y72417D01*
X457929Y72750D01*
X458012Y73083D01*
X458221Y73333D01*
X458471Y73500D01*
X458804Y73625D01*
X459179Y73667D01*
X459554Y73625D01*
X459887Y73500D01*
X460137Y73333D01*
X460346Y73083D01*
X460429Y72750D01*
G01X475504Y47833D02*
X475171Y47625D01*
X474796Y47500D01*
X474462D01*
X474129Y47625D01*
X473879Y47833D01*
X473754Y48125D01*
X473837Y48417D01*
X474046Y48667D01*
X474421Y48833D01*
X474921Y48917D01*
X475212Y49083D01*
X475337Y49375D01*
X475254Y49667D01*
X475046Y49875D01*
X474754Y50000D01*
X474462D01*
X474171Y49917D01*
X473921Y49708D01*
G01X472362Y47500D02*
Y50000D01*
X471321D01*
X470987Y49875D01*
X470779Y49708D01*
X470696Y49375D01*
X470779Y49042D01*
X471029Y48833D01*
X471321Y48708D01*
X472362D01*
G01X471321D02*
X470696Y47500D01*
G01X469221Y48542D02*
X468929Y48833D01*
X468679Y49000D01*
X468346Y49083D01*
X468054Y49000D01*
X467846Y48833D01*
X467679Y48583D01*
X467637Y48292D01*
X467679Y48042D01*
X467846Y47792D01*
X468096Y47583D01*
X468387Y47500D01*
X468721Y47583D01*
X469012Y47833D01*
X469179Y48208D01*
X469221Y48625D01*
X469137Y49167D01*
X469012Y49458D01*
X468804Y49750D01*
X468512Y49958D01*
X468221Y50000D01*
X467929Y49917D01*
X467721Y49708D01*
G01X464829Y47500D02*
Y50000D01*
X466371Y48208D01*
X464287D01*
G01X463146Y48000D02*
X462896Y47708D01*
X462562Y47542D01*
X462187Y47500D01*
X461854Y47542D01*
X461521Y47750D01*
X461312Y48000D01*
X461271Y48250D01*
X461354Y48542D01*
X461646Y48750D01*
X461937Y48833D01*
X462312D01*
G01X461937D02*
X461687Y48958D01*
X461479Y49167D01*
X461396Y49417D01*
X461479Y49667D01*
X461687Y49875D01*
X462062Y50000D01*
X462437Y49958D01*
X462812Y49792D01*
G01X451262Y59425D02*
X451054Y59758D01*
X450929Y60133D01*
Y60467D01*
X451054Y60800D01*
X451262Y61050D01*
X451554Y61175D01*
X451846Y61092D01*
X452096Y60883D01*
X452262Y60508D01*
X452346Y60008D01*
X452512Y59717D01*
X452804Y59592D01*
X453096Y59675D01*
X453304Y59883D01*
X453429Y60175D01*
Y60467D01*
X453346Y60758D01*
X453137Y61008D01*
G01X453429Y63400D02*
X450929D01*
G01X453429Y62442D02*
Y64358D01*
G01X450929Y65667D02*
X453429D01*
Y66667D01*
X453304Y67000D01*
X453012Y67250D01*
X452679Y67333D01*
X452346Y67250D01*
X452096Y67042D01*
X451971Y66667D01*
Y65667D01*
G01X451221Y68892D02*
X451012Y69183D01*
X450929Y69517D01*
X451012Y69850D01*
X451262Y70142D01*
X451637Y70350D01*
X452012Y70433D01*
X452471D01*
X452846Y70350D01*
X453179Y70142D01*
X453346Y69892D01*
X453429Y69600D01*
X453346Y69267D01*
X453179Y69017D01*
X452929Y68850D01*
X452596Y68767D01*
X452304Y68850D01*
X452012Y69058D01*
X451846Y69308D01*
X451804Y69600D01*
X451887Y69933D01*
X452096Y70183D01*
X452471Y70433D01*
G01X451429Y71783D02*
X451137Y72033D01*
X450971Y72367D01*
X450929Y72742D01*
X450971Y73075D01*
X451179Y73408D01*
X451429Y73617D01*
X451679Y73658D01*
X451971Y73575D01*
X452179Y73283D01*
X452262Y72992D01*
Y72617D01*
G01Y72992D02*
X452387Y73242D01*
X452596Y73450D01*
X452846Y73533D01*
X453096Y73450D01*
X453304Y73242D01*
X453429Y72867D01*
X453387Y72492D01*
X453221Y72117D01*
G01X448262Y77425D02*
X448054Y77758D01*
X447929Y78133D01*
Y78467D01*
X448054Y78800D01*
X448262Y79050D01*
X448554Y79175D01*
X448846Y79092D01*
X449096Y78883D01*
X449262Y78508D01*
X449346Y78008D01*
X449512Y77717D01*
X449804Y77592D01*
X450096Y77675D01*
X450304Y77883D01*
X450429Y78175D01*
Y78467D01*
X450346Y78758D01*
X450137Y79008D01*
G01X450429Y81400D02*
X447929D01*
G01X450429Y80442D02*
Y82358D01*
G01X447929Y83667D02*
X450429D01*
Y84667D01*
X450304Y85000D01*
X450012Y85250D01*
X449679Y85333D01*
X449346Y85250D01*
X449096Y85042D01*
X448971Y84667D01*
Y83667D01*
G01X450012Y86808D02*
X450262Y87058D01*
X450387Y87350D01*
X450429Y87683D01*
X450346Y88100D01*
X450137Y88392D01*
X449887Y88475D01*
X449637Y88433D01*
X449429Y88267D01*
X449012Y87433D01*
X448721Y87058D01*
X448304Y86808D01*
X447929Y86725D01*
Y88475D01*
G01X448971Y89908D02*
X449262Y90200D01*
X449429Y90450D01*
X449512Y90783D01*
X449429Y91075D01*
X449262Y91283D01*
X449012Y91450D01*
X448721Y91492D01*
X448471Y91450D01*
X448221Y91283D01*
X448012Y91033D01*
X447929Y90742D01*
X448012Y90408D01*
X448262Y90117D01*
X448637Y89950D01*
X449054Y89908D01*
X449596Y89992D01*
X449887Y90117D01*
X450179Y90325D01*
X450387Y90617D01*
X450429Y90908D01*
X450346Y91200D01*
X450137Y91408D01*
G01X460062Y77425D02*
X459854Y77758D01*
X459729Y78133D01*
Y78467D01*
X459854Y78800D01*
X460062Y79050D01*
X460354Y79175D01*
X460646Y79092D01*
X460896Y78883D01*
X461062Y78508D01*
X461146Y78008D01*
X461312Y77717D01*
X461604Y77592D01*
X461896Y77675D01*
X462104Y77883D01*
X462229Y78175D01*
Y78467D01*
X462146Y78758D01*
X461937Y79008D01*
G01X462229Y81400D02*
X459729D01*
G01X462229Y80442D02*
Y82358D01*
G01X459729Y83667D02*
X462229D01*
Y84667D01*
X462104Y85000D01*
X461812Y85250D01*
X461479Y85333D01*
X461146Y85250D01*
X460896Y85042D01*
X460771Y84667D01*
Y83667D01*
G01X459729Y88100D02*
X462229D01*
X460437Y86558D01*
Y88642D01*
G01X459729Y90617D02*
X460271Y90700D01*
X460729Y90825D01*
X461146Y90992D01*
X461604Y91200D01*
X462229Y91533D01*
Y89867D01*
G01X452262Y77425D02*
X452054Y77758D01*
X451929Y78133D01*
Y78467D01*
X452054Y78800D01*
X452262Y79050D01*
X452554Y79175D01*
X452846Y79092D01*
X453096Y78883D01*
X453262Y78508D01*
X453346Y78008D01*
X453512Y77717D01*
X453804Y77592D01*
X454096Y77675D01*
X454304Y77883D01*
X454429Y78175D01*
Y78467D01*
X454346Y78758D01*
X454137Y79008D01*
G01X454429Y81400D02*
X451929D01*
G01X454429Y80442D02*
Y82358D01*
G01X451929Y83667D02*
X454429D01*
Y84667D01*
X454304Y85000D01*
X454012Y85250D01*
X453679Y85333D01*
X453346Y85250D01*
X453096Y85042D01*
X452971Y84667D01*
Y83667D01*
G01X452304Y86683D02*
X452096Y86933D01*
X451971Y87225D01*
X451929Y87600D01*
X452012Y87975D01*
X452179Y88267D01*
X452471Y88475D01*
X452804Y88517D01*
X453137Y88433D01*
X453346Y88225D01*
X453512Y87933D01*
X453554Y87642D01*
X453512Y87350D01*
X453346Y86975D01*
X454429Y87100D01*
Y88225D01*
G01Y90700D02*
X454346Y90367D01*
X454137Y90117D01*
X453887Y89950D01*
X453554Y89825D01*
X453179Y89783D01*
X452804Y89825D01*
X452471Y89950D01*
X452221Y90117D01*
X452012Y90367D01*
X451929Y90700D01*
X452012Y91033D01*
X452221Y91283D01*
X452471Y91450D01*
X452804Y91575D01*
X453179Y91617D01*
X453554Y91575D01*
X453887Y91450D01*
X454137Y91283D01*
X454346Y91033D01*
X454429Y90700D01*
G01X456151Y77275D02*
X455943Y77608D01*
X455818Y77983D01*
Y78317D01*
X455943Y78650D01*
X456151Y78900D01*
X456443Y79025D01*
X456735Y78942D01*
X456985Y78733D01*
X457151Y78358D01*
X457235Y77858D01*
X457401Y77567D01*
X457693Y77442D01*
X457985Y77525D01*
X458193Y77733D01*
X458318Y78025D01*
Y78317D01*
X458235Y78608D01*
X458026Y78858D01*
G01X458318Y81250D02*
X455818D01*
G01X458318Y80292D02*
Y82208D01*
G01X455818Y83517D02*
X458318D01*
Y84517D01*
X458193Y84850D01*
X457901Y85100D01*
X457568Y85183D01*
X457235Y85100D01*
X456985Y84892D01*
X456860Y84517D01*
Y83517D01*
G01X455818Y87450D02*
X458318D01*
X457818Y86950D01*
G01X455818D02*
Y87950D01*
G01X456318Y89633D02*
X456026Y89883D01*
X455860Y90217D01*
X455818Y90592D01*
X455860Y90925D01*
X456068Y91258D01*
X456318Y91467D01*
X456568Y91508D01*
X456860Y91425D01*
X457068Y91133D01*
X457151Y90842D01*
Y90467D01*
G01Y90842D02*
X457276Y91092D01*
X457485Y91300D01*
X457735Y91383D01*
X457985Y91300D01*
X458193Y91092D01*
X458318Y90717D01*
X458276Y90342D01*
X458110Y89967D01*
G01X455818Y93650D02*
X455860Y93942D01*
X455985Y94275D01*
X456193Y94483D01*
X456485Y94567D01*
X456776Y94483D01*
X457026Y94233D01*
X457151Y93858D01*
Y93442D01*
X457235Y93192D01*
X457443Y92983D01*
X457735Y92900D01*
X458026Y93025D01*
X458235Y93317D01*
X458318Y93650D01*
X458235Y93983D01*
X458026Y94275D01*
X457735Y94400D01*
X457443Y94317D01*
X457235Y94108D01*
X457151Y93858D01*
Y93442D01*
X457026Y93067D01*
X456776Y92817D01*
X456485Y92733D01*
X456193Y92817D01*
X455985Y93025D01*
X455860Y93358D01*
X455818Y93650D01*
G01X457500Y187500D02*
X458500D01*
Y171500D01*
X455500D01*
Y165000D01*
X458000D01*
Y161500D01*
G01X459000Y159000D02*
Y157000D01*
X467500D01*
G01X453629Y173500D02*
Y169500D01*
X446229D01*
G01X453629Y186500D02*
Y182500D01*
X446229D01*
G01X453629Y182000D02*
Y178000D01*
X446229D01*
G01Y173500D02*
Y177500D01*
X453629D01*
G01X469951Y202908D02*
X469618Y202700D01*
X469243Y202575D01*
X468909D01*
X468576Y202700D01*
X468326Y202908D01*
X468201Y203200D01*
X468284Y203492D01*
X468493Y203742D01*
X468868Y203908D01*
X469368Y203992D01*
X469659Y204158D01*
X469784Y204450D01*
X469701Y204742D01*
X469493Y204950D01*
X469201Y205075D01*
X468909D01*
X468618Y204992D01*
X468368Y204783D01*
G01X465976Y205075D02*
Y202575D01*
G01X466934Y205075D02*
X465018D01*
G01X463709Y202575D02*
Y205075D01*
X462709D01*
X462376Y204950D01*
X462126Y204658D01*
X462043Y204325D01*
X462126Y203992D01*
X462334Y203742D01*
X462709Y203617D01*
X463709D01*
G01X459776Y202575D02*
Y205075D01*
X460276Y204575D01*
G01Y202575D02*
X459276D01*
G01X457468Y203617D02*
X457176Y203908D01*
X456926Y204075D01*
X456593Y204158D01*
X456301Y204075D01*
X456093Y203908D01*
X455926Y203658D01*
X455884Y203367D01*
X455926Y203117D01*
X456093Y202867D01*
X456343Y202658D01*
X456634Y202575D01*
X456968Y202658D01*
X457259Y202908D01*
X457426Y203283D01*
X457468Y203700D01*
X457384Y204242D01*
X457259Y204533D01*
X457051Y204825D01*
X456759Y205033D01*
X456468Y205075D01*
X456176Y204992D01*
X455968Y204783D01*
G01X453576Y205075D02*
X453909Y204992D01*
X454159Y204783D01*
X454326Y204533D01*
X454451Y204200D01*
X454493Y203825D01*
X454451Y203450D01*
X454326Y203117D01*
X454159Y202867D01*
X453909Y202658D01*
X453576Y202575D01*
X453243Y202658D01*
X452993Y202867D01*
X452826Y203117D01*
X452701Y203450D01*
X452659Y203825D01*
X452701Y204200D01*
X452826Y204533D01*
X452993Y204783D01*
X453243Y204992D01*
X453576Y205075D01*
G01X467075Y189333D02*
X466742Y189125D01*
X466367Y189000D01*
X466033D01*
X465700Y189125D01*
X465450Y189333D01*
X465325Y189625D01*
X465408Y189917D01*
X465617Y190167D01*
X465992Y190333D01*
X466492Y190417D01*
X466783Y190583D01*
X466908Y190875D01*
X466825Y191167D01*
X466617Y191375D01*
X466325Y191500D01*
X466033D01*
X465742Y191417D01*
X465492Y191208D01*
G01X462183Y191292D02*
X462433Y191417D01*
X462725Y191500D01*
X463058D01*
X463433Y191375D01*
X463725Y191167D01*
X463933Y190917D01*
X464100Y190500D01*
X464142Y190125D01*
X464058Y189750D01*
X463933Y189500D01*
X463683Y189250D01*
X463392Y189083D01*
X463100Y189000D01*
X462808D01*
X462517Y189083D01*
X462267Y189208D01*
X462058Y189375D01*
G01X460708Y189292D02*
X460417Y189083D01*
X460083Y189000D01*
X459750Y189083D01*
X459458Y189333D01*
X459250Y189708D01*
X459167Y190083D01*
Y190542D01*
X459250Y190917D01*
X459458Y191250D01*
X459708Y191417D01*
X460000Y191500D01*
X460333Y191417D01*
X460583Y191250D01*
X460750Y191000D01*
X460833Y190667D01*
X460750Y190375D01*
X460542Y190083D01*
X460292Y189917D01*
X460000Y189875D01*
X459667Y189958D01*
X459417Y190167D01*
X459167Y190542D01*
G01X456983Y189000D02*
X456900Y189542D01*
X456775Y190000D01*
X456608Y190417D01*
X456400Y190875D01*
X456067Y191500D01*
X457733D01*
G01X454508Y189292D02*
X454217Y189083D01*
X453883Y189000D01*
X453550Y189083D01*
X453258Y189333D01*
X453050Y189708D01*
X452967Y190083D01*
Y190542D01*
X453050Y190917D01*
X453258Y191250D01*
X453508Y191417D01*
X453800Y191500D01*
X454133Y191417D01*
X454383Y191250D01*
X454550Y191000D01*
X454633Y190667D01*
X454550Y190375D01*
X454342Y190083D01*
X454092Y189917D01*
X453800Y189875D01*
X453467Y189958D01*
X453217Y190167D01*
X452967Y190542D01*
G01X471312Y208008D02*
X470979Y207800D01*
X470604Y207675D01*
X470270D01*
X469937Y207800D01*
X469687Y208008D01*
X469562Y208300D01*
X469645Y208592D01*
X469854Y208842D01*
X470229Y209008D01*
X470729Y209092D01*
X471020Y209258D01*
X471145Y209550D01*
X471062Y209842D01*
X470854Y210050D01*
X470562Y210175D01*
X470270D01*
X469979Y210092D01*
X469729Y209883D01*
G01X467337Y210175D02*
Y207675D01*
G01X468295Y210175D02*
X466379D01*
G01X465070Y207675D02*
Y210175D01*
X464070D01*
X463737Y210050D01*
X463487Y209758D01*
X463404Y209425D01*
X463487Y209092D01*
X463695Y208842D01*
X464070Y208717D01*
X465070D01*
G01X461137Y207675D02*
Y210175D01*
X461637Y209675D01*
G01Y207675D02*
X460637D01*
G01X458829Y208717D02*
X458537Y209008D01*
X458287Y209175D01*
X457954Y209258D01*
X457662Y209175D01*
X457454Y209008D01*
X457287Y208758D01*
X457245Y208467D01*
X457287Y208217D01*
X457454Y207967D01*
X457704Y207758D01*
X457995Y207675D01*
X458329Y207758D01*
X458620Y208008D01*
X458787Y208383D01*
X458829Y208800D01*
X458745Y209342D01*
X458620Y209633D01*
X458412Y209925D01*
X458120Y210133D01*
X457829Y210175D01*
X457537Y210092D01*
X457329Y209883D01*
G01X454937Y207675D02*
Y210175D01*
X455437Y209675D01*
G01Y207675D02*
X454437D01*
G01X457333Y231425D02*
X457125Y231758D01*
X457000Y232133D01*
Y232467D01*
X457125Y232800D01*
X457333Y233050D01*
X457625Y233175D01*
X457917Y233092D01*
X458167Y232883D01*
X458333Y232508D01*
X458417Y232008D01*
X458583Y231717D01*
X458875Y231592D01*
X459167Y231675D01*
X459375Y231883D01*
X459500Y232175D01*
Y232467D01*
X459417Y232758D01*
X459208Y233008D01*
G01X459500Y235400D02*
X457000D01*
G01X459500Y234442D02*
Y236358D01*
G01X457000Y237667D02*
X459500D01*
Y238667D01*
X459375Y239000D01*
X459083Y239250D01*
X458750Y239333D01*
X458417Y239250D01*
X458167Y239042D01*
X458042Y238667D01*
Y237667D01*
G01Y240808D02*
X458333Y241100D01*
X458500Y241350D01*
X458583Y241683D01*
X458500Y241975D01*
X458333Y242183D01*
X458083Y242350D01*
X457792Y242392D01*
X457542Y242350D01*
X457292Y242183D01*
X457083Y241933D01*
X457000Y241642D01*
X457083Y241308D01*
X457333Y241017D01*
X457708Y240850D01*
X458125Y240808D01*
X458667Y240892D01*
X458958Y241017D01*
X459250Y241225D01*
X459458Y241517D01*
X459500Y241808D01*
X459417Y242100D01*
X459208Y242308D01*
G01X457000Y244700D02*
X459500D01*
X459000Y244200D01*
G01X457000D02*
Y245200D01*
G01X453333Y231375D02*
X453125Y231708D01*
X453000Y232083D01*
Y232417D01*
X453125Y232750D01*
X453333Y233000D01*
X453625Y233125D01*
X453917Y233042D01*
X454167Y232833D01*
X454333Y232458D01*
X454417Y231958D01*
X454583Y231667D01*
X454875Y231542D01*
X455167Y231625D01*
X455375Y231833D01*
X455500Y232125D01*
Y232417D01*
X455417Y232708D01*
X455208Y232958D01*
G01X455292Y236267D02*
X455417Y236017D01*
X455500Y235725D01*
Y235392D01*
X455375Y235017D01*
X455167Y234725D01*
X454917Y234517D01*
X454500Y234350D01*
X454125Y234308D01*
X453750Y234392D01*
X453500Y234517D01*
X453250Y234767D01*
X453083Y235058D01*
X453000Y235350D01*
Y235642D01*
X453083Y235933D01*
X453208Y236183D01*
X453375Y236392D01*
G01X453000Y238450D02*
X455500D01*
X455000Y237950D01*
G01X453000D02*
Y238950D01*
G01X455500Y241550D02*
X455417Y241217D01*
X455208Y240967D01*
X454958Y240800D01*
X454625Y240675D01*
X454250Y240633D01*
X453875Y240675D01*
X453542Y240800D01*
X453292Y240967D01*
X453083Y241217D01*
X453000Y241550D01*
X453083Y241883D01*
X453292Y242133D01*
X453542Y242300D01*
X453875Y242425D01*
X454250Y242467D01*
X454625Y242425D01*
X454958Y242300D01*
X455208Y242133D01*
X455417Y241883D01*
X455500Y241550D01*
G01X453000Y244650D02*
X455500D01*
X455000Y244150D01*
G01X453000D02*
Y245150D01*
G01X455083Y246958D02*
X455333Y247208D01*
X455458Y247500D01*
X455500Y247833D01*
X455417Y248250D01*
X455208Y248542D01*
X454958Y248625D01*
X454708Y248583D01*
X454500Y248417D01*
X454083Y247583D01*
X453792Y247208D01*
X453375Y246958D01*
X453000Y246875D01*
Y248625D01*
G01X453388Y270425D02*
X453180Y270758D01*
X453055Y271133D01*
Y271467D01*
X453180Y271800D01*
X453388Y272050D01*
X453680Y272175D01*
X453972Y272092D01*
X454222Y271883D01*
X454388Y271508D01*
X454472Y271008D01*
X454638Y270717D01*
X454930Y270592D01*
X455222Y270675D01*
X455430Y270883D01*
X455555Y271175D01*
Y271467D01*
X455472Y271758D01*
X455263Y272008D01*
G01X455555Y274400D02*
X453055D01*
G01X455555Y273442D02*
Y275358D01*
G01X453055Y276667D02*
X455555D01*
Y277667D01*
X455430Y278000D01*
X455138Y278250D01*
X454805Y278333D01*
X454472Y278250D01*
X454222Y278042D01*
X454097Y277667D01*
Y276667D01*
G01Y279808D02*
X454388Y280100D01*
X454555Y280350D01*
X454638Y280683D01*
X454555Y280975D01*
X454388Y281183D01*
X454138Y281350D01*
X453847Y281392D01*
X453597Y281350D01*
X453347Y281183D01*
X453138Y280933D01*
X453055Y280642D01*
X453138Y280308D01*
X453388Y280017D01*
X453763Y279850D01*
X454180Y279808D01*
X454722Y279892D01*
X455013Y280017D01*
X455305Y280225D01*
X455513Y280517D01*
X455555Y280808D01*
X455472Y281100D01*
X455263Y281308D01*
G01X453055Y283700D02*
X453097Y283992D01*
X453222Y284325D01*
X453430Y284533D01*
X453722Y284617D01*
X454013Y284533D01*
X454263Y284283D01*
X454388Y283908D01*
Y283492D01*
X454472Y283242D01*
X454680Y283033D01*
X454972Y282950D01*
X455263Y283075D01*
X455472Y283367D01*
X455555Y283700D01*
X455472Y284033D01*
X455263Y284325D01*
X454972Y284450D01*
X454680Y284367D01*
X454472Y284158D01*
X454388Y283908D01*
Y283492D01*
X454263Y283117D01*
X454013Y282867D01*
X453722Y282783D01*
X453430Y282867D01*
X453222Y283075D01*
X453097Y283408D01*
X453055Y283700D01*
G01X454388Y286375D02*
X454180Y286708D01*
X454055Y287083D01*
Y287417D01*
X454180Y287750D01*
X454388Y288000D01*
X454680Y288125D01*
X454972Y288042D01*
X455222Y287833D01*
X455388Y287458D01*
X455472Y286958D01*
X455638Y286667D01*
X455930Y286542D01*
X456222Y286625D01*
X456430Y286833D01*
X456555Y287125D01*
Y287417D01*
X456472Y287708D01*
X456263Y287958D01*
G01X456555Y290350D02*
X454055D01*
G01X456555Y289392D02*
Y291308D01*
G01X454055Y292617D02*
X456555D01*
Y293617D01*
X456430Y293950D01*
X456138Y294200D01*
X455805Y294283D01*
X455472Y294200D01*
X455222Y293992D01*
X455097Y293617D01*
Y292617D01*
G01X454055Y296550D02*
X456555D01*
X456055Y296050D01*
G01X454055D02*
Y297050D01*
G01X456555Y299650D02*
X456472Y299317D01*
X456263Y299067D01*
X456013Y298900D01*
X455680Y298775D01*
X455305Y298733D01*
X454930Y298775D01*
X454597Y298900D01*
X454347Y299067D01*
X454138Y299317D01*
X454055Y299650D01*
X454138Y299983D01*
X454347Y300233D01*
X454597Y300400D01*
X454930Y300525D01*
X455305Y300567D01*
X455680Y300525D01*
X456013Y300400D01*
X456263Y300233D01*
X456472Y299983D01*
X456555Y299650D01*
G01X454430Y301833D02*
X454222Y302083D01*
X454097Y302375D01*
X454055Y302750D01*
X454138Y303125D01*
X454305Y303417D01*
X454597Y303625D01*
X454930Y303667D01*
X455263Y303583D01*
X455472Y303375D01*
X455638Y303083D01*
X455680Y302792D01*
X455638Y302500D01*
X455472Y302125D01*
X456555Y302250D01*
Y303375D01*
G01X449888Y286375D02*
X449680Y286708D01*
X449555Y287083D01*
Y287417D01*
X449680Y287750D01*
X449888Y288000D01*
X450180Y288125D01*
X450472Y288042D01*
X450722Y287833D01*
X450888Y287458D01*
X450972Y286958D01*
X451138Y286667D01*
X451430Y286542D01*
X451722Y286625D01*
X451930Y286833D01*
X452055Y287125D01*
Y287417D01*
X451972Y287708D01*
X451763Y287958D01*
G01X452055Y290350D02*
X449555D01*
G01X452055Y289392D02*
Y291308D01*
G01X449555Y292617D02*
X452055D01*
Y293617D01*
X451930Y293950D01*
X451638Y294200D01*
X451305Y294283D01*
X450972Y294200D01*
X450722Y293992D01*
X450597Y293617D01*
Y292617D01*
G01X449555Y296550D02*
X452055D01*
X451555Y296050D01*
G01X449555D02*
Y297050D01*
G01X452055Y299650D02*
X451972Y299317D01*
X451763Y299067D01*
X451513Y298900D01*
X451180Y298775D01*
X450805Y298733D01*
X450430Y298775D01*
X450097Y298900D01*
X449847Y299067D01*
X449638Y299317D01*
X449555Y299650D01*
X449638Y299983D01*
X449847Y300233D01*
X450097Y300400D01*
X450430Y300525D01*
X450805Y300567D01*
X451180Y300525D01*
X451513Y300400D01*
X451763Y300233D01*
X451972Y299983D01*
X452055Y299650D01*
G01X449555Y302667D02*
X450097Y302750D01*
X450555Y302875D01*
X450972Y303042D01*
X451430Y303250D01*
X452055Y303583D01*
Y301917D01*
G01X467700Y288500D02*
Y284500D01*
X460300D01*
G01X468855Y311100D02*
Y318100D01*
X455455D01*
Y311100D01*
X468855D01*
G01X473625Y329333D02*
X473292Y329125D01*
X472917Y329000D01*
X472583D01*
X472250Y329125D01*
X472000Y329333D01*
X471875Y329625D01*
X471958Y329917D01*
X472167Y330167D01*
X472542Y330333D01*
X473042Y330417D01*
X473333Y330583D01*
X473458Y330875D01*
X473375Y331167D01*
X473167Y331375D01*
X472875Y331500D01*
X472583D01*
X472292Y331417D01*
X472042Y331208D01*
G01X469650Y331500D02*
Y329000D01*
G01X470608Y331500D02*
X468692D01*
G01X467383Y329000D02*
Y331500D01*
X466383D01*
X466050Y331375D01*
X465800Y331083D01*
X465717Y330750D01*
X465800Y330417D01*
X466008Y330167D01*
X466383Y330042D01*
X467383D01*
G01X463450Y329000D02*
Y331500D01*
X463950Y331000D01*
G01Y329000D02*
X462950D01*
G01X460350D02*
Y331500D01*
X460850Y331000D01*
G01Y329000D02*
X459850D01*
G01X456750D02*
Y331500D01*
X458292Y329708D01*
X456208D01*
G01X471625Y337333D02*
X471292Y337125D01*
X470917Y337000D01*
X470583D01*
X470250Y337125D01*
X470000Y337333D01*
X469875Y337625D01*
X469958Y337917D01*
X470167Y338167D01*
X470542Y338333D01*
X471042Y338417D01*
X471333Y338583D01*
X471458Y338875D01*
X471375Y339167D01*
X471167Y339375D01*
X470875Y339500D01*
X470583D01*
X470292Y339417D01*
X470042Y339208D01*
G01X467650Y339500D02*
Y337000D01*
G01X468608Y339500D02*
X466692D01*
G01X465383Y337000D02*
Y339500D01*
X464383D01*
X464050Y339375D01*
X463800Y339083D01*
X463717Y338750D01*
X463800Y338417D01*
X464008Y338167D01*
X464383Y338042D01*
X465383D01*
G01X461450Y337000D02*
Y339500D01*
X461950Y339000D01*
G01Y337000D02*
X460950D01*
G01X458350Y339500D02*
X458683Y339417D01*
X458933Y339208D01*
X459100Y338958D01*
X459225Y338625D01*
X459267Y338250D01*
X459225Y337875D01*
X459100Y337542D01*
X458933Y337292D01*
X458683Y337083D01*
X458350Y337000D01*
X458017Y337083D01*
X457767Y337292D01*
X457600Y337542D01*
X457475Y337875D01*
X457433Y338250D01*
X457475Y338625D01*
X457600Y338958D01*
X457767Y339208D01*
X458017Y339417D01*
X458350Y339500D01*
G01X456167Y337500D02*
X455917Y337208D01*
X455583Y337042D01*
X455208Y337000D01*
X454875Y337042D01*
X454542Y337250D01*
X454333Y337500D01*
X454292Y337750D01*
X454375Y338042D01*
X454667Y338250D01*
X454958Y338333D01*
X455333D01*
G01X454958D02*
X454708Y338458D01*
X454500Y338667D01*
X454417Y338917D01*
X454500Y339167D01*
X454708Y339375D01*
X455083Y339500D01*
X455458Y339458D01*
X455833Y339292D01*
G01X458333Y347875D02*
X458125Y348208D01*
X458000Y348583D01*
Y348917D01*
X458125Y349250D01*
X458333Y349500D01*
X458625Y349625D01*
X458917Y349542D01*
X459167Y349333D01*
X459333Y348958D01*
X459417Y348458D01*
X459583Y348167D01*
X459875Y348042D01*
X460167Y348125D01*
X460375Y348333D01*
X460500Y348625D01*
Y348917D01*
X460417Y349208D01*
X460208Y349458D01*
G01X460500Y351850D02*
X458000D01*
G01X460500Y350892D02*
Y352808D01*
G01X458000Y354117D02*
X460500D01*
Y355117D01*
X460375Y355450D01*
X460083Y355700D01*
X459750Y355783D01*
X459417Y355700D01*
X459167Y355492D01*
X459042Y355117D01*
Y354117D01*
G01X458000Y358050D02*
X460500D01*
X460000Y357550D01*
G01X458000D02*
Y358550D01*
G01X460500Y361150D02*
X460417Y360817D01*
X460208Y360567D01*
X459958Y360400D01*
X459625Y360275D01*
X459250Y360233D01*
X458875Y360275D01*
X458542Y360400D01*
X458292Y360567D01*
X458083Y360817D01*
X458000Y361150D01*
X458083Y361483D01*
X458292Y361733D01*
X458542Y361900D01*
X458875Y362025D01*
X459250Y362067D01*
X459625Y362025D01*
X459958Y361900D01*
X460208Y361733D01*
X460417Y361483D01*
X460500Y361150D01*
G01X458000Y364250D02*
X458042Y364542D01*
X458167Y364875D01*
X458375Y365083D01*
X458667Y365167D01*
X458958Y365083D01*
X459208Y364833D01*
X459333Y364458D01*
Y364042D01*
X459417Y363792D01*
X459625Y363583D01*
X459917Y363500D01*
X460208Y363625D01*
X460417Y363917D01*
X460500Y364250D01*
X460417Y364583D01*
X460208Y364875D01*
X459917Y365000D01*
X459625Y364917D01*
X459417Y364708D01*
X459333Y364458D01*
Y364042D01*
X459208Y363667D01*
X458958Y363417D01*
X458667Y363333D01*
X458375Y363417D01*
X458167Y363625D01*
X458042Y363958D01*
X458000Y364250D01*
G01X477680Y379333D02*
X477347Y379125D01*
X476972Y379000D01*
X476638D01*
X476305Y379125D01*
X476055Y379333D01*
X475930Y379625D01*
X476013Y379917D01*
X476222Y380167D01*
X476597Y380333D01*
X477097Y380417D01*
X477388Y380583D01*
X477513Y380875D01*
X477430Y381167D01*
X477222Y381375D01*
X476930Y381500D01*
X476638D01*
X476347Y381417D01*
X476097Y381208D01*
G01X472788Y381292D02*
X473038Y381417D01*
X473330Y381500D01*
X473663D01*
X474038Y381375D01*
X474330Y381167D01*
X474538Y380917D01*
X474705Y380500D01*
X474747Y380125D01*
X474663Y379750D01*
X474538Y379500D01*
X474288Y379250D01*
X473997Y379083D01*
X473705Y379000D01*
X473413D01*
X473122Y379083D01*
X472872Y379208D01*
X472663Y379375D01*
G01X470605Y379000D02*
Y381500D01*
X471105Y381000D01*
G01Y379000D02*
X470105D01*
G01X467505D02*
Y381500D01*
X468005Y381000D01*
G01Y379000D02*
X467005D01*
G01X463905D02*
Y381500D01*
X465447Y379708D01*
X463363D01*
G01X461305Y379000D02*
Y381500D01*
X461805Y381000D01*
G01Y379000D02*
X460805D01*
G01X450888Y403875D02*
X450680Y404208D01*
X450555Y404583D01*
Y404917D01*
X450680Y405250D01*
X450888Y405500D01*
X451180Y405625D01*
X451472Y405542D01*
X451722Y405333D01*
X451888Y404958D01*
X451972Y404458D01*
X452138Y404167D01*
X452430Y404042D01*
X452722Y404125D01*
X452930Y404333D01*
X453055Y404625D01*
Y404917D01*
X452972Y405208D01*
X452763Y405458D01*
G01X452847Y408767D02*
X452972Y408517D01*
X453055Y408225D01*
Y407892D01*
X452930Y407517D01*
X452722Y407225D01*
X452472Y407017D01*
X452055Y406850D01*
X451680Y406808D01*
X451305Y406892D01*
X451055Y407017D01*
X450805Y407267D01*
X450638Y407558D01*
X450555Y407850D01*
Y408142D01*
X450638Y408433D01*
X450763Y408683D01*
X450930Y408892D01*
G01X450555Y410950D02*
X453055D01*
X452555Y410450D01*
G01X450555D02*
Y411450D01*
G01X452638Y413258D02*
X452888Y413508D01*
X453013Y413800D01*
X453055Y414133D01*
X452972Y414550D01*
X452763Y414842D01*
X452513Y414925D01*
X452263Y414883D01*
X452055Y414717D01*
X451638Y413883D01*
X451347Y413508D01*
X450930Y413258D01*
X450555Y413175D01*
Y414925D01*
G01Y417650D02*
X453055D01*
X451263Y416108D01*
Y418192D01*
G01X450555Y420167D02*
X451097Y420250D01*
X451555Y420375D01*
X451972Y420542D01*
X452430Y420750D01*
X453055Y421083D01*
Y419417D01*
G01X451388Y422875D02*
X451180Y423208D01*
X451055Y423583D01*
Y423917D01*
X451180Y424250D01*
X451388Y424500D01*
X451680Y424625D01*
X451972Y424542D01*
X452222Y424333D01*
X452388Y423958D01*
X452472Y423458D01*
X452638Y423167D01*
X452930Y423042D01*
X453222Y423125D01*
X453430Y423333D01*
X453555Y423625D01*
Y423917D01*
X453472Y424208D01*
X453263Y424458D01*
G01X453347Y427767D02*
X453472Y427517D01*
X453555Y427225D01*
Y426892D01*
X453430Y426517D01*
X453222Y426225D01*
X452972Y426017D01*
X452555Y425850D01*
X452180Y425808D01*
X451805Y425892D01*
X451555Y426017D01*
X451305Y426267D01*
X451138Y426558D01*
X451055Y426850D01*
Y427142D01*
X451138Y427433D01*
X451263Y427683D01*
X451430Y427892D01*
G01X451055Y429950D02*
X453555D01*
X453055Y429450D01*
G01X451055D02*
Y430450D01*
G01X453138Y432258D02*
X453388Y432508D01*
X453513Y432800D01*
X453555Y433133D01*
X453472Y433550D01*
X453263Y433842D01*
X453013Y433925D01*
X452763Y433883D01*
X452555Y433717D01*
X452138Y432883D01*
X451847Y432508D01*
X451430Y432258D01*
X451055Y432175D01*
Y433925D01*
G01X452097Y435358D02*
X452388Y435650D01*
X452555Y435900D01*
X452638Y436233D01*
X452555Y436525D01*
X452388Y436733D01*
X452138Y436900D01*
X451847Y436942D01*
X451597Y436900D01*
X451347Y436733D01*
X451138Y436483D01*
X451055Y436192D01*
X451138Y435858D01*
X451388Y435567D01*
X451763Y435400D01*
X452180Y435358D01*
X452722Y435442D01*
X453013Y435567D01*
X453305Y435775D01*
X453513Y436067D01*
X453555Y436358D01*
X453472Y436650D01*
X453263Y436858D01*
G01X453555Y439250D02*
X453472Y438917D01*
X453263Y438667D01*
X453013Y438500D01*
X452680Y438375D01*
X452305Y438333D01*
X451930Y438375D01*
X451597Y438500D01*
X451347Y438667D01*
X451138Y438917D01*
X451055Y439250D01*
X451138Y439583D01*
X451347Y439833D01*
X451597Y440000D01*
X451930Y440125D01*
X452305Y440167D01*
X452680Y440125D01*
X453013Y440000D01*
X453263Y439833D01*
X453472Y439583D01*
X453555Y439250D01*
G01X476680Y440333D02*
X476347Y440125D01*
X475972Y440000D01*
X475638D01*
X475305Y440125D01*
X475055Y440333D01*
X474930Y440625D01*
X475013Y440917D01*
X475222Y441167D01*
X475597Y441333D01*
X476097Y441417D01*
X476388Y441583D01*
X476513Y441875D01*
X476430Y442167D01*
X476222Y442375D01*
X475930Y442500D01*
X475638D01*
X475347Y442417D01*
X475097Y442208D01*
G01X471788Y442292D02*
X472038Y442417D01*
X472330Y442500D01*
X472663D01*
X473038Y442375D01*
X473330Y442167D01*
X473538Y441917D01*
X473705Y441500D01*
X473747Y441125D01*
X473663Y440750D01*
X473538Y440500D01*
X473288Y440250D01*
X472997Y440083D01*
X472705Y440000D01*
X472413D01*
X472122Y440083D01*
X471872Y440208D01*
X471663Y440375D01*
G01X469605Y440000D02*
Y442500D01*
X470105Y442000D01*
G01Y440000D02*
X469105D01*
G01X466505D02*
Y442500D01*
X467005Y442000D01*
G01Y440000D02*
X466005D01*
G01X463405D02*
X463113Y440042D01*
X462780Y440167D01*
X462572Y440375D01*
X462488Y440667D01*
X462572Y440958D01*
X462822Y441208D01*
X463197Y441333D01*
X463613D01*
X463863Y441417D01*
X464072Y441625D01*
X464155Y441917D01*
X464030Y442208D01*
X463738Y442417D01*
X463405Y442500D01*
X463072Y442417D01*
X462780Y442208D01*
X462655Y441917D01*
X462738Y441625D01*
X462947Y441417D01*
X463197Y441333D01*
X463613D01*
X463988Y441208D01*
X464238Y440958D01*
X464322Y440667D01*
X464238Y440375D01*
X464030Y440167D01*
X463697Y440042D01*
X463405Y440000D01*
G01X461222Y440375D02*
X460972Y440167D01*
X460680Y440042D01*
X460305Y440000D01*
X459930Y440083D01*
X459638Y440250D01*
X459430Y440542D01*
X459388Y440875D01*
X459472Y441208D01*
X459680Y441417D01*
X459972Y441583D01*
X460263Y441625D01*
X460555Y441583D01*
X460930Y441417D01*
X460805Y442500D01*
X459680D01*
G01X477680Y446333D02*
X477347Y446125D01*
X476972Y446000D01*
X476638D01*
X476305Y446125D01*
X476055Y446333D01*
X475930Y446625D01*
X476013Y446917D01*
X476222Y447167D01*
X476597Y447333D01*
X477097Y447417D01*
X477388Y447583D01*
X477513Y447875D01*
X477430Y448167D01*
X477222Y448375D01*
X476930Y448500D01*
X476638D01*
X476347Y448417D01*
X476097Y448208D01*
G01X472788Y448292D02*
X473038Y448417D01*
X473330Y448500D01*
X473663D01*
X474038Y448375D01*
X474330Y448167D01*
X474538Y447917D01*
X474705Y447500D01*
X474747Y447125D01*
X474663Y446750D01*
X474538Y446500D01*
X474288Y446250D01*
X473997Y446083D01*
X473705Y446000D01*
X473413D01*
X473122Y446083D01*
X472872Y446208D01*
X472663Y446375D01*
G01X470605Y446000D02*
Y448500D01*
X471105Y448000D01*
G01Y446000D02*
X470105D01*
G01X467505D02*
Y448500D01*
X468005Y448000D01*
G01Y446000D02*
X467005D01*
G01X464488D02*
X464405Y446542D01*
X464280Y447000D01*
X464113Y447417D01*
X463905Y447875D01*
X463572Y448500D01*
X465238D01*
G01X462013Y446292D02*
X461722Y446083D01*
X461388Y446000D01*
X461055Y446083D01*
X460763Y446333D01*
X460555Y446708D01*
X460472Y447083D01*
Y447542D01*
X460555Y447917D01*
X460763Y448250D01*
X461013Y448417D01*
X461305Y448500D01*
X461638Y448417D01*
X461888Y448250D01*
X462055Y448000D01*
X462138Y447667D01*
X462055Y447375D01*
X461847Y447083D01*
X461597Y446917D01*
X461305Y446875D01*
X460972Y446958D01*
X460722Y447167D01*
X460472Y447542D01*
G01X450388Y447875D02*
X450180Y448208D01*
X450055Y448583D01*
Y448917D01*
X450180Y449250D01*
X450388Y449500D01*
X450680Y449625D01*
X450972Y449542D01*
X451222Y449333D01*
X451388Y448958D01*
X451472Y448458D01*
X451638Y448167D01*
X451930Y448042D01*
X452222Y448125D01*
X452430Y448333D01*
X452555Y448625D01*
Y448917D01*
X452472Y449208D01*
X452263Y449458D01*
G01X452347Y452767D02*
X452472Y452517D01*
X452555Y452225D01*
Y451892D01*
X452430Y451517D01*
X452222Y451225D01*
X451972Y451017D01*
X451555Y450850D01*
X451180Y450808D01*
X450805Y450892D01*
X450555Y451017D01*
X450305Y451267D01*
X450138Y451558D01*
X450055Y451850D01*
Y452142D01*
X450138Y452433D01*
X450263Y452683D01*
X450430Y452892D01*
G01X450055Y454950D02*
X452555D01*
X452055Y454450D01*
G01X450055D02*
Y455450D01*
G01Y458050D02*
X452555D01*
X452055Y457550D01*
G01X450055D02*
Y458550D01*
G01X450555Y460233D02*
X450263Y460483D01*
X450097Y460817D01*
X450055Y461192D01*
X450097Y461525D01*
X450305Y461858D01*
X450555Y462067D01*
X450805Y462108D01*
X451097Y462025D01*
X451305Y461733D01*
X451388Y461442D01*
Y461067D01*
G01Y461442D02*
X451513Y461692D01*
X451722Y461900D01*
X451972Y461983D01*
X452222Y461900D01*
X452430Y461692D01*
X452555Y461317D01*
X452513Y460942D01*
X452347Y460567D01*
G01X450055Y464250D02*
X450097Y464542D01*
X450222Y464875D01*
X450430Y465083D01*
X450722Y465167D01*
X451013Y465083D01*
X451263Y464833D01*
X451388Y464458D01*
Y464042D01*
X451472Y463792D01*
X451680Y463583D01*
X451972Y463500D01*
X452263Y463625D01*
X452472Y463917D01*
X452555Y464250D01*
X452472Y464583D01*
X452263Y464875D01*
X451972Y465000D01*
X451680Y464917D01*
X451472Y464708D01*
X451388Y464458D01*
Y464042D01*
X451263Y463667D01*
X451013Y463417D01*
X450722Y463333D01*
X450430Y463417D01*
X450222Y463625D01*
X450097Y463958D01*
X450055Y464250D01*
G01X446088Y448075D02*
X445880Y448408D01*
X445755Y448783D01*
Y449117D01*
X445880Y449450D01*
X446088Y449700D01*
X446380Y449825D01*
X446672Y449742D01*
X446922Y449533D01*
X447088Y449158D01*
X447172Y448658D01*
X447338Y448367D01*
X447630Y448242D01*
X447922Y448325D01*
X448130Y448533D01*
X448255Y448825D01*
Y449117D01*
X448172Y449408D01*
X447963Y449658D01*
G01X448047Y452967D02*
X448172Y452717D01*
X448255Y452425D01*
Y452092D01*
X448130Y451717D01*
X447922Y451425D01*
X447672Y451217D01*
X447255Y451050D01*
X446880Y451008D01*
X446505Y451092D01*
X446255Y451217D01*
X446005Y451467D01*
X445838Y451758D01*
X445755Y452050D01*
Y452342D01*
X445838Y452633D01*
X445963Y452883D01*
X446130Y453092D01*
G01X445755Y455150D02*
X448255D01*
X447755Y454650D01*
G01X445755D02*
Y455650D01*
G01Y458250D02*
X448255D01*
X447755Y457750D01*
G01X445755D02*
Y458750D01*
G01X446255Y460433D02*
X445963Y460683D01*
X445797Y461017D01*
X445755Y461392D01*
X445797Y461725D01*
X446005Y462058D01*
X446255Y462267D01*
X446505Y462308D01*
X446797Y462225D01*
X447005Y461933D01*
X447088Y461642D01*
Y461267D01*
G01Y461642D02*
X447213Y461892D01*
X447422Y462100D01*
X447672Y462183D01*
X447922Y462100D01*
X448130Y461892D01*
X448255Y461517D01*
X448213Y461142D01*
X448047Y460767D01*
G01X445755Y464367D02*
X446297Y464450D01*
X446755Y464575D01*
X447172Y464742D01*
X447630Y464950D01*
X448255Y465283D01*
Y463617D01*
G01X461611Y786425D02*
X461403Y786758D01*
X461278Y787133D01*
Y787467D01*
X461403Y787800D01*
X461611Y788050D01*
X461903Y788175D01*
X462195Y788092D01*
X462445Y787883D01*
X462611Y787508D01*
X462695Y787008D01*
X462861Y786717D01*
X463153Y786592D01*
X463445Y786675D01*
X463653Y786883D01*
X463778Y787175D01*
Y787467D01*
X463695Y787758D01*
X463486Y788008D01*
G01X461278Y789567D02*
X463778D01*
Y790608D01*
X463653Y790942D01*
X463486Y791150D01*
X463153Y791233D01*
X462820Y791150D01*
X462611Y790900D01*
X462486Y790608D01*
Y789567D01*
G01Y790608D02*
X461278Y791233D01*
G01Y793500D02*
X461320Y793792D01*
X461445Y794125D01*
X461653Y794333D01*
X461945Y794417D01*
X462236Y794333D01*
X462486Y794083D01*
X462611Y793708D01*
Y793292D01*
X462695Y793042D01*
X462903Y792833D01*
X463195Y792750D01*
X463486Y792875D01*
X463695Y793167D01*
X463778Y793500D01*
X463695Y793833D01*
X463486Y794125D01*
X463195Y794250D01*
X462903Y794167D01*
X462695Y793958D01*
X462611Y793708D01*
Y793292D01*
X462486Y792917D01*
X462236Y792667D01*
X461945Y792583D01*
X461653Y792667D01*
X461445Y792875D01*
X461320Y793208D01*
X461278Y793500D01*
G01Y796600D02*
X461320Y796892D01*
X461445Y797225D01*
X461653Y797433D01*
X461945Y797517D01*
X462236Y797433D01*
X462486Y797183D01*
X462611Y796808D01*
Y796392D01*
X462695Y796142D01*
X462903Y795933D01*
X463195Y795850D01*
X463486Y795975D01*
X463695Y796267D01*
X463778Y796600D01*
X463695Y796933D01*
X463486Y797225D01*
X463195Y797350D01*
X462903Y797267D01*
X462695Y797058D01*
X462611Y796808D01*
Y796392D01*
X462486Y796017D01*
X462236Y795767D01*
X461945Y795683D01*
X461653Y795767D01*
X461445Y795975D01*
X461320Y796308D01*
X461278Y796600D01*
G01Y799700D02*
X461320Y799992D01*
X461445Y800325D01*
X461653Y800533D01*
X461945Y800617D01*
X462236Y800533D01*
X462486Y800283D01*
X462611Y799908D01*
Y799492D01*
X462695Y799242D01*
X462903Y799033D01*
X463195Y798950D01*
X463486Y799075D01*
X463695Y799367D01*
X463778Y799700D01*
X463695Y800033D01*
X463486Y800325D01*
X463195Y800450D01*
X462903Y800367D01*
X462695Y800158D01*
X462611Y799908D01*
Y799492D01*
X462486Y799117D01*
X462236Y798867D01*
X461945Y798783D01*
X461653Y798867D01*
X461445Y799075D01*
X461320Y799408D01*
X461278Y799700D01*
G01X455111Y786425D02*
X454903Y786758D01*
X454778Y787133D01*
Y787467D01*
X454903Y787800D01*
X455111Y788050D01*
X455403Y788175D01*
X455695Y788092D01*
X455945Y787883D01*
X456111Y787508D01*
X456195Y787008D01*
X456361Y786717D01*
X456653Y786592D01*
X456945Y786675D01*
X457153Y786883D01*
X457278Y787175D01*
Y787467D01*
X457195Y787758D01*
X456986Y788008D01*
G01X454778Y789567D02*
X457278D01*
Y790608D01*
X457153Y790942D01*
X456986Y791150D01*
X456653Y791233D01*
X456320Y791150D01*
X456111Y790900D01*
X455986Y790608D01*
Y789567D01*
G01Y790608D02*
X454778Y791233D01*
G01Y793500D02*
X454820Y793792D01*
X454945Y794125D01*
X455153Y794333D01*
X455445Y794417D01*
X455736Y794333D01*
X455986Y794083D01*
X456111Y793708D01*
Y793292D01*
X456195Y793042D01*
X456403Y792833D01*
X456695Y792750D01*
X456986Y792875D01*
X457195Y793167D01*
X457278Y793500D01*
X457195Y793833D01*
X456986Y794125D01*
X456695Y794250D01*
X456403Y794167D01*
X456195Y793958D01*
X456111Y793708D01*
Y793292D01*
X455986Y792917D01*
X455736Y792667D01*
X455445Y792583D01*
X455153Y792667D01*
X454945Y792875D01*
X454820Y793208D01*
X454778Y793500D01*
G01X455070Y795892D02*
X454861Y796183D01*
X454778Y796517D01*
X454861Y796850D01*
X455111Y797142D01*
X455486Y797350D01*
X455861Y797433D01*
X456320D01*
X456695Y797350D01*
X457028Y797142D01*
X457195Y796892D01*
X457278Y796600D01*
X457195Y796267D01*
X457028Y796017D01*
X456778Y795850D01*
X456445Y795767D01*
X456153Y795850D01*
X455861Y796058D01*
X455695Y796308D01*
X455653Y796600D01*
X455736Y796933D01*
X455945Y797183D01*
X456320Y797433D01*
G01X456861Y798908D02*
X457111Y799158D01*
X457236Y799450D01*
X457278Y799783D01*
X457195Y800200D01*
X456986Y800492D01*
X456736Y800575D01*
X456486Y800533D01*
X456278Y800367D01*
X455861Y799533D01*
X455570Y799158D01*
X455153Y798908D01*
X454778Y798825D01*
Y800575D01*
G01X464778Y803300D02*
X460778D01*
Y810700D01*
G01X454278Y814200D02*
X458278D01*
Y806800D01*
G01Y803300D02*
X454278D01*
Y810700D01*
G01X460778Y814200D02*
X464778D01*
Y806800D01*
G01X453278Y833000D02*
Y836000D01*
G01X462703Y861833D02*
X462370Y861625D01*
X461995Y861500D01*
X461661D01*
X461328Y861625D01*
X461078Y861833D01*
X460953Y862125D01*
X461036Y862417D01*
X461245Y862667D01*
X461620Y862833D01*
X462120Y862917D01*
X462411Y863083D01*
X462536Y863375D01*
X462453Y863667D01*
X462245Y863875D01*
X461953Y864000D01*
X461661D01*
X461370Y863917D01*
X461120Y863708D01*
G01X459645Y864000D02*
Y862208D01*
X459478Y861833D01*
X459145Y861583D01*
X458728Y861500D01*
X458311Y861583D01*
X457978Y861833D01*
X457811Y862208D01*
Y864000D01*
G01X455711Y861500D02*
X455628Y862042D01*
X455503Y862500D01*
X455336Y862917D01*
X455128Y863375D01*
X454795Y864000D01*
X456461D01*
G01X452611Y861500D02*
X452528Y862042D01*
X452403Y862500D01*
X452236Y862917D01*
X452028Y863375D01*
X451695Y864000D01*
X453361D01*
G01X455328Y856000D02*
Y859000D01*
G01X445478Y856000D02*
Y858000D01*
G01X465253Y866833D02*
X464920Y866625D01*
X464545Y866500D01*
X464211D01*
X463878Y866625D01*
X463628Y866833D01*
X463503Y867125D01*
X463586Y867417D01*
X463795Y867667D01*
X464170Y867833D01*
X464670Y867917D01*
X464961Y868083D01*
X465086Y868375D01*
X465003Y868667D01*
X464795Y868875D01*
X464503Y869000D01*
X464211D01*
X463920Y868917D01*
X463670Y868708D01*
G01X462111Y866500D02*
Y869000D01*
X461070D01*
X460736Y868875D01*
X460528Y868708D01*
X460445Y868375D01*
X460528Y868042D01*
X460778Y867833D01*
X461070Y867708D01*
X462111D01*
G01X461070D02*
X460445Y866500D01*
G01X458178D02*
X457886Y866542D01*
X457553Y866667D01*
X457345Y866875D01*
X457261Y867167D01*
X457345Y867458D01*
X457595Y867708D01*
X457970Y867833D01*
X458386D01*
X458636Y867917D01*
X458845Y868125D01*
X458928Y868417D01*
X458803Y868708D01*
X458511Y868917D01*
X458178Y869000D01*
X457845Y868917D01*
X457553Y868708D01*
X457428Y868417D01*
X457511Y868125D01*
X457720Y867917D01*
X457970Y867833D01*
X458386D01*
X458761Y867708D01*
X459011Y867458D01*
X459095Y867167D01*
X459011Y866875D01*
X458803Y866667D01*
X458470Y866542D01*
X458178Y866500D01*
G01X455078D02*
X454786Y866542D01*
X454453Y866667D01*
X454245Y866875D01*
X454161Y867167D01*
X454245Y867458D01*
X454495Y867708D01*
X454870Y867833D01*
X455286D01*
X455536Y867917D01*
X455745Y868125D01*
X455828Y868417D01*
X455703Y868708D01*
X455411Y868917D01*
X455078Y869000D01*
X454745Y868917D01*
X454453Y868708D01*
X454328Y868417D01*
X454411Y868125D01*
X454620Y867917D01*
X454870Y867833D01*
X455286D01*
X455661Y867708D01*
X455911Y867458D01*
X455995Y867167D01*
X455911Y866875D01*
X455703Y866667D01*
X455370Y866542D01*
X455078Y866500D01*
G01X452686Y866792D02*
X452395Y866583D01*
X452061Y866500D01*
X451728Y866583D01*
X451436Y866833D01*
X451228Y867208D01*
X451145Y867583D01*
Y868042D01*
X451228Y868417D01*
X451436Y868750D01*
X451686Y868917D01*
X451978Y869000D01*
X452311Y868917D01*
X452561Y868750D01*
X452728Y868500D01*
X452811Y868167D01*
X452728Y867875D01*
X452520Y867583D01*
X452270Y867417D01*
X451978Y867375D01*
X451645Y867458D01*
X451395Y867667D01*
X451145Y868042D01*
G01X462778Y873800D02*
X458778D01*
Y881200D01*
G01Y877700D02*
X462778D01*
Y870300D01*
G01X459111Y885425D02*
X458903Y885758D01*
X458778Y886133D01*
Y886467D01*
X458903Y886800D01*
X459111Y887050D01*
X459403Y887175D01*
X459695Y887092D01*
X459945Y886883D01*
X460111Y886508D01*
X460195Y886008D01*
X460361Y885717D01*
X460653Y885592D01*
X460945Y885675D01*
X461153Y885883D01*
X461278Y886175D01*
Y886467D01*
X461195Y886758D01*
X460986Y887008D01*
G01X458778Y888567D02*
X461278D01*
Y889608D01*
X461153Y889942D01*
X460986Y890150D01*
X460653Y890233D01*
X460320Y890150D01*
X460111Y889900D01*
X459986Y889608D01*
Y888567D01*
G01Y889608D02*
X458778Y890233D01*
G01Y892500D02*
X458820Y892792D01*
X458945Y893125D01*
X459153Y893333D01*
X459445Y893417D01*
X459736Y893333D01*
X459986Y893083D01*
X460111Y892708D01*
Y892292D01*
X460195Y892042D01*
X460403Y891833D01*
X460695Y891750D01*
X460986Y891875D01*
X461195Y892167D01*
X461278Y892500D01*
X461195Y892833D01*
X460986Y893125D01*
X460695Y893250D01*
X460403Y893167D01*
X460195Y892958D01*
X460111Y892708D01*
Y892292D01*
X459986Y891917D01*
X459736Y891667D01*
X459445Y891583D01*
X459153Y891667D01*
X458945Y891875D01*
X458820Y892208D01*
X458778Y892500D01*
G01X459070Y894892D02*
X458861Y895183D01*
X458778Y895517D01*
X458861Y895850D01*
X459111Y896142D01*
X459486Y896350D01*
X459861Y896433D01*
X460320D01*
X460695Y896350D01*
X461028Y896142D01*
X461195Y895892D01*
X461278Y895600D01*
X461195Y895267D01*
X461028Y895017D01*
X460778Y894850D01*
X460445Y894767D01*
X460153Y894850D01*
X459861Y895058D01*
X459695Y895308D01*
X459653Y895600D01*
X459736Y895933D01*
X459945Y896183D01*
X460320Y896433D01*
G01X458778Y898700D02*
X461278D01*
X460778Y898200D01*
G01X458778D02*
Y899200D01*
G01X454111Y880375D02*
X453903Y880708D01*
X453778Y881083D01*
Y881417D01*
X453903Y881750D01*
X454111Y882000D01*
X454403Y882125D01*
X454695Y882042D01*
X454945Y881833D01*
X455111Y881458D01*
X455195Y880958D01*
X455361Y880667D01*
X455653Y880542D01*
X455945Y880625D01*
X456153Y880833D01*
X456278Y881125D01*
Y881417D01*
X456195Y881708D01*
X455986Y881958D01*
G01X456070Y885267D02*
X456195Y885017D01*
X456278Y884725D01*
Y884392D01*
X456153Y884017D01*
X455945Y883725D01*
X455695Y883517D01*
X455278Y883350D01*
X454903Y883308D01*
X454528Y883392D01*
X454278Y883517D01*
X454028Y883767D01*
X453861Y884058D01*
X453778Y884350D01*
Y884642D01*
X453861Y884933D01*
X453986Y885183D01*
X454153Y885392D01*
G01X453778Y887450D02*
X456278D01*
X455778Y886950D01*
G01X453778D02*
Y887950D01*
G01X455861Y889758D02*
X456111Y890008D01*
X456236Y890300D01*
X456278Y890633D01*
X456195Y891050D01*
X455986Y891342D01*
X455736Y891425D01*
X455486Y891383D01*
X455278Y891217D01*
X454861Y890383D01*
X454570Y890008D01*
X454153Y889758D01*
X453778Y889675D01*
Y891425D01*
G01X454070Y892942D02*
X453861Y893233D01*
X453778Y893567D01*
X453861Y893900D01*
X454111Y894192D01*
X454486Y894400D01*
X454861Y894483D01*
X455320D01*
X455695Y894400D01*
X456028Y894192D01*
X456195Y893942D01*
X456278Y893650D01*
X456195Y893317D01*
X456028Y893067D01*
X455778Y892900D01*
X455445Y892817D01*
X455153Y892900D01*
X454861Y893108D01*
X454695Y893358D01*
X454653Y893650D01*
X454736Y893983D01*
X454945Y894233D01*
X455320Y894483D01*
G01X455861Y895958D02*
X456111Y896208D01*
X456236Y896500D01*
X456278Y896833D01*
X456195Y897250D01*
X455986Y897542D01*
X455736Y897625D01*
X455486Y897583D01*
X455278Y897417D01*
X454861Y896583D01*
X454570Y896208D01*
X454153Y895958D01*
X453778Y895875D01*
Y897625D01*
G01X467262Y52425D02*
X467054Y52758D01*
X466929Y53133D01*
Y53467D01*
X467054Y53800D01*
X467262Y54050D01*
X467554Y54175D01*
X467846Y54092D01*
X468096Y53883D01*
X468262Y53508D01*
X468346Y53008D01*
X468512Y52717D01*
X468804Y52592D01*
X469096Y52675D01*
X469304Y52883D01*
X469429Y53175D01*
Y53467D01*
X469346Y53758D01*
X469137Y54008D01*
G01X469429Y56400D02*
X466929D01*
G01X469429Y55442D02*
Y57358D01*
G01X466929Y58667D02*
X469429D01*
Y59667D01*
X469304Y60000D01*
X469012Y60250D01*
X468679Y60333D01*
X468346Y60250D01*
X468096Y60042D01*
X467971Y59667D01*
Y58667D01*
G01X469012Y61808D02*
X469262Y62058D01*
X469387Y62350D01*
X469429Y62683D01*
X469346Y63100D01*
X469137Y63392D01*
X468887Y63475D01*
X468637Y63433D01*
X468429Y63267D01*
X468012Y62433D01*
X467721Y62058D01*
X467304Y61808D01*
X466929Y61725D01*
Y63475D01*
G01Y65700D02*
X466971Y65992D01*
X467096Y66325D01*
X467304Y66533D01*
X467596Y66617D01*
X467887Y66533D01*
X468137Y66283D01*
X468262Y65908D01*
Y65492D01*
X468346Y65242D01*
X468554Y65033D01*
X468846Y64950D01*
X469137Y65075D01*
X469346Y65367D01*
X469429Y65700D01*
X469346Y66033D01*
X469137Y66325D01*
X468846Y66450D01*
X468554Y66367D01*
X468346Y66158D01*
X468262Y65908D01*
Y65492D01*
X468137Y65117D01*
X467887Y64867D01*
X467596Y64783D01*
X467304Y64867D01*
X467096Y65075D01*
X466971Y65408D01*
X466929Y65700D01*
G01X463262Y53875D02*
X463054Y54208D01*
X462929Y54583D01*
Y54917D01*
X463054Y55250D01*
X463262Y55500D01*
X463554Y55625D01*
X463846Y55542D01*
X464096Y55333D01*
X464262Y54958D01*
X464346Y54458D01*
X464512Y54167D01*
X464804Y54042D01*
X465096Y54125D01*
X465304Y54333D01*
X465429Y54625D01*
Y54917D01*
X465346Y55208D01*
X465137Y55458D01*
G01X465429Y57850D02*
X462929D01*
G01X465429Y56892D02*
Y58808D01*
G01X462929Y60117D02*
X465429D01*
Y61117D01*
X465304Y61450D01*
X465012Y61700D01*
X464679Y61783D01*
X464346Y61700D01*
X464096Y61492D01*
X463971Y61117D01*
Y60117D01*
G01X462929Y64050D02*
X465429D01*
X464929Y63550D01*
G01X462929D02*
Y64550D01*
G01X463429Y66233D02*
X463137Y66483D01*
X462971Y66817D01*
X462929Y67192D01*
X462971Y67525D01*
X463179Y67858D01*
X463429Y68067D01*
X463679Y68108D01*
X463971Y68025D01*
X464179Y67733D01*
X464262Y67442D01*
Y67067D01*
G01Y67442D02*
X464387Y67692D01*
X464596Y67900D01*
X464846Y67983D01*
X465096Y67900D01*
X465304Y67692D01*
X465429Y67317D01*
X465387Y66942D01*
X465221Y66567D01*
G01X462929Y70167D02*
X463471Y70250D01*
X463929Y70375D01*
X464346Y70542D01*
X464804Y70750D01*
X465429Y71083D01*
Y69417D01*
G01X472762Y51875D02*
X472554Y52208D01*
X472429Y52583D01*
Y52917D01*
X472554Y53250D01*
X472762Y53500D01*
X473054Y53625D01*
X473346Y53542D01*
X473596Y53333D01*
X473762Y52958D01*
X473846Y52458D01*
X474012Y52167D01*
X474304Y52042D01*
X474596Y52125D01*
X474804Y52333D01*
X474929Y52625D01*
Y52917D01*
X474846Y53208D01*
X474637Y53458D01*
G01X474721Y56767D02*
X474846Y56517D01*
X474929Y56225D01*
Y55892D01*
X474804Y55517D01*
X474596Y55225D01*
X474346Y55017D01*
X473929Y54850D01*
X473554Y54808D01*
X473179Y54892D01*
X472929Y55017D01*
X472679Y55267D01*
X472512Y55558D01*
X472429Y55850D01*
Y56142D01*
X472512Y56433D01*
X472637Y56683D01*
X472804Y56892D01*
G01X472429Y58950D02*
X474929D01*
X474429Y58450D01*
G01X472429D02*
Y59450D01*
G01X474929Y62050D02*
X474846Y61717D01*
X474637Y61467D01*
X474387Y61300D01*
X474054Y61175D01*
X473679Y61133D01*
X473304Y61175D01*
X472971Y61300D01*
X472721Y61467D01*
X472512Y61717D01*
X472429Y62050D01*
X472512Y62383D01*
X472721Y62633D01*
X472971Y62800D01*
X473304Y62925D01*
X473679Y62967D01*
X474054Y62925D01*
X474387Y62800D01*
X474637Y62633D01*
X474846Y62383D01*
X474929Y62050D01*
G01Y65150D02*
X474846Y64817D01*
X474637Y64567D01*
X474387Y64400D01*
X474054Y64275D01*
X473679Y64233D01*
X473304Y64275D01*
X472971Y64400D01*
X472721Y64567D01*
X472512Y64817D01*
X472429Y65150D01*
X472512Y65483D01*
X472721Y65733D01*
X472971Y65900D01*
X473304Y66025D01*
X473679Y66067D01*
X474054Y66025D01*
X474387Y65900D01*
X474637Y65733D01*
X474846Y65483D01*
X474929Y65150D01*
G01X472429Y68250D02*
X474929D01*
X474429Y67750D01*
G01X472429D02*
Y68750D01*
G01X464262Y77425D02*
X464054Y77758D01*
X463929Y78133D01*
Y78467D01*
X464054Y78800D01*
X464262Y79050D01*
X464554Y79175D01*
X464846Y79092D01*
X465096Y78883D01*
X465262Y78508D01*
X465346Y78008D01*
X465512Y77717D01*
X465804Y77592D01*
X466096Y77675D01*
X466304Y77883D01*
X466429Y78175D01*
Y78467D01*
X466346Y78758D01*
X466137Y79008D01*
G01X466429Y81400D02*
X463929D01*
G01X466429Y80442D02*
Y82358D01*
G01X463929Y83667D02*
X466429D01*
Y84667D01*
X466304Y85000D01*
X466012Y85250D01*
X465679Y85333D01*
X465346Y85250D01*
X465096Y85042D01*
X464971Y84667D01*
Y83667D01*
G01X464221Y86892D02*
X464012Y87183D01*
X463929Y87517D01*
X464012Y87850D01*
X464262Y88142D01*
X464637Y88350D01*
X465012Y88433D01*
X465471D01*
X465846Y88350D01*
X466179Y88142D01*
X466346Y87892D01*
X466429Y87600D01*
X466346Y87267D01*
X466179Y87017D01*
X465929Y86850D01*
X465596Y86767D01*
X465304Y86850D01*
X465012Y87058D01*
X464846Y87308D01*
X464804Y87600D01*
X464887Y87933D01*
X465096Y88183D01*
X465471Y88433D01*
G01X463929Y91200D02*
X466429D01*
X464637Y89658D01*
Y91742D01*
G01X471000Y133500D02*
X476500D01*
Y101000D01*
X544500D01*
X540500Y105000D01*
Y97000D01*
X544500Y101000D01*
G01X470129Y106000D02*
Y102000D01*
X462729D01*
G01X473129Y124000D02*
Y120000D01*
X465729D01*
G01X476000Y165500D02*
X467500D01*
Y141000D01*
X471000D01*
Y136500D01*
X481500D01*
Y141000D01*
G01X479700Y142000D02*
Y138000D01*
X472300D01*
G01X476129Y151000D02*
Y147000D01*
X468729D01*
G01X476129Y155500D02*
Y151500D01*
X468729D01*
G01X476200Y146500D02*
Y142500D01*
X468800D01*
G01X476700Y159500D02*
Y155500D01*
X469300D01*
G01X476200Y164000D02*
Y160000D01*
X468800D01*
G01X478833Y162425D02*
X478625Y162758D01*
X478500Y163133D01*
Y163467D01*
X478625Y163800D01*
X478833Y164050D01*
X479125Y164175D01*
X479417Y164092D01*
X479667Y163883D01*
X479833Y163508D01*
X479917Y163008D01*
X480083Y162717D01*
X480375Y162592D01*
X480667Y162675D01*
X480875Y162883D01*
X481000Y163175D01*
Y163467D01*
X480917Y163758D01*
X480708Y164008D01*
G01X478500Y165567D02*
X481000D01*
Y166608D01*
X480875Y166942D01*
X480708Y167150D01*
X480375Y167233D01*
X480042Y167150D01*
X479833Y166900D01*
X479708Y166608D01*
Y165567D01*
G01Y166608D02*
X478500Y167233D01*
G01X479542Y168708D02*
X479833Y169000D01*
X480000Y169250D01*
X480083Y169583D01*
X480000Y169875D01*
X479833Y170083D01*
X479583Y170250D01*
X479292Y170292D01*
X479042Y170250D01*
X478792Y170083D01*
X478583Y169833D01*
X478500Y169542D01*
X478583Y169208D01*
X478833Y168917D01*
X479208Y168750D01*
X479625Y168708D01*
X480167Y168792D01*
X480458Y168917D01*
X480750Y169125D01*
X480958Y169417D01*
X481000Y169708D01*
X480917Y170000D01*
X480708Y170208D01*
G01X478875Y171683D02*
X478667Y171933D01*
X478542Y172225D01*
X478500Y172600D01*
X478583Y172975D01*
X478750Y173267D01*
X479042Y173475D01*
X479375Y173517D01*
X479708Y173433D01*
X479917Y173225D01*
X480083Y172933D01*
X480125Y172642D01*
X480083Y172350D01*
X479917Y171975D01*
X481000Y172100D01*
Y173225D01*
G01X479000Y174783D02*
X478708Y175033D01*
X478542Y175367D01*
X478500Y175742D01*
X478542Y176075D01*
X478750Y176408D01*
X479000Y176617D01*
X479250Y176658D01*
X479542Y176575D01*
X479750Y176283D01*
X479833Y175992D01*
Y175617D01*
G01Y175992D02*
X479958Y176242D01*
X480167Y176450D01*
X480417Y176533D01*
X480667Y176450D01*
X480875Y176242D01*
X481000Y175867D01*
X480958Y175492D01*
X480792Y175117D01*
G01X471700Y171000D02*
Y167000D01*
X464300D01*
G01X479575Y179333D02*
X479242Y179125D01*
X478867Y179000D01*
X478533D01*
X478200Y179125D01*
X477950Y179333D01*
X477825Y179625D01*
X477908Y179917D01*
X478117Y180167D01*
X478492Y180333D01*
X478992Y180417D01*
X479283Y180583D01*
X479408Y180875D01*
X479325Y181167D01*
X479117Y181375D01*
X478825Y181500D01*
X478533D01*
X478242Y181417D01*
X477992Y181208D01*
G01X476433Y179000D02*
Y181500D01*
X475392D01*
X475058Y181375D01*
X474850Y181208D01*
X474767Y180875D01*
X474850Y180542D01*
X475100Y180333D01*
X475392Y180208D01*
X476433D01*
G01X475392D02*
X474767Y179000D01*
G01X473292Y180042D02*
X473000Y180333D01*
X472750Y180500D01*
X472417Y180583D01*
X472125Y180500D01*
X471917Y180333D01*
X471750Y180083D01*
X471708Y179792D01*
X471750Y179542D01*
X471917Y179292D01*
X472167Y179083D01*
X472458Y179000D01*
X472792Y179083D01*
X473083Y179333D01*
X473250Y179708D01*
X473292Y180125D01*
X473208Y180667D01*
X473083Y180958D01*
X472875Y181250D01*
X472583Y181458D01*
X472292Y181500D01*
X472000Y181417D01*
X471792Y181208D01*
G01X469400Y179000D02*
Y181500D01*
X469900Y181000D01*
G01Y179000D02*
X468900D01*
G01X466383D02*
X466300Y179542D01*
X466175Y180000D01*
X466008Y180417D01*
X465800Y180875D01*
X465467Y181500D01*
X467133D01*
G01X471700Y178000D02*
Y174000D01*
X464300D01*
G01X474300Y184231D02*
Y188231D01*
X481700D01*
G01X483606Y198124D02*
X483273Y197916D01*
X482898Y197791D01*
X482564D01*
X482231Y197916D01*
X481981Y198124D01*
X481856Y198416D01*
X481939Y198708D01*
X482148Y198958D01*
X482523Y199124D01*
X483023Y199208D01*
X483314Y199374D01*
X483439Y199666D01*
X483356Y199958D01*
X483148Y200166D01*
X482856Y200291D01*
X482564D01*
X482273Y200208D01*
X482023Y199999D01*
G01X480464Y197791D02*
Y200291D01*
X479423D01*
X479089Y200166D01*
X478881Y199999D01*
X478798Y199666D01*
X478881Y199333D01*
X479131Y199124D01*
X479423Y198999D01*
X480464D01*
G01X479423D02*
X478798Y197791D01*
G01X477323Y198833D02*
X477031Y199124D01*
X476781Y199291D01*
X476448Y199374D01*
X476156Y199291D01*
X475948Y199124D01*
X475781Y198874D01*
X475739Y198583D01*
X475781Y198333D01*
X475948Y198083D01*
X476198Y197874D01*
X476489Y197791D01*
X476823Y197874D01*
X477114Y198124D01*
X477281Y198499D01*
X477323Y198916D01*
X477239Y199458D01*
X477114Y199749D01*
X476906Y200041D01*
X476614Y200249D01*
X476323Y200291D01*
X476031Y200208D01*
X475823Y199999D01*
G01X473431Y197791D02*
Y200291D01*
X473931Y199791D01*
G01Y197791D02*
X472931D01*
G01X470331D02*
X470039Y197833D01*
X469706Y197958D01*
X469498Y198166D01*
X469414Y198458D01*
X469498Y198749D01*
X469748Y198999D01*
X470123Y199124D01*
X470539D01*
X470789Y199208D01*
X470998Y199416D01*
X471081Y199708D01*
X470956Y199999D01*
X470664Y200208D01*
X470331Y200291D01*
X469998Y200208D01*
X469706Y199999D01*
X469581Y199708D01*
X469664Y199416D01*
X469873Y199208D01*
X470123Y199124D01*
X470539D01*
X470914Y198999D01*
X471164Y198749D01*
X471248Y198458D01*
X471164Y198166D01*
X470956Y197958D01*
X470623Y197833D01*
X470331Y197791D01*
G01X481731Y192291D02*
Y188291D01*
X474331D01*
G01X483575Y194064D02*
X483242Y193856D01*
X482867Y193731D01*
X482533D01*
X482200Y193856D01*
X481950Y194064D01*
X481825Y194356D01*
X481908Y194648D01*
X482117Y194898D01*
X482492Y195064D01*
X482992Y195148D01*
X483283Y195314D01*
X483408Y195606D01*
X483325Y195898D01*
X483117Y196106D01*
X482825Y196231D01*
X482533D01*
X482242Y196148D01*
X481992Y195939D01*
G01X480433Y193731D02*
Y196231D01*
X479392D01*
X479058Y196106D01*
X478850Y195939D01*
X478767Y195606D01*
X478850Y195273D01*
X479100Y195064D01*
X479392Y194939D01*
X480433D01*
G01X479392D02*
X478767Y193731D01*
G01X477417Y194106D02*
X477167Y193898D01*
X476875Y193773D01*
X476500Y193731D01*
X476125Y193814D01*
X475833Y193981D01*
X475625Y194273D01*
X475583Y194606D01*
X475667Y194939D01*
X475875Y195148D01*
X476167Y195314D01*
X476458Y195356D01*
X476750Y195314D01*
X477125Y195148D01*
X477000Y196231D01*
X475875D01*
G01X473400Y193731D02*
X473108Y193773D01*
X472775Y193898D01*
X472567Y194106D01*
X472483Y194398D01*
X472567Y194689D01*
X472817Y194939D01*
X473192Y195064D01*
X473608D01*
X473858Y195148D01*
X474067Y195356D01*
X474150Y195648D01*
X474025Y195939D01*
X473733Y196148D01*
X473400Y196231D01*
X473067Y196148D01*
X472775Y195939D01*
X472650Y195648D01*
X472733Y195356D01*
X472942Y195148D01*
X473192Y195064D01*
X473608D01*
X473983Y194939D01*
X474233Y194689D01*
X474317Y194398D01*
X474233Y194106D01*
X474025Y193898D01*
X473692Y193773D01*
X473400Y193731D01*
G01X471217Y194231D02*
X470967Y193939D01*
X470633Y193773D01*
X470258Y193731D01*
X469925Y193773D01*
X469592Y193981D01*
X469383Y194231D01*
X469342Y194481D01*
X469425Y194773D01*
X469717Y194981D01*
X470008Y195064D01*
X470383D01*
G01X470008D02*
X469758Y195189D01*
X469550Y195398D01*
X469467Y195648D01*
X469550Y195898D01*
X469758Y196106D01*
X470133Y196231D01*
X470508Y196189D01*
X470883Y196023D01*
G01X484625Y219333D02*
X484292Y219125D01*
X483917Y219000D01*
X483583D01*
X483250Y219125D01*
X483000Y219333D01*
X482875Y219625D01*
X482958Y219917D01*
X483167Y220167D01*
X483542Y220333D01*
X484042Y220417D01*
X484333Y220583D01*
X484458Y220875D01*
X484375Y221167D01*
X484167Y221375D01*
X483875Y221500D01*
X483583D01*
X483292Y221417D01*
X483042Y221208D01*
G01X479733Y221292D02*
X479983Y221417D01*
X480275Y221500D01*
X480608D01*
X480983Y221375D01*
X481275Y221167D01*
X481483Y220917D01*
X481650Y220500D01*
X481692Y220125D01*
X481608Y219750D01*
X481483Y219500D01*
X481233Y219250D01*
X480942Y219083D01*
X480650Y219000D01*
X480358D01*
X480067Y219083D01*
X479817Y219208D01*
X479608Y219375D01*
G01X477550Y219000D02*
Y221500D01*
X478050Y221000D01*
G01Y219000D02*
X477050D01*
G01X474450Y221500D02*
X474783Y221417D01*
X475033Y221208D01*
X475200Y220958D01*
X475325Y220625D01*
X475367Y220250D01*
X475325Y219875D01*
X475200Y219542D01*
X475033Y219292D01*
X474783Y219083D01*
X474450Y219000D01*
X474117Y219083D01*
X473867Y219292D01*
X473700Y219542D01*
X473575Y219875D01*
X473533Y220250D01*
X473575Y220625D01*
X473700Y220958D01*
X473867Y221208D01*
X474117Y221417D01*
X474450Y221500D01*
G01X471350Y219000D02*
Y221500D01*
X471850Y221000D01*
G01Y219000D02*
X470850D01*
G01X468250D02*
Y221500D01*
X468750Y221000D01*
G01Y219000D02*
X467750D01*
G01X484625Y236333D02*
X484292Y236125D01*
X483917Y236000D01*
X483583D01*
X483250Y236125D01*
X483000Y236333D01*
X482875Y236625D01*
X482958Y236917D01*
X483167Y237167D01*
X483542Y237333D01*
X484042Y237417D01*
X484333Y237583D01*
X484458Y237875D01*
X484375Y238167D01*
X484167Y238375D01*
X483875Y238500D01*
X483583D01*
X483292Y238417D01*
X483042Y238208D01*
G01X480650Y238500D02*
Y236000D01*
G01X481608Y238500D02*
X479692D01*
G01X478383Y236000D02*
Y238500D01*
X477383D01*
X477050Y238375D01*
X476800Y238083D01*
X476717Y237750D01*
X476800Y237417D01*
X477008Y237167D01*
X477383Y237042D01*
X478383D01*
G01X474450Y236000D02*
Y238500D01*
X474950Y238000D01*
G01Y236000D02*
X473950D01*
G01X472267Y236375D02*
X472017Y236167D01*
X471725Y236042D01*
X471350Y236000D01*
X470975Y236083D01*
X470683Y236250D01*
X470475Y236542D01*
X470433Y236875D01*
X470517Y237208D01*
X470725Y237417D01*
X471017Y237583D01*
X471308Y237625D01*
X471600Y237583D01*
X471975Y237417D01*
X471850Y238500D01*
X470725D01*
G01X468250Y236000D02*
Y238500D01*
X468750Y238000D01*
G01Y236000D02*
X467750D01*
G01X480625Y230833D02*
X480292Y230625D01*
X479917Y230500D01*
X479583D01*
X479250Y230625D01*
X479000Y230833D01*
X478875Y231125D01*
X478958Y231417D01*
X479167Y231667D01*
X479542Y231833D01*
X480042Y231917D01*
X480333Y232083D01*
X480458Y232375D01*
X480375Y232667D01*
X480167Y232875D01*
X479875Y233000D01*
X479583D01*
X479292Y232917D01*
X479042Y232708D01*
G01X476650Y233000D02*
Y230500D01*
G01X477608Y233000D02*
X475692D01*
G01X474383Y230500D02*
Y233000D01*
X473383D01*
X473050Y232875D01*
X472800Y232583D01*
X472717Y232250D01*
X472800Y231917D01*
X473008Y231667D01*
X473383Y231542D01*
X474383D01*
G01X470450Y230500D02*
Y233000D01*
X470950Y232500D01*
G01Y230500D02*
X469950D01*
G01X468267Y230875D02*
X468017Y230667D01*
X467725Y230542D01*
X467350Y230500D01*
X466975Y230583D01*
X466683Y230750D01*
X466475Y231042D01*
X466433Y231375D01*
X466517Y231708D01*
X466725Y231917D01*
X467017Y232083D01*
X467308Y232125D01*
X467600Y232083D01*
X467975Y231917D01*
X467850Y233000D01*
X466725D01*
G01X464958Y230792D02*
X464667Y230583D01*
X464333Y230500D01*
X464000Y230583D01*
X463708Y230833D01*
X463500Y231208D01*
X463417Y231583D01*
Y232042D01*
X463500Y232417D01*
X463708Y232750D01*
X463958Y232917D01*
X464250Y233000D01*
X464583Y232917D01*
X464833Y232750D01*
X465000Y232500D01*
X465083Y232167D01*
X465000Y231875D01*
X464792Y231583D01*
X464542Y231417D01*
X464250Y231375D01*
X463917Y231458D01*
X463667Y231667D01*
X463417Y232042D01*
G01X480125Y225333D02*
X479792Y225125D01*
X479417Y225000D01*
X479083D01*
X478750Y225125D01*
X478500Y225333D01*
X478375Y225625D01*
X478458Y225917D01*
X478667Y226167D01*
X479042Y226333D01*
X479542Y226417D01*
X479833Y226583D01*
X479958Y226875D01*
X479875Y227167D01*
X479667Y227375D01*
X479375Y227500D01*
X479083D01*
X478792Y227417D01*
X478542Y227208D01*
G01X476150Y227500D02*
Y225000D01*
G01X477108Y227500D02*
X475192D01*
G01X473883Y225000D02*
Y227500D01*
X472883D01*
X472550Y227375D01*
X472300Y227083D01*
X472217Y226750D01*
X472300Y226417D01*
X472508Y226167D01*
X472883Y226042D01*
X473883D01*
G01X469950Y225000D02*
Y227500D01*
X470450Y227000D01*
G01Y225000D02*
X469450D01*
G01X467767Y225375D02*
X467517Y225167D01*
X467225Y225042D01*
X466850Y225000D01*
X466475Y225083D01*
X466183Y225250D01*
X465975Y225542D01*
X465933Y225875D01*
X466017Y226208D01*
X466225Y226417D01*
X466517Y226583D01*
X466808Y226625D01*
X467100Y226583D01*
X467475Y226417D01*
X467350Y227500D01*
X466225D01*
G01X464667Y225500D02*
X464417Y225208D01*
X464083Y225042D01*
X463708Y225000D01*
X463375Y225042D01*
X463042Y225250D01*
X462833Y225500D01*
X462792Y225750D01*
X462875Y226042D01*
X463167Y226250D01*
X463458Y226333D01*
X463833D01*
G01X463458D02*
X463208Y226458D01*
X463000Y226667D01*
X462917Y226917D01*
X463000Y227167D01*
X463208Y227375D01*
X463583Y227500D01*
X463958Y227458D01*
X464333Y227292D01*
G01X465333Y264925D02*
X465125Y265258D01*
X465000Y265633D01*
Y265967D01*
X465125Y266300D01*
X465333Y266550D01*
X465625Y266675D01*
X465917Y266592D01*
X466167Y266383D01*
X466333Y266008D01*
X466417Y265508D01*
X466583Y265217D01*
X466875Y265092D01*
X467167Y265175D01*
X467375Y265383D01*
X467500Y265675D01*
Y265967D01*
X467417Y266258D01*
X467208Y266508D01*
G01X465000Y268067D02*
X467500D01*
Y269108D01*
X467375Y269442D01*
X467208Y269650D01*
X466875Y269733D01*
X466542Y269650D01*
X466333Y269400D01*
X466208Y269108D01*
Y268067D01*
G01Y269108D02*
X465000Y269733D01*
G01X465292Y271292D02*
X465083Y271583D01*
X465000Y271917D01*
X465083Y272250D01*
X465333Y272542D01*
X465708Y272750D01*
X466083Y272833D01*
X466542D01*
X466917Y272750D01*
X467250Y272542D01*
X467417Y272292D01*
X467500Y272000D01*
X467417Y271667D01*
X467250Y271417D01*
X467000Y271250D01*
X466667Y271167D01*
X466375Y271250D01*
X466083Y271458D01*
X465917Y271708D01*
X465875Y272000D01*
X465958Y272333D01*
X466167Y272583D01*
X466542Y272833D01*
G01X465375Y274183D02*
X465167Y274433D01*
X465042Y274725D01*
X465000Y275100D01*
X465083Y275475D01*
X465250Y275767D01*
X465542Y275975D01*
X465875Y276017D01*
X466208Y275933D01*
X466417Y275725D01*
X466583Y275433D01*
X466625Y275142D01*
X466583Y274850D01*
X466417Y274475D01*
X467500Y274600D01*
Y275725D01*
G01X465000Y278117D02*
X465542Y278200D01*
X466000Y278325D01*
X466417Y278492D01*
X466875Y278700D01*
X467500Y279033D01*
Y277367D01*
G01X487625Y283833D02*
X487292Y283625D01*
X486917Y283500D01*
X486583D01*
X486250Y283625D01*
X486000Y283833D01*
X485875Y284125D01*
X485958Y284417D01*
X486167Y284667D01*
X486542Y284833D01*
X487042Y284917D01*
X487333Y285083D01*
X487458Y285375D01*
X487375Y285667D01*
X487167Y285875D01*
X486875Y286000D01*
X486583D01*
X486292Y285917D01*
X486042Y285708D01*
G01X483650Y286000D02*
Y283500D01*
G01X484608Y286000D02*
X482692D01*
G01X481383Y283500D02*
Y286000D01*
X480383D01*
X480050Y285875D01*
X479800Y285583D01*
X479717Y285250D01*
X479800Y284917D01*
X480008Y284667D01*
X480383Y284542D01*
X481383D01*
G01X477450Y283500D02*
Y286000D01*
X477950Y285500D01*
G01Y283500D02*
X476950D01*
G01X474350D02*
Y286000D01*
X474850Y285500D01*
G01Y283500D02*
X473850D01*
G01X472042Y285583D02*
X471792Y285833D01*
X471500Y285958D01*
X471167Y286000D01*
X470750Y285917D01*
X470458Y285708D01*
X470375Y285458D01*
X470417Y285208D01*
X470583Y285000D01*
X471417Y284583D01*
X471792Y284292D01*
X472042Y283875D01*
X472125Y283500D01*
X470375D01*
G01X487625Y292833D02*
X487292Y292625D01*
X486917Y292500D01*
X486583D01*
X486250Y292625D01*
X486000Y292833D01*
X485875Y293125D01*
X485958Y293417D01*
X486167Y293667D01*
X486542Y293833D01*
X487042Y293917D01*
X487333Y294083D01*
X487458Y294375D01*
X487375Y294667D01*
X487167Y294875D01*
X486875Y295000D01*
X486583D01*
X486292Y294917D01*
X486042Y294708D01*
G01X482733Y294792D02*
X482983Y294917D01*
X483275Y295000D01*
X483608D01*
X483983Y294875D01*
X484275Y294667D01*
X484483Y294417D01*
X484650Y294000D01*
X484692Y293625D01*
X484608Y293250D01*
X484483Y293000D01*
X484233Y292750D01*
X483942Y292583D01*
X483650Y292500D01*
X483358D01*
X483067Y292583D01*
X482817Y292708D01*
X482608Y292875D01*
G01X480550Y292500D02*
Y295000D01*
X481050Y294500D01*
G01Y292500D02*
X480050D01*
G01X478242Y294583D02*
X477992Y294833D01*
X477700Y294958D01*
X477367Y295000D01*
X476950Y294917D01*
X476658Y294708D01*
X476575Y294458D01*
X476617Y294208D01*
X476783Y294000D01*
X477617Y293583D01*
X477992Y293292D01*
X478242Y292875D01*
X478325Y292500D01*
X476575D01*
G01X474350D02*
Y295000D01*
X474850Y294500D01*
G01Y292500D02*
X473850D01*
G01X472042Y294583D02*
X471792Y294833D01*
X471500Y294958D01*
X471167Y295000D01*
X470750Y294917D01*
X470458Y294708D01*
X470375Y294458D01*
X470417Y294208D01*
X470583Y294000D01*
X471417Y293583D01*
X471792Y293292D01*
X472042Y292875D01*
X472125Y292500D01*
X470375D01*
G01X465455Y306700D02*
Y310700D01*
X472855D01*
G01X474323Y332283D02*
Y336283D01*
X481723D01*
G01X494125Y340333D02*
X493792Y340125D01*
X493417Y340000D01*
X493083D01*
X492750Y340125D01*
X492500Y340333D01*
X492375Y340625D01*
X492458Y340917D01*
X492667Y341167D01*
X493042Y341333D01*
X493542Y341417D01*
X493833Y341583D01*
X493958Y341875D01*
X493875Y342167D01*
X493667Y342375D01*
X493375Y342500D01*
X493083D01*
X492792Y342417D01*
X492542Y342208D01*
G01X489233Y342292D02*
X489483Y342417D01*
X489775Y342500D01*
X490108D01*
X490483Y342375D01*
X490775Y342167D01*
X490983Y341917D01*
X491150Y341500D01*
X491192Y341125D01*
X491108Y340750D01*
X490983Y340500D01*
X490733Y340250D01*
X490442Y340083D01*
X490150Y340000D01*
X489858D01*
X489567Y340083D01*
X489317Y340208D01*
X489108Y340375D01*
G01X487050Y340000D02*
Y342500D01*
X487550Y342000D01*
G01Y340000D02*
X486550D01*
G01X483950D02*
Y342500D01*
X484450Y342000D01*
G01Y340000D02*
X483450D01*
G01X480850D02*
X480558Y340042D01*
X480225Y340167D01*
X480017Y340375D01*
X479933Y340667D01*
X480017Y340958D01*
X480267Y341208D01*
X480642Y341333D01*
X481058D01*
X481308Y341417D01*
X481517Y341625D01*
X481600Y341917D01*
X481475Y342208D01*
X481183Y342417D01*
X480850Y342500D01*
X480517Y342417D01*
X480225Y342208D01*
X480100Y341917D01*
X480183Y341625D01*
X480392Y341417D01*
X480642Y341333D01*
X481058D01*
X481433Y341208D01*
X481683Y340958D01*
X481767Y340667D01*
X481683Y340375D01*
X481475Y340167D01*
X481142Y340042D01*
X480850Y340000D01*
G01X477750D02*
Y342500D01*
X478250Y342000D01*
G01Y340000D02*
X477250D01*
G01X495125Y348333D02*
X494792Y348125D01*
X494417Y348000D01*
X494083D01*
X493750Y348125D01*
X493500Y348333D01*
X493375Y348625D01*
X493458Y348917D01*
X493667Y349167D01*
X494042Y349333D01*
X494542Y349417D01*
X494833Y349583D01*
X494958Y349875D01*
X494875Y350167D01*
X494667Y350375D01*
X494375Y350500D01*
X494083D01*
X493792Y350417D01*
X493542Y350208D01*
G01X490233Y350292D02*
X490483Y350417D01*
X490775Y350500D01*
X491108D01*
X491483Y350375D01*
X491775Y350167D01*
X491983Y349917D01*
X492150Y349500D01*
X492192Y349125D01*
X492108Y348750D01*
X491983Y348500D01*
X491733Y348250D01*
X491442Y348083D01*
X491150Y348000D01*
X490858D01*
X490567Y348083D01*
X490317Y348208D01*
X490108Y348375D01*
G01X488050Y348000D02*
Y350500D01*
X488550Y350000D01*
G01Y348000D02*
X487550D01*
G01X484950D02*
Y350500D01*
X485450Y350000D01*
G01Y348000D02*
X484450D01*
G01X481350D02*
Y350500D01*
X482892Y348708D01*
X480808D01*
G01X478750Y350500D02*
X479083Y350417D01*
X479333Y350208D01*
X479500Y349958D01*
X479625Y349625D01*
X479667Y349250D01*
X479625Y348875D01*
X479500Y348542D01*
X479333Y348292D01*
X479083Y348083D01*
X478750Y348000D01*
X478417Y348083D01*
X478167Y348292D01*
X478000Y348542D01*
X477875Y348875D01*
X477833Y349250D01*
X477875Y349625D01*
X478000Y349958D01*
X478167Y350208D01*
X478417Y350417D01*
X478750Y350500D01*
G01X467333Y344925D02*
X467125Y345258D01*
X467000Y345633D01*
Y345967D01*
X467125Y346300D01*
X467333Y346550D01*
X467625Y346675D01*
X467917Y346592D01*
X468167Y346383D01*
X468333Y346008D01*
X468417Y345508D01*
X468583Y345217D01*
X468875Y345092D01*
X469167Y345175D01*
X469375Y345383D01*
X469500Y345675D01*
Y345967D01*
X469417Y346258D01*
X469208Y346508D01*
G01X469500Y348900D02*
X467000D01*
G01X469500Y347942D02*
Y349858D01*
G01X467000Y351167D02*
X469500D01*
Y352167D01*
X469375Y352500D01*
X469083Y352750D01*
X468750Y352833D01*
X468417Y352750D01*
X468167Y352542D01*
X468042Y352167D01*
Y351167D01*
G01Y354308D02*
X468333Y354600D01*
X468500Y354850D01*
X468583Y355183D01*
X468500Y355475D01*
X468333Y355683D01*
X468083Y355850D01*
X467792Y355892D01*
X467542Y355850D01*
X467292Y355683D01*
X467083Y355433D01*
X467000Y355142D01*
X467083Y354808D01*
X467333Y354517D01*
X467708Y354350D01*
X468125Y354308D01*
X468667Y354392D01*
X468958Y354517D01*
X469250Y354725D01*
X469458Y355017D01*
X469500Y355308D01*
X469417Y355600D01*
X469208Y355808D01*
G01X467000Y358700D02*
X469500D01*
X467708Y357158D01*
Y359242D01*
G01X479625Y360833D02*
X479292Y360625D01*
X478917Y360500D01*
X478583D01*
X478250Y360625D01*
X478000Y360833D01*
X477875Y361125D01*
X477958Y361417D01*
X478167Y361667D01*
X478542Y361833D01*
X479042Y361917D01*
X479333Y362083D01*
X479458Y362375D01*
X479375Y362667D01*
X479167Y362875D01*
X478875Y363000D01*
X478583D01*
X478292Y362917D01*
X478042Y362708D01*
G01X474733Y362792D02*
X474983Y362917D01*
X475275Y363000D01*
X475608D01*
X475983Y362875D01*
X476275Y362667D01*
X476483Y362417D01*
X476650Y362000D01*
X476692Y361625D01*
X476608Y361250D01*
X476483Y361000D01*
X476233Y360750D01*
X475942Y360583D01*
X475650Y360500D01*
X475358D01*
X475067Y360583D01*
X474817Y360708D01*
X474608Y360875D01*
G01X472550Y360500D02*
Y363000D01*
X473050Y362500D01*
G01Y360500D02*
X472050D01*
G01X470242Y362583D02*
X469992Y362833D01*
X469700Y362958D01*
X469367Y363000D01*
X468950Y362917D01*
X468658Y362708D01*
X468575Y362458D01*
X468617Y362208D01*
X468783Y362000D01*
X469617Y361583D01*
X469992Y361292D01*
X470242Y360875D01*
X470325Y360500D01*
X468575D01*
G01X467267Y360875D02*
X467017Y360667D01*
X466725Y360542D01*
X466350Y360500D01*
X465975Y360583D01*
X465683Y360750D01*
X465475Y361042D01*
X465433Y361375D01*
X465517Y361708D01*
X465725Y361917D01*
X466017Y362083D01*
X466308Y362125D01*
X466600Y362083D01*
X466975Y361917D01*
X466850Y363000D01*
X465725D01*
G01X463250Y360500D02*
X462958Y360542D01*
X462625Y360667D01*
X462417Y360875D01*
X462333Y361167D01*
X462417Y361458D01*
X462667Y361708D01*
X463042Y361833D01*
X463458D01*
X463708Y361917D01*
X463917Y362125D01*
X464000Y362417D01*
X463875Y362708D01*
X463583Y362917D01*
X463250Y363000D01*
X462917Y362917D01*
X462625Y362708D01*
X462500Y362417D01*
X462583Y362125D01*
X462792Y361917D01*
X463042Y361833D01*
X463458D01*
X463833Y361708D01*
X464083Y361458D01*
X464167Y361167D01*
X464083Y360875D01*
X463875Y360667D01*
X463542Y360542D01*
X463250Y360500D01*
G01X479125Y367833D02*
X478792Y367625D01*
X478417Y367500D01*
X478083D01*
X477750Y367625D01*
X477500Y367833D01*
X477375Y368125D01*
X477458Y368417D01*
X477667Y368667D01*
X478042Y368833D01*
X478542Y368917D01*
X478833Y369083D01*
X478958Y369375D01*
X478875Y369667D01*
X478667Y369875D01*
X478375Y370000D01*
X478083D01*
X477792Y369917D01*
X477542Y369708D01*
G01X474233Y369792D02*
X474483Y369917D01*
X474775Y370000D01*
X475108D01*
X475483Y369875D01*
X475775Y369667D01*
X475983Y369417D01*
X476150Y369000D01*
X476192Y368625D01*
X476108Y368250D01*
X475983Y368000D01*
X475733Y367750D01*
X475442Y367583D01*
X475150Y367500D01*
X474858D01*
X474567Y367583D01*
X474317Y367708D01*
X474108Y367875D01*
G01X472050Y367500D02*
Y370000D01*
X472550Y369500D01*
G01Y367500D02*
X471550D01*
G01X468950D02*
Y370000D01*
X469450Y369500D01*
G01Y367500D02*
X468450D01*
G01X465350D02*
Y370000D01*
X466892Y368208D01*
X464808D01*
G01X463667Y368000D02*
X463417Y367708D01*
X463083Y367542D01*
X462708Y367500D01*
X462375Y367542D01*
X462042Y367750D01*
X461833Y368000D01*
X461792Y368250D01*
X461875Y368542D01*
X462167Y368750D01*
X462458Y368833D01*
X462833D01*
G01X462458D02*
X462208Y368958D01*
X462000Y369167D01*
X461917Y369417D01*
X462000Y369667D01*
X462208Y369875D01*
X462583Y370000D01*
X462958Y369958D01*
X463333Y369792D01*
G01X478388Y383375D02*
X478180Y383708D01*
X478055Y384083D01*
Y384417D01*
X478180Y384750D01*
X478388Y385000D01*
X478680Y385125D01*
X478972Y385042D01*
X479222Y384833D01*
X479388Y384458D01*
X479472Y383958D01*
X479638Y383667D01*
X479930Y383542D01*
X480222Y383625D01*
X480430Y383833D01*
X480555Y384125D01*
Y384417D01*
X480472Y384708D01*
X480263Y384958D01*
G01X480347Y388267D02*
X480472Y388017D01*
X480555Y387725D01*
Y387392D01*
X480430Y387017D01*
X480222Y386725D01*
X479972Y386517D01*
X479555Y386350D01*
X479180Y386308D01*
X478805Y386392D01*
X478555Y386517D01*
X478305Y386767D01*
X478138Y387058D01*
X478055Y387350D01*
Y387642D01*
X478138Y387933D01*
X478263Y388183D01*
X478430Y388392D01*
G01X478055Y390450D02*
X480555D01*
X480055Y389950D01*
G01X478055D02*
Y390950D01*
G01Y393550D02*
X480555D01*
X480055Y393050D01*
G01X478055D02*
Y394050D01*
G01Y396650D02*
X478097Y396942D01*
X478222Y397275D01*
X478430Y397483D01*
X478722Y397567D01*
X479013Y397483D01*
X479263Y397233D01*
X479388Y396858D01*
Y396442D01*
X479472Y396192D01*
X479680Y395983D01*
X479972Y395900D01*
X480263Y396025D01*
X480472Y396317D01*
X480555Y396650D01*
X480472Y396983D01*
X480263Y397275D01*
X479972Y397400D01*
X479680Y397317D01*
X479472Y397108D01*
X479388Y396858D01*
Y396442D01*
X479263Y396067D01*
X479013Y395817D01*
X478722Y395733D01*
X478430Y395817D01*
X478222Y396025D01*
X478097Y396358D01*
X478055Y396650D01*
G01X479097Y398958D02*
X479388Y399250D01*
X479555Y399500D01*
X479638Y399833D01*
X479555Y400125D01*
X479388Y400333D01*
X479138Y400500D01*
X478847Y400542D01*
X478597Y400500D01*
X478347Y400333D01*
X478138Y400083D01*
X478055Y399792D01*
X478138Y399458D01*
X478388Y399167D01*
X478763Y399000D01*
X479180Y398958D01*
X479722Y399042D01*
X480013Y399167D01*
X480305Y399375D01*
X480513Y399667D01*
X480555Y399958D01*
X480472Y400250D01*
X480263Y400458D01*
G01X463888Y390375D02*
X463680Y390708D01*
X463555Y391083D01*
Y391417D01*
X463680Y391750D01*
X463888Y392000D01*
X464180Y392125D01*
X464472Y392042D01*
X464722Y391833D01*
X464888Y391458D01*
X464972Y390958D01*
X465138Y390667D01*
X465430Y390542D01*
X465722Y390625D01*
X465930Y390833D01*
X466055Y391125D01*
Y391417D01*
X465972Y391708D01*
X465763Y391958D01*
G01X465847Y395267D02*
X465972Y395017D01*
X466055Y394725D01*
Y394392D01*
X465930Y394017D01*
X465722Y393725D01*
X465472Y393517D01*
X465055Y393350D01*
X464680Y393308D01*
X464305Y393392D01*
X464055Y393517D01*
X463805Y393767D01*
X463638Y394058D01*
X463555Y394350D01*
Y394642D01*
X463638Y394933D01*
X463763Y395183D01*
X463930Y395392D01*
G01X463555Y397450D02*
X466055D01*
X465555Y396950D01*
G01X463555D02*
Y397950D01*
G01Y400550D02*
X466055D01*
X465555Y400050D01*
G01X463555D02*
Y401050D01*
G01X464597Y402858D02*
X464888Y403150D01*
X465055Y403400D01*
X465138Y403733D01*
X465055Y404025D01*
X464888Y404233D01*
X464638Y404400D01*
X464347Y404442D01*
X464097Y404400D01*
X463847Y404233D01*
X463638Y403983D01*
X463555Y403692D01*
X463638Y403358D01*
X463888Y403067D01*
X464263Y402900D01*
X464680Y402858D01*
X465222Y402942D01*
X465513Y403067D01*
X465805Y403275D01*
X466013Y403567D01*
X466055Y403858D01*
X465972Y404150D01*
X465763Y404358D01*
G01X463847Y406042D02*
X463638Y406333D01*
X463555Y406667D01*
X463638Y407000D01*
X463888Y407292D01*
X464263Y407500D01*
X464638Y407583D01*
X465097D01*
X465472Y407500D01*
X465805Y407292D01*
X465972Y407042D01*
X466055Y406750D01*
X465972Y406417D01*
X465805Y406167D01*
X465555Y406000D01*
X465222Y405917D01*
X464930Y406000D01*
X464638Y406208D01*
X464472Y406458D01*
X464430Y406750D01*
X464513Y407083D01*
X464722Y407333D01*
X465097Y407583D01*
G01X474888Y455875D02*
X474680Y456208D01*
X474555Y456583D01*
Y456917D01*
X474680Y457250D01*
X474888Y457500D01*
X475180Y457625D01*
X475472Y457542D01*
X475722Y457333D01*
X475888Y456958D01*
X475972Y456458D01*
X476138Y456167D01*
X476430Y456042D01*
X476722Y456125D01*
X476930Y456333D01*
X477055Y456625D01*
Y456917D01*
X476972Y457208D01*
X476763Y457458D01*
G01X476847Y460767D02*
X476972Y460517D01*
X477055Y460225D01*
Y459892D01*
X476930Y459517D01*
X476722Y459225D01*
X476472Y459017D01*
X476055Y458850D01*
X475680Y458808D01*
X475305Y458892D01*
X475055Y459017D01*
X474805Y459267D01*
X474638Y459558D01*
X474555Y459850D01*
Y460142D01*
X474638Y460433D01*
X474763Y460683D01*
X474930Y460892D01*
G01X474555Y462950D02*
X477055D01*
X476555Y462450D01*
G01X474555D02*
Y463450D01*
G01Y466050D02*
X477055D01*
X476555Y465550D01*
G01X474555D02*
Y466550D01*
G01X475597Y468358D02*
X475888Y468650D01*
X476055Y468900D01*
X476138Y469233D01*
X476055Y469525D01*
X475888Y469733D01*
X475638Y469900D01*
X475347Y469942D01*
X475097Y469900D01*
X474847Y469733D01*
X474638Y469483D01*
X474555Y469192D01*
X474638Y468858D01*
X474888Y468567D01*
X475263Y468400D01*
X475680Y468358D01*
X476222Y468442D01*
X476513Y468567D01*
X476805Y468775D01*
X477013Y469067D01*
X477055Y469358D01*
X476972Y469650D01*
X476763Y469858D01*
G01X474555Y472250D02*
X474597Y472542D01*
X474722Y472875D01*
X474930Y473083D01*
X475222Y473167D01*
X475513Y473083D01*
X475763Y472833D01*
X475888Y472458D01*
Y472042D01*
X475972Y471792D01*
X476180Y471583D01*
X476472Y471500D01*
X476763Y471625D01*
X476972Y471917D01*
X477055Y472250D01*
X476972Y472583D01*
X476763Y472875D01*
X476472Y473000D01*
X476180Y472917D01*
X475972Y472708D01*
X475888Y472458D01*
Y472042D01*
X475763Y471667D01*
X475513Y471417D01*
X475222Y471333D01*
X474930Y471417D01*
X474722Y471625D01*
X474597Y471958D01*
X474555Y472250D01*
G01X469888Y455875D02*
X469680Y456208D01*
X469555Y456583D01*
Y456917D01*
X469680Y457250D01*
X469888Y457500D01*
X470180Y457625D01*
X470472Y457542D01*
X470722Y457333D01*
X470888Y456958D01*
X470972Y456458D01*
X471138Y456167D01*
X471430Y456042D01*
X471722Y456125D01*
X471930Y456333D01*
X472055Y456625D01*
Y456917D01*
X471972Y457208D01*
X471763Y457458D01*
G01X471847Y460767D02*
X471972Y460517D01*
X472055Y460225D01*
Y459892D01*
X471930Y459517D01*
X471722Y459225D01*
X471472Y459017D01*
X471055Y458850D01*
X470680Y458808D01*
X470305Y458892D01*
X470055Y459017D01*
X469805Y459267D01*
X469638Y459558D01*
X469555Y459850D01*
Y460142D01*
X469638Y460433D01*
X469763Y460683D01*
X469930Y460892D01*
G01X469555Y462950D02*
X472055D01*
X471555Y462450D01*
G01X469555D02*
Y463450D01*
G01Y466050D02*
X472055D01*
X471555Y465550D01*
G01X469555D02*
Y466550D01*
G01X470597Y468358D02*
X470888Y468650D01*
X471055Y468900D01*
X471138Y469233D01*
X471055Y469525D01*
X470888Y469733D01*
X470638Y469900D01*
X470347Y469942D01*
X470097Y469900D01*
X469847Y469733D01*
X469638Y469483D01*
X469555Y469192D01*
X469638Y468858D01*
X469888Y468567D01*
X470263Y468400D01*
X470680Y468358D01*
X471222Y468442D01*
X471513Y468567D01*
X471805Y468775D01*
X472013Y469067D01*
X472055Y469358D01*
X471972Y469650D01*
X471763Y469858D01*
G01X470055Y471333D02*
X469763Y471583D01*
X469597Y471917D01*
X469555Y472292D01*
X469597Y472625D01*
X469805Y472958D01*
X470055Y473167D01*
X470305Y473208D01*
X470597Y473125D01*
X470805Y472833D01*
X470888Y472542D01*
Y472167D01*
G01Y472542D02*
X471013Y472792D01*
X471222Y473000D01*
X471472Y473083D01*
X471722Y473000D01*
X471930Y472792D01*
X472055Y472417D01*
X472013Y472042D01*
X471847Y471667D01*
G01X472011Y799425D02*
X471803Y799758D01*
X471678Y800133D01*
Y800467D01*
X471803Y800800D01*
X472011Y801050D01*
X472303Y801175D01*
X472595Y801092D01*
X472845Y800883D01*
X473011Y800508D01*
X473095Y800008D01*
X473261Y799717D01*
X473553Y799592D01*
X473845Y799675D01*
X474053Y799883D01*
X474178Y800175D01*
Y800467D01*
X474095Y800758D01*
X473886Y801008D01*
G01X471678Y802567D02*
X474178D01*
Y803608D01*
X474053Y803942D01*
X473886Y804150D01*
X473553Y804233D01*
X473220Y804150D01*
X473011Y803900D01*
X472886Y803608D01*
Y802567D01*
G01Y803608D02*
X471678Y804233D01*
G01Y806500D02*
X471720Y806792D01*
X471845Y807125D01*
X472053Y807333D01*
X472345Y807417D01*
X472636Y807333D01*
X472886Y807083D01*
X473011Y806708D01*
Y806292D01*
X473095Y806042D01*
X473303Y805833D01*
X473595Y805750D01*
X473886Y805875D01*
X474095Y806167D01*
X474178Y806500D01*
X474095Y806833D01*
X473886Y807125D01*
X473595Y807250D01*
X473303Y807167D01*
X473095Y806958D01*
X473011Y806708D01*
Y806292D01*
X472886Y805917D01*
X472636Y805667D01*
X472345Y805583D01*
X472053Y805667D01*
X471845Y805875D01*
X471720Y806208D01*
X471678Y806500D01*
G01Y809600D02*
X471720Y809892D01*
X471845Y810225D01*
X472053Y810433D01*
X472345Y810517D01*
X472636Y810433D01*
X472886Y810183D01*
X473011Y809808D01*
Y809392D01*
X473095Y809142D01*
X473303Y808933D01*
X473595Y808850D01*
X473886Y808975D01*
X474095Y809267D01*
X474178Y809600D01*
X474095Y809933D01*
X473886Y810225D01*
X473595Y810350D01*
X473303Y810267D01*
X473095Y810058D01*
X473011Y809808D01*
Y809392D01*
X472886Y809017D01*
X472636Y808767D01*
X472345Y808683D01*
X472053Y808767D01*
X471845Y808975D01*
X471720Y809308D01*
X471678Y809600D01*
G01X472720Y811908D02*
X473011Y812200D01*
X473178Y812450D01*
X473261Y812783D01*
X473178Y813075D01*
X473011Y813283D01*
X472761Y813450D01*
X472470Y813492D01*
X472220Y813450D01*
X471970Y813283D01*
X471761Y813033D01*
X471678Y812742D01*
X471761Y812408D01*
X472011Y812117D01*
X472386Y811950D01*
X472803Y811908D01*
X473345Y811992D01*
X473636Y812117D01*
X473928Y812325D01*
X474136Y812617D01*
X474178Y812908D01*
X474095Y813200D01*
X473886Y813408D01*
G01X467511Y799425D02*
X467303Y799758D01*
X467178Y800133D01*
Y800467D01*
X467303Y800800D01*
X467511Y801050D01*
X467803Y801175D01*
X468095Y801092D01*
X468345Y800883D01*
X468511Y800508D01*
X468595Y800008D01*
X468761Y799717D01*
X469053Y799592D01*
X469345Y799675D01*
X469553Y799883D01*
X469678Y800175D01*
Y800467D01*
X469595Y800758D01*
X469386Y801008D01*
G01X467178Y802567D02*
X469678D01*
Y803608D01*
X469553Y803942D01*
X469386Y804150D01*
X469053Y804233D01*
X468720Y804150D01*
X468511Y803900D01*
X468386Y803608D01*
Y802567D01*
G01Y803608D02*
X467178Y804233D01*
G01Y806500D02*
X467220Y806792D01*
X467345Y807125D01*
X467553Y807333D01*
X467845Y807417D01*
X468136Y807333D01*
X468386Y807083D01*
X468511Y806708D01*
Y806292D01*
X468595Y806042D01*
X468803Y805833D01*
X469095Y805750D01*
X469386Y805875D01*
X469595Y806167D01*
X469678Y806500D01*
X469595Y806833D01*
X469386Y807125D01*
X469095Y807250D01*
X468803Y807167D01*
X468595Y806958D01*
X468511Y806708D01*
Y806292D01*
X468386Y805917D01*
X468136Y805667D01*
X467845Y805583D01*
X467553Y805667D01*
X467345Y805875D01*
X467220Y806208D01*
X467178Y806500D01*
G01X467470Y808892D02*
X467261Y809183D01*
X467178Y809517D01*
X467261Y809850D01*
X467511Y810142D01*
X467886Y810350D01*
X468261Y810433D01*
X468720D01*
X469095Y810350D01*
X469428Y810142D01*
X469595Y809892D01*
X469678Y809600D01*
X469595Y809267D01*
X469428Y809017D01*
X469178Y808850D01*
X468845Y808767D01*
X468553Y808850D01*
X468261Y809058D01*
X468095Y809308D01*
X468053Y809600D01*
X468136Y809933D01*
X468345Y810183D01*
X468720Y810433D01*
G01X469678Y812700D02*
X469595Y812367D01*
X469386Y812117D01*
X469136Y811950D01*
X468803Y811825D01*
X468428Y811783D01*
X468053Y811825D01*
X467720Y811950D01*
X467470Y812117D01*
X467261Y812367D01*
X467178Y812700D01*
X467261Y813033D01*
X467470Y813283D01*
X467720Y813450D01*
X468053Y813575D01*
X468428Y813617D01*
X468803Y813575D01*
X469136Y813450D01*
X469386Y813283D01*
X469595Y813033D01*
X469678Y812700D01*
G01X463128Y834000D02*
Y836000D01*
G01X471978Y856900D02*
X476978D01*
Y851900D01*
G01X476078Y847000D02*
X479078D01*
G01X465128Y856000D02*
Y858000D01*
G01X477833Y872375D02*
X477625Y872708D01*
X477500Y873083D01*
Y873417D01*
X477625Y873750D01*
X477833Y874000D01*
X478125Y874125D01*
X478417Y874042D01*
X478667Y873833D01*
X478833Y873458D01*
X478917Y872958D01*
X479083Y872667D01*
X479375Y872542D01*
X479667Y872625D01*
X479875Y872833D01*
X480000Y873125D01*
Y873417D01*
X479917Y873708D01*
X479708Y873958D01*
G01X480000Y876350D02*
X477500D01*
G01X480000Y875392D02*
Y877308D01*
G01X477500Y878617D02*
X480000D01*
Y879617D01*
X479875Y879950D01*
X479583Y880200D01*
X479250Y880283D01*
X478917Y880200D01*
X478667Y879992D01*
X478542Y879617D01*
Y878617D01*
G01X477500Y882550D02*
X480000D01*
X479500Y882050D01*
G01X477500D02*
Y883050D01*
G01Y886150D02*
X480000D01*
X478208Y884608D01*
Y886692D01*
G01X478000Y887833D02*
X477708Y888083D01*
X477542Y888417D01*
X477500Y888792D01*
X477542Y889125D01*
X477750Y889458D01*
X478000Y889667D01*
X478250Y889708D01*
X478542Y889625D01*
X478750Y889333D01*
X478833Y889042D01*
Y888667D01*
G01Y889042D02*
X478958Y889292D01*
X479167Y889500D01*
X479417Y889583D01*
X479667Y889500D01*
X479875Y889292D01*
X480000Y888917D01*
X479958Y888542D01*
X479792Y888167D01*
G01X481753Y866833D02*
X481420Y866625D01*
X481045Y866500D01*
X480711D01*
X480378Y866625D01*
X480128Y866833D01*
X480003Y867125D01*
X480086Y867417D01*
X480295Y867667D01*
X480670Y867833D01*
X481170Y867917D01*
X481461Y868083D01*
X481586Y868375D01*
X481503Y868667D01*
X481295Y868875D01*
X481003Y869000D01*
X480711D01*
X480420Y868917D01*
X480170Y868708D01*
G01X478611Y866500D02*
Y869000D01*
X477570D01*
X477236Y868875D01*
X477028Y868708D01*
X476945Y868375D01*
X477028Y868042D01*
X477278Y867833D01*
X477570Y867708D01*
X478611D01*
G01X477570D02*
X476945Y866500D01*
G01X474678D02*
X474386Y866542D01*
X474053Y866667D01*
X473845Y866875D01*
X473761Y867167D01*
X473845Y867458D01*
X474095Y867708D01*
X474470Y867833D01*
X474886D01*
X475136Y867917D01*
X475345Y868125D01*
X475428Y868417D01*
X475303Y868708D01*
X475011Y868917D01*
X474678Y869000D01*
X474345Y868917D01*
X474053Y868708D01*
X473928Y868417D01*
X474011Y868125D01*
X474220Y867917D01*
X474470Y867833D01*
X474886D01*
X475261Y867708D01*
X475511Y867458D01*
X475595Y867167D01*
X475511Y866875D01*
X475303Y866667D01*
X474970Y866542D01*
X474678Y866500D01*
G01X471578D02*
X471286Y866542D01*
X470953Y866667D01*
X470745Y866875D01*
X470661Y867167D01*
X470745Y867458D01*
X470995Y867708D01*
X471370Y867833D01*
X471786D01*
X472036Y867917D01*
X472245Y868125D01*
X472328Y868417D01*
X472203Y868708D01*
X471911Y868917D01*
X471578Y869000D01*
X471245Y868917D01*
X470953Y868708D01*
X470828Y868417D01*
X470911Y868125D01*
X471120Y867917D01*
X471370Y867833D01*
X471786D01*
X472161Y867708D01*
X472411Y867458D01*
X472495Y867167D01*
X472411Y866875D01*
X472203Y866667D01*
X471870Y866542D01*
X471578Y866500D01*
G01X469395Y866875D02*
X469145Y866667D01*
X468853Y866542D01*
X468478Y866500D01*
X468103Y866583D01*
X467811Y866750D01*
X467603Y867042D01*
X467561Y867375D01*
X467645Y867708D01*
X467853Y867917D01*
X468145Y868083D01*
X468436Y868125D01*
X468728Y868083D01*
X469103Y867917D01*
X468978Y869000D01*
X467853D01*
G01X465278Y877700D02*
X469278D01*
Y870300D01*
G01Y873800D02*
X465278D01*
Y881200D01*
G01X465611Y885425D02*
X465403Y885758D01*
X465278Y886133D01*
Y886467D01*
X465403Y886800D01*
X465611Y887050D01*
X465903Y887175D01*
X466195Y887092D01*
X466445Y886883D01*
X466611Y886508D01*
X466695Y886008D01*
X466861Y885717D01*
X467153Y885592D01*
X467445Y885675D01*
X467653Y885883D01*
X467778Y886175D01*
Y886467D01*
X467695Y886758D01*
X467486Y887008D01*
G01X465278Y888567D02*
X467778D01*
Y889608D01*
X467653Y889942D01*
X467486Y890150D01*
X467153Y890233D01*
X466820Y890150D01*
X466611Y889900D01*
X466486Y889608D01*
Y888567D01*
G01Y889608D02*
X465278Y890233D01*
G01Y892500D02*
X465320Y892792D01*
X465445Y893125D01*
X465653Y893333D01*
X465945Y893417D01*
X466236Y893333D01*
X466486Y893083D01*
X466611Y892708D01*
Y892292D01*
X466695Y892042D01*
X466903Y891833D01*
X467195Y891750D01*
X467486Y891875D01*
X467695Y892167D01*
X467778Y892500D01*
X467695Y892833D01*
X467486Y893125D01*
X467195Y893250D01*
X466903Y893167D01*
X466695Y892958D01*
X466611Y892708D01*
Y892292D01*
X466486Y891917D01*
X466236Y891667D01*
X465945Y891583D01*
X465653Y891667D01*
X465445Y891875D01*
X465320Y892208D01*
X465278Y892500D01*
G01Y895600D02*
X465320Y895892D01*
X465445Y896225D01*
X465653Y896433D01*
X465945Y896517D01*
X466236Y896433D01*
X466486Y896183D01*
X466611Y895808D01*
Y895392D01*
X466695Y895142D01*
X466903Y894933D01*
X467195Y894850D01*
X467486Y894975D01*
X467695Y895267D01*
X467778Y895600D01*
X467695Y895933D01*
X467486Y896225D01*
X467195Y896350D01*
X466903Y896267D01*
X466695Y896058D01*
X466611Y895808D01*
Y895392D01*
X466486Y895017D01*
X466236Y894767D01*
X465945Y894683D01*
X465653Y894767D01*
X465445Y894975D01*
X465320Y895308D01*
X465278Y895600D01*
G01Y898617D02*
X465820Y898700D01*
X466278Y898825D01*
X466695Y898992D01*
X467153Y899200D01*
X467778Y899533D01*
Y897867D01*
G01X482833Y108925D02*
X482625Y109258D01*
X482500Y109633D01*
Y109967D01*
X482625Y110300D01*
X482833Y110550D01*
X483125Y110675D01*
X483417Y110592D01*
X483667Y110383D01*
X483833Y110008D01*
X483917Y109508D01*
X484083Y109217D01*
X484375Y109092D01*
X484667Y109175D01*
X484875Y109383D01*
X485000Y109675D01*
Y109967D01*
X484917Y110258D01*
X484708Y110508D01*
G01X484792Y113817D02*
X484917Y113567D01*
X485000Y113275D01*
Y112942D01*
X484875Y112567D01*
X484667Y112275D01*
X484417Y112067D01*
X484000Y111900D01*
X483625Y111858D01*
X483250Y111942D01*
X483000Y112067D01*
X482750Y112317D01*
X482583Y112608D01*
X482500Y112900D01*
Y113192D01*
X482583Y113483D01*
X482708Y113733D01*
X482875Y113942D01*
G01X482792Y115292D02*
X482583Y115583D01*
X482500Y115917D01*
X482583Y116250D01*
X482833Y116542D01*
X483208Y116750D01*
X483583Y116833D01*
X484042D01*
X484417Y116750D01*
X484750Y116542D01*
X484917Y116292D01*
X485000Y116000D01*
X484917Y115667D01*
X484750Y115417D01*
X484500Y115250D01*
X484167Y115167D01*
X483875Y115250D01*
X483583Y115458D01*
X483417Y115708D01*
X483375Y116000D01*
X483458Y116333D01*
X483667Y116583D01*
X484042Y116833D01*
G01X483000Y118183D02*
X482708Y118433D01*
X482542Y118767D01*
X482500Y119142D01*
X482542Y119475D01*
X482750Y119808D01*
X483000Y120017D01*
X483250Y120058D01*
X483542Y119975D01*
X483750Y119683D01*
X483833Y119392D01*
Y119017D01*
G01Y119392D02*
X483958Y119642D01*
X484167Y119850D01*
X484417Y119933D01*
X484667Y119850D01*
X484875Y119642D01*
X485000Y119267D01*
X484958Y118892D01*
X484792Y118517D01*
G01X483000Y121283D02*
X482708Y121533D01*
X482542Y121867D01*
X482500Y122242D01*
X482542Y122575D01*
X482750Y122908D01*
X483000Y123117D01*
X483250Y123158D01*
X483542Y123075D01*
X483750Y122783D01*
X483833Y122492D01*
Y122117D01*
G01Y122492D02*
X483958Y122742D01*
X484167Y122950D01*
X484417Y123033D01*
X484667Y122950D01*
X484875Y122742D01*
X485000Y122367D01*
X484958Y121992D01*
X484792Y121617D01*
G01X487262Y108925D02*
X487054Y109258D01*
X486929Y109633D01*
Y109967D01*
X487054Y110300D01*
X487262Y110550D01*
X487554Y110675D01*
X487846Y110592D01*
X488096Y110383D01*
X488262Y110008D01*
X488346Y109508D01*
X488512Y109217D01*
X488804Y109092D01*
X489096Y109175D01*
X489304Y109383D01*
X489429Y109675D01*
Y109967D01*
X489346Y110258D01*
X489137Y110508D01*
G01X489221Y113817D02*
X489346Y113567D01*
X489429Y113275D01*
Y112942D01*
X489304Y112567D01*
X489096Y112275D01*
X488846Y112067D01*
X488429Y111900D01*
X488054Y111858D01*
X487679Y111942D01*
X487429Y112067D01*
X487179Y112317D01*
X487012Y112608D01*
X486929Y112900D01*
Y113192D01*
X487012Y113483D01*
X487137Y113733D01*
X487304Y113942D01*
G01X487221Y115292D02*
X487012Y115583D01*
X486929Y115917D01*
X487012Y116250D01*
X487262Y116542D01*
X487637Y116750D01*
X488012Y116833D01*
X488471D01*
X488846Y116750D01*
X489179Y116542D01*
X489346Y116292D01*
X489429Y116000D01*
X489346Y115667D01*
X489179Y115417D01*
X488929Y115250D01*
X488596Y115167D01*
X488304Y115250D01*
X488012Y115458D01*
X487846Y115708D01*
X487804Y116000D01*
X487887Y116333D01*
X488096Y116583D01*
X488471Y116833D01*
G01X487429Y118183D02*
X487137Y118433D01*
X486971Y118767D01*
X486929Y119142D01*
X486971Y119475D01*
X487179Y119808D01*
X487429Y120017D01*
X487679Y120058D01*
X487971Y119975D01*
X488179Y119683D01*
X488262Y119392D01*
Y119017D01*
G01Y119392D02*
X488387Y119642D01*
X488596Y119850D01*
X488846Y119933D01*
X489096Y119850D01*
X489304Y119642D01*
X489429Y119267D01*
X489387Y118892D01*
X489221Y118517D01*
G01X486929Y122700D02*
X489429D01*
X487637Y121158D01*
Y123242D01*
G01X491762Y108925D02*
X491554Y109258D01*
X491429Y109633D01*
Y109967D01*
X491554Y110300D01*
X491762Y110550D01*
X492054Y110675D01*
X492346Y110592D01*
X492596Y110383D01*
X492762Y110008D01*
X492846Y109508D01*
X493012Y109217D01*
X493304Y109092D01*
X493596Y109175D01*
X493804Y109383D01*
X493929Y109675D01*
Y109967D01*
X493846Y110258D01*
X493637Y110508D01*
G01X493721Y113817D02*
X493846Y113567D01*
X493929Y113275D01*
Y112942D01*
X493804Y112567D01*
X493596Y112275D01*
X493346Y112067D01*
X492929Y111900D01*
X492554Y111858D01*
X492179Y111942D01*
X491929Y112067D01*
X491679Y112317D01*
X491512Y112608D01*
X491429Y112900D01*
Y113192D01*
X491512Y113483D01*
X491637Y113733D01*
X491804Y113942D01*
G01X491721Y115292D02*
X491512Y115583D01*
X491429Y115917D01*
X491512Y116250D01*
X491762Y116542D01*
X492137Y116750D01*
X492512Y116833D01*
X492971D01*
X493346Y116750D01*
X493679Y116542D01*
X493846Y116292D01*
X493929Y116000D01*
X493846Y115667D01*
X493679Y115417D01*
X493429Y115250D01*
X493096Y115167D01*
X492804Y115250D01*
X492512Y115458D01*
X492346Y115708D01*
X492304Y116000D01*
X492387Y116333D01*
X492596Y116583D01*
X492971Y116833D01*
G01X491929Y118183D02*
X491637Y118433D01*
X491471Y118767D01*
X491429Y119142D01*
X491471Y119475D01*
X491679Y119808D01*
X491929Y120017D01*
X492179Y120058D01*
X492471Y119975D01*
X492679Y119683D01*
X492762Y119392D01*
Y119017D01*
G01Y119392D02*
X492887Y119642D01*
X493096Y119850D01*
X493346Y119933D01*
X493596Y119850D01*
X493804Y119642D01*
X493929Y119267D01*
X493887Y118892D01*
X493721Y118517D01*
G01X491429Y122200D02*
X493929D01*
X493429Y121700D01*
G01X491429D02*
Y122700D01*
G01X480500Y147000D02*
Y161000D01*
X486500D01*
Y162500D01*
X501500D01*
Y173000D01*
X504000Y170500D01*
X499000D01*
X501500Y173000D01*
G01X488929Y142800D02*
X490929D01*
G01X488929Y156200D02*
Y142800D01*
G01X490929D02*
Y156200D01*
G01D02*
X488929D01*
G01X504575Y158333D02*
X504242Y158125D01*
X503867Y158000D01*
X503533D01*
X503200Y158125D01*
X502950Y158333D01*
X502825Y158625D01*
X502908Y158917D01*
X503117Y159167D01*
X503492Y159333D01*
X503992Y159417D01*
X504283Y159583D01*
X504408Y159875D01*
X504325Y160167D01*
X504117Y160375D01*
X503825Y160500D01*
X503533D01*
X503242Y160417D01*
X502992Y160208D01*
G01X499683Y160292D02*
X499933Y160417D01*
X500225Y160500D01*
X500558D01*
X500933Y160375D01*
X501225Y160167D01*
X501433Y159917D01*
X501600Y159500D01*
X501642Y159125D01*
X501558Y158750D01*
X501433Y158500D01*
X501183Y158250D01*
X500892Y158083D01*
X500600Y158000D01*
X500308D01*
X500017Y158083D01*
X499767Y158208D01*
X499558Y158375D01*
G01X498208Y158292D02*
X497917Y158083D01*
X497583Y158000D01*
X497250Y158083D01*
X496958Y158333D01*
X496750Y158708D01*
X496667Y159083D01*
Y159542D01*
X496750Y159917D01*
X496958Y160250D01*
X497208Y160417D01*
X497500Y160500D01*
X497833Y160417D01*
X498083Y160250D01*
X498250Y160000D01*
X498333Y159667D01*
X498250Y159375D01*
X498042Y159083D01*
X497792Y158917D01*
X497500Y158875D01*
X497167Y158958D01*
X496917Y159167D01*
X496667Y159542D01*
G01X494483Y158000D02*
X494400Y158542D01*
X494275Y159000D01*
X494108Y159417D01*
X493900Y159875D01*
X493567Y160500D01*
X495233D01*
G01X492217Y158500D02*
X491967Y158208D01*
X491633Y158042D01*
X491258Y158000D01*
X490925Y158042D01*
X490592Y158250D01*
X490383Y158500D01*
X490342Y158750D01*
X490425Y159042D01*
X490717Y159250D01*
X491008Y159333D01*
X491383D01*
G01X491008D02*
X490758Y159458D01*
X490550Y159667D01*
X490467Y159917D01*
X490550Y160167D01*
X490758Y160375D01*
X491133Y160500D01*
X491508Y160458D01*
X491883Y160292D01*
G01X499504Y198333D02*
X499171Y198125D01*
X498796Y198000D01*
X498462D01*
X498129Y198125D01*
X497879Y198333D01*
X497754Y198625D01*
X497837Y198917D01*
X498046Y199167D01*
X498421Y199333D01*
X498921Y199417D01*
X499212Y199583D01*
X499337Y199875D01*
X499254Y200167D01*
X499046Y200375D01*
X498754Y200500D01*
X498462D01*
X498171Y200417D01*
X497921Y200208D01*
G01X494612Y200292D02*
X494862Y200417D01*
X495154Y200500D01*
X495487D01*
X495862Y200375D01*
X496154Y200167D01*
X496362Y199917D01*
X496529Y199500D01*
X496571Y199125D01*
X496487Y198750D01*
X496362Y198500D01*
X496112Y198250D01*
X495821Y198083D01*
X495529Y198000D01*
X495237D01*
X494946Y198083D01*
X494696Y198208D01*
X494487Y198375D01*
G01X493137Y198292D02*
X492846Y198083D01*
X492512Y198000D01*
X492179Y198083D01*
X491887Y198333D01*
X491679Y198708D01*
X491596Y199083D01*
Y199542D01*
X491679Y199917D01*
X491887Y200250D01*
X492137Y200417D01*
X492429Y200500D01*
X492762Y200417D01*
X493012Y200250D01*
X493179Y200000D01*
X493262Y199667D01*
X493179Y199375D01*
X492971Y199083D01*
X492721Y198917D01*
X492429Y198875D01*
X492096Y198958D01*
X491846Y199167D01*
X491596Y199542D01*
G01X489412Y198000D02*
X489329Y198542D01*
X489204Y199000D01*
X489037Y199417D01*
X488829Y199875D01*
X488496Y200500D01*
X490162D01*
G01X485729Y198000D02*
Y200500D01*
X487271Y198708D01*
X485187D01*
G01X499504Y193833D02*
X499171Y193625D01*
X498796Y193500D01*
X498462D01*
X498129Y193625D01*
X497879Y193833D01*
X497754Y194125D01*
X497837Y194417D01*
X498046Y194667D01*
X498421Y194833D01*
X498921Y194917D01*
X499212Y195083D01*
X499337Y195375D01*
X499254Y195667D01*
X499046Y195875D01*
X498754Y196000D01*
X498462D01*
X498171Y195917D01*
X497921Y195708D01*
G01X494612Y195792D02*
X494862Y195917D01*
X495154Y196000D01*
X495487D01*
X495862Y195875D01*
X496154Y195667D01*
X496362Y195417D01*
X496529Y195000D01*
X496571Y194625D01*
X496487Y194250D01*
X496362Y194000D01*
X496112Y193750D01*
X495821Y193583D01*
X495529Y193500D01*
X495237D01*
X494946Y193583D01*
X494696Y193708D01*
X494487Y193875D01*
G01X493137Y193792D02*
X492846Y193583D01*
X492512Y193500D01*
X492179Y193583D01*
X491887Y193833D01*
X491679Y194208D01*
X491596Y194583D01*
Y195042D01*
X491679Y195417D01*
X491887Y195750D01*
X492137Y195917D01*
X492429Y196000D01*
X492762Y195917D01*
X493012Y195750D01*
X493179Y195500D01*
X493262Y195167D01*
X493179Y194875D01*
X492971Y194583D01*
X492721Y194417D01*
X492429Y194375D01*
X492096Y194458D01*
X491846Y194667D01*
X491596Y195042D01*
G01X489412Y193500D02*
X489329Y194042D01*
X489204Y194500D01*
X489037Y194917D01*
X488829Y195375D01*
X488496Y196000D01*
X490162D01*
G01X487146Y193875D02*
X486896Y193667D01*
X486604Y193542D01*
X486229Y193500D01*
X485854Y193583D01*
X485562Y193750D01*
X485354Y194042D01*
X485312Y194375D01*
X485396Y194708D01*
X485604Y194917D01*
X485896Y195083D01*
X486187Y195125D01*
X486479Y195083D01*
X486854Y194917D01*
X486729Y196000D01*
X485604D01*
G01X499504Y189333D02*
X499171Y189125D01*
X498796Y189000D01*
X498462D01*
X498129Y189125D01*
X497879Y189333D01*
X497754Y189625D01*
X497837Y189917D01*
X498046Y190167D01*
X498421Y190333D01*
X498921Y190417D01*
X499212Y190583D01*
X499337Y190875D01*
X499254Y191167D01*
X499046Y191375D01*
X498754Y191500D01*
X498462D01*
X498171Y191417D01*
X497921Y191208D01*
G01X494612Y191292D02*
X494862Y191417D01*
X495154Y191500D01*
X495487D01*
X495862Y191375D01*
X496154Y191167D01*
X496362Y190917D01*
X496529Y190500D01*
X496571Y190125D01*
X496487Y189750D01*
X496362Y189500D01*
X496112Y189250D01*
X495821Y189083D01*
X495529Y189000D01*
X495237D01*
X494946Y189083D01*
X494696Y189208D01*
X494487Y189375D01*
G01X493137Y189292D02*
X492846Y189083D01*
X492512Y189000D01*
X492179Y189083D01*
X491887Y189333D01*
X491679Y189708D01*
X491596Y190083D01*
Y190542D01*
X491679Y190917D01*
X491887Y191250D01*
X492137Y191417D01*
X492429Y191500D01*
X492762Y191417D01*
X493012Y191250D01*
X493179Y191000D01*
X493262Y190667D01*
X493179Y190375D01*
X492971Y190083D01*
X492721Y189917D01*
X492429Y189875D01*
X492096Y189958D01*
X491846Y190167D01*
X491596Y190542D01*
G01X490037Y189292D02*
X489746Y189083D01*
X489412Y189000D01*
X489079Y189083D01*
X488787Y189333D01*
X488579Y189708D01*
X488496Y190083D01*
Y190542D01*
X488579Y190917D01*
X488787Y191250D01*
X489037Y191417D01*
X489329Y191500D01*
X489662Y191417D01*
X489912Y191250D01*
X490079Y191000D01*
X490162Y190667D01*
X490079Y190375D01*
X489871Y190083D01*
X489621Y189917D01*
X489329Y189875D01*
X488996Y189958D01*
X488746Y190167D01*
X488496Y190542D01*
G01X485729Y189000D02*
Y191500D01*
X487271Y189708D01*
X485187D01*
G01X503625Y219333D02*
X503292Y219125D01*
X502917Y219000D01*
X502583D01*
X502250Y219125D01*
X502000Y219333D01*
X501875Y219625D01*
X501958Y219917D01*
X502167Y220167D01*
X502542Y220333D01*
X503042Y220417D01*
X503333Y220583D01*
X503458Y220875D01*
X503375Y221167D01*
X503167Y221375D01*
X502875Y221500D01*
X502583D01*
X502292Y221417D01*
X502042Y221208D01*
G01X498733Y221292D02*
X498983Y221417D01*
X499275Y221500D01*
X499608D01*
X499983Y221375D01*
X500275Y221167D01*
X500483Y220917D01*
X500650Y220500D01*
X500692Y220125D01*
X500608Y219750D01*
X500483Y219500D01*
X500233Y219250D01*
X499942Y219083D01*
X499650Y219000D01*
X499358D01*
X499067Y219083D01*
X498817Y219208D01*
X498608Y219375D01*
G01X496550Y219000D02*
Y221500D01*
X497050Y221000D01*
G01Y219000D02*
X496050D01*
G01X493450Y221500D02*
X493783Y221417D01*
X494033Y221208D01*
X494200Y220958D01*
X494325Y220625D01*
X494367Y220250D01*
X494325Y219875D01*
X494200Y219542D01*
X494033Y219292D01*
X493783Y219083D01*
X493450Y219000D01*
X493117Y219083D01*
X492867Y219292D01*
X492700Y219542D01*
X492575Y219875D01*
X492533Y220250D01*
X492575Y220625D01*
X492700Y220958D01*
X492867Y221208D01*
X493117Y221417D01*
X493450Y221500D01*
G01X490350Y219000D02*
Y221500D01*
X490850Y221000D01*
G01Y219000D02*
X489850D01*
G01X487250Y221500D02*
X487583Y221417D01*
X487833Y221208D01*
X488000Y220958D01*
X488125Y220625D01*
X488167Y220250D01*
X488125Y219875D01*
X488000Y219542D01*
X487833Y219292D01*
X487583Y219083D01*
X487250Y219000D01*
X486917Y219083D01*
X486667Y219292D01*
X486500Y219542D01*
X486375Y219875D01*
X486333Y220250D01*
X486375Y220625D01*
X486500Y220958D01*
X486667Y221208D01*
X486917Y221417D01*
X487250Y221500D01*
G01X504125Y229833D02*
X503792Y229625D01*
X503417Y229500D01*
X503083D01*
X502750Y229625D01*
X502500Y229833D01*
X502375Y230125D01*
X502458Y230417D01*
X502667Y230667D01*
X503042Y230833D01*
X503542Y230917D01*
X503833Y231083D01*
X503958Y231375D01*
X503875Y231667D01*
X503667Y231875D01*
X503375Y232000D01*
X503083D01*
X502792Y231917D01*
X502542Y231708D01*
G01X500150Y232000D02*
Y229500D01*
G01X501108Y232000D02*
X499192D01*
G01X497883Y229500D02*
Y232000D01*
X496883D01*
X496550Y231875D01*
X496300Y231583D01*
X496217Y231250D01*
X496300Y230917D01*
X496508Y230667D01*
X496883Y230542D01*
X497883D01*
G01X493950Y229500D02*
Y232000D01*
X494450Y231500D01*
G01Y229500D02*
X493450D01*
G01X491767Y229875D02*
X491517Y229667D01*
X491225Y229542D01*
X490850Y229500D01*
X490475Y229583D01*
X490183Y229750D01*
X489975Y230042D01*
X489933Y230375D01*
X490017Y230708D01*
X490225Y230917D01*
X490517Y231083D01*
X490808Y231125D01*
X491100Y231083D01*
X491475Y230917D01*
X491350Y232000D01*
X490225D01*
G01X488542Y231583D02*
X488292Y231833D01*
X488000Y231958D01*
X487667Y232000D01*
X487250Y231917D01*
X486958Y231708D01*
X486875Y231458D01*
X486917Y231208D01*
X487083Y231000D01*
X487917Y230583D01*
X488292Y230292D01*
X488542Y229875D01*
X488625Y229500D01*
X486875D01*
G01X501625Y225333D02*
X501292Y225125D01*
X500917Y225000D01*
X500583D01*
X500250Y225125D01*
X500000Y225333D01*
X499875Y225625D01*
X499958Y225917D01*
X500167Y226167D01*
X500542Y226333D01*
X501042Y226417D01*
X501333Y226583D01*
X501458Y226875D01*
X501375Y227167D01*
X501167Y227375D01*
X500875Y227500D01*
X500583D01*
X500292Y227417D01*
X500042Y227208D01*
G01X497650Y227500D02*
Y225000D01*
G01X498608Y227500D02*
X496692D01*
G01X495383Y225000D02*
Y227500D01*
X494383D01*
X494050Y227375D01*
X493800Y227083D01*
X493717Y226750D01*
X493800Y226417D01*
X494008Y226167D01*
X494383Y226042D01*
X495383D01*
G01X491450Y225000D02*
Y227500D01*
X491950Y227000D01*
G01Y225000D02*
X490950D01*
G01X489267Y225375D02*
X489017Y225167D01*
X488725Y225042D01*
X488350Y225000D01*
X487975Y225083D01*
X487683Y225250D01*
X487475Y225542D01*
X487433Y225875D01*
X487517Y226208D01*
X487725Y226417D01*
X488017Y226583D01*
X488308Y226625D01*
X488600Y226583D01*
X488975Y226417D01*
X488850Y227500D01*
X487725D01*
G01X485250Y225000D02*
X484958Y225042D01*
X484625Y225167D01*
X484417Y225375D01*
X484333Y225667D01*
X484417Y225958D01*
X484667Y226208D01*
X485042Y226333D01*
X485458D01*
X485708Y226417D01*
X485917Y226625D01*
X486000Y226917D01*
X485875Y227208D01*
X485583Y227417D01*
X485250Y227500D01*
X484917Y227417D01*
X484625Y227208D01*
X484500Y226917D01*
X484583Y226625D01*
X484792Y226417D01*
X485042Y226333D01*
X485458D01*
X485833Y226208D01*
X486083Y225958D01*
X486167Y225667D01*
X486083Y225375D01*
X485875Y225167D01*
X485542Y225042D01*
X485250Y225000D01*
G01X498625Y279333D02*
X498292Y279125D01*
X497917Y279000D01*
X497583D01*
X497250Y279125D01*
X497000Y279333D01*
X496875Y279625D01*
X496958Y279917D01*
X497167Y280167D01*
X497542Y280333D01*
X498042Y280417D01*
X498333Y280583D01*
X498458Y280875D01*
X498375Y281167D01*
X498167Y281375D01*
X497875Y281500D01*
X497583D01*
X497292Y281417D01*
X497042Y281208D01*
G01X494650Y281500D02*
Y279000D01*
G01X495608Y281500D02*
X493692D01*
G01X492383Y279000D02*
Y281500D01*
X491383D01*
X491050Y281375D01*
X490800Y281083D01*
X490717Y280750D01*
X490800Y280417D01*
X491008Y280167D01*
X491383Y280042D01*
X492383D01*
G01X488450Y279000D02*
Y281500D01*
X488950Y281000D01*
G01Y279000D02*
X487950D01*
G01X485350D02*
Y281500D01*
X485850Y281000D01*
G01Y279000D02*
X484850D01*
G01X482250D02*
Y281500D01*
X482750Y281000D01*
G01Y279000D02*
X481750D01*
G01X498662Y302350D02*
X498329Y302142D01*
X497954Y302017D01*
X497620D01*
X497287Y302142D01*
X497037Y302350D01*
X496912Y302642D01*
X496995Y302934D01*
X497204Y303184D01*
X497579Y303350D01*
X498079Y303434D01*
X498370Y303600D01*
X498495Y303892D01*
X498412Y304184D01*
X498204Y304392D01*
X497912Y304517D01*
X497620D01*
X497329Y304434D01*
X497079Y304225D01*
G01X495520Y302017D02*
Y304517D01*
X494479D01*
X494145Y304392D01*
X493937Y304225D01*
X493854Y303892D01*
X493937Y303559D01*
X494187Y303350D01*
X494479Y303225D01*
X495520D01*
G01X494479D02*
X493854Y302017D01*
G01X491587D02*
X491295Y302059D01*
X490962Y302184D01*
X490754Y302392D01*
X490670Y302684D01*
X490754Y302975D01*
X491004Y303225D01*
X491379Y303350D01*
X491795D01*
X492045Y303434D01*
X492254Y303642D01*
X492337Y303934D01*
X492212Y304225D01*
X491920Y304434D01*
X491587Y304517D01*
X491254Y304434D01*
X490962Y304225D01*
X490837Y303934D01*
X490920Y303642D01*
X491129Y303434D01*
X491379Y303350D01*
X491795D01*
X492170Y303225D01*
X492420Y302975D01*
X492504Y302684D01*
X492420Y302392D01*
X492212Y302184D01*
X491879Y302059D01*
X491587Y302017D01*
G01X489279Y304100D02*
X489029Y304350D01*
X488737Y304475D01*
X488404Y304517D01*
X487987Y304434D01*
X487695Y304225D01*
X487612Y303975D01*
X487654Y303725D01*
X487820Y303517D01*
X488654Y303100D01*
X489029Y302809D01*
X489279Y302392D01*
X489362Y302017D01*
X487612D01*
G01X486095Y302309D02*
X485804Y302100D01*
X485470Y302017D01*
X485137Y302100D01*
X484845Y302350D01*
X484637Y302725D01*
X484554Y303100D01*
Y303559D01*
X484637Y303934D01*
X484845Y304267D01*
X485095Y304434D01*
X485387Y304517D01*
X485720Y304434D01*
X485970Y304267D01*
X486137Y304017D01*
X486220Y303684D01*
X486137Y303392D01*
X485929Y303100D01*
X485679Y302934D01*
X485387Y302892D01*
X485054Y302975D01*
X484804Y303184D01*
X484554Y303559D01*
G01X498625Y288833D02*
X498292Y288625D01*
X497917Y288500D01*
X497583D01*
X497250Y288625D01*
X497000Y288833D01*
X496875Y289125D01*
X496958Y289417D01*
X497167Y289667D01*
X497542Y289833D01*
X498042Y289917D01*
X498333Y290083D01*
X498458Y290375D01*
X498375Y290667D01*
X498167Y290875D01*
X497875Y291000D01*
X497583D01*
X497292Y290917D01*
X497042Y290708D01*
G01X493733Y290792D02*
X493983Y290917D01*
X494275Y291000D01*
X494608D01*
X494983Y290875D01*
X495275Y290667D01*
X495483Y290417D01*
X495650Y290000D01*
X495692Y289625D01*
X495608Y289250D01*
X495483Y289000D01*
X495233Y288750D01*
X494942Y288583D01*
X494650Y288500D01*
X494358D01*
X494067Y288583D01*
X493817Y288708D01*
X493608Y288875D01*
G01X491550Y288500D02*
Y291000D01*
X492050Y290500D01*
G01Y288500D02*
X491050D01*
G01X489242Y290583D02*
X488992Y290833D01*
X488700Y290958D01*
X488367Y291000D01*
X487950Y290917D01*
X487658Y290708D01*
X487575Y290458D01*
X487617Y290208D01*
X487783Y290000D01*
X488617Y289583D01*
X488992Y289292D01*
X489242Y288875D01*
X489325Y288500D01*
X487575D01*
G01X486142Y290583D02*
X485892Y290833D01*
X485600Y290958D01*
X485267Y291000D01*
X484850Y290917D01*
X484558Y290708D01*
X484475Y290458D01*
X484517Y290208D01*
X484683Y290000D01*
X485517Y289583D01*
X485892Y289292D01*
X486142Y288875D01*
X486225Y288500D01*
X484475D01*
G01X483167Y289000D02*
X482917Y288708D01*
X482583Y288542D01*
X482208Y288500D01*
X481875Y288542D01*
X481542Y288750D01*
X481333Y289000D01*
X481292Y289250D01*
X481375Y289542D01*
X481667Y289750D01*
X481958Y289833D01*
X482333D01*
G01X481958D02*
X481708Y289958D01*
X481500Y290167D01*
X481417Y290417D01*
X481500Y290667D01*
X481708Y290875D01*
X482083Y291000D01*
X482458Y290958D01*
X482833Y290792D01*
G01X499180Y297833D02*
X498847Y297625D01*
X498472Y297500D01*
X498138D01*
X497805Y297625D01*
X497555Y297833D01*
X497430Y298125D01*
X497513Y298417D01*
X497722Y298667D01*
X498097Y298833D01*
X498597Y298917D01*
X498888Y299083D01*
X499013Y299375D01*
X498930Y299667D01*
X498722Y299875D01*
X498430Y300000D01*
X498138D01*
X497847Y299917D01*
X497597Y299708D01*
G01X494288Y299792D02*
X494538Y299917D01*
X494830Y300000D01*
X495163D01*
X495538Y299875D01*
X495830Y299667D01*
X496038Y299417D01*
X496205Y299000D01*
X496247Y298625D01*
X496163Y298250D01*
X496038Y298000D01*
X495788Y297750D01*
X495497Y297583D01*
X495205Y297500D01*
X494913D01*
X494622Y297583D01*
X494372Y297708D01*
X494163Y297875D01*
G01X492105Y297500D02*
Y300000D01*
X492605Y299500D01*
G01Y297500D02*
X491605D01*
G01X489005D02*
Y300000D01*
X489505Y299500D01*
G01Y297500D02*
X488505D01*
G01X486822Y297875D02*
X486572Y297667D01*
X486280Y297542D01*
X485905Y297500D01*
X485530Y297583D01*
X485238Y297750D01*
X485030Y298042D01*
X484988Y298375D01*
X485072Y298708D01*
X485280Y298917D01*
X485572Y299083D01*
X485863Y299125D01*
X486155Y299083D01*
X486530Y298917D01*
X486405Y300000D01*
X485280D01*
G01X482805D02*
X483138Y299917D01*
X483388Y299708D01*
X483555Y299458D01*
X483680Y299125D01*
X483722Y298750D01*
X483680Y298375D01*
X483555Y298042D01*
X483388Y297792D01*
X483138Y297583D01*
X482805Y297500D01*
X482472Y297583D01*
X482222Y297792D01*
X482055Y298042D01*
X481930Y298375D01*
X481888Y298750D01*
X481930Y299125D01*
X482055Y299458D01*
X482222Y299708D01*
X482472Y299917D01*
X482805Y300000D01*
G01X507180Y314333D02*
X506847Y314125D01*
X506472Y314000D01*
X506138D01*
X505805Y314125D01*
X505555Y314333D01*
X505430Y314625D01*
X505513Y314917D01*
X505722Y315167D01*
X506097Y315333D01*
X506597Y315417D01*
X506888Y315583D01*
X507013Y315875D01*
X506930Y316167D01*
X506722Y316375D01*
X506430Y316500D01*
X506138D01*
X505847Y316417D01*
X505597Y316208D01*
G01X502288Y316292D02*
X502538Y316417D01*
X502830Y316500D01*
X503163D01*
X503538Y316375D01*
X503830Y316167D01*
X504038Y315917D01*
X504205Y315500D01*
X504247Y315125D01*
X504163Y314750D01*
X504038Y314500D01*
X503788Y314250D01*
X503497Y314083D01*
X503205Y314000D01*
X502913D01*
X502622Y314083D01*
X502372Y314208D01*
X502163Y314375D01*
G01X500105Y314000D02*
Y316500D01*
X500605Y316000D01*
G01Y314000D02*
X499605D01*
G01X497005D02*
Y316500D01*
X497505Y316000D01*
G01Y314000D02*
X496505D01*
G01X494822Y314375D02*
X494572Y314167D01*
X494280Y314042D01*
X493905Y314000D01*
X493530Y314083D01*
X493238Y314250D01*
X493030Y314542D01*
X492988Y314875D01*
X493072Y315208D01*
X493280Y315417D01*
X493572Y315583D01*
X493863Y315625D01*
X494155Y315583D01*
X494530Y315417D01*
X494405Y316500D01*
X493280D01*
G01X491597Y316083D02*
X491347Y316333D01*
X491055Y316458D01*
X490722Y316500D01*
X490305Y316417D01*
X490013Y316208D01*
X489930Y315958D01*
X489972Y315708D01*
X490138Y315500D01*
X490972Y315083D01*
X491347Y314792D01*
X491597Y314375D01*
X491680Y314000D01*
X489930D01*
G01X498580Y306833D02*
X498247Y306625D01*
X497872Y306500D01*
X497538D01*
X497205Y306625D01*
X496955Y306833D01*
X496830Y307125D01*
X496913Y307417D01*
X497122Y307667D01*
X497497Y307833D01*
X497997Y307917D01*
X498288Y308083D01*
X498413Y308375D01*
X498330Y308667D01*
X498122Y308875D01*
X497830Y309000D01*
X497538D01*
X497247Y308917D01*
X496997Y308708D01*
G01X495438Y309000D02*
Y306500D01*
X493772D01*
G01X491505D02*
Y309000D01*
X492005Y308500D01*
G01Y306500D02*
X491005D01*
G01X489322Y307000D02*
X489072Y306708D01*
X488738Y306542D01*
X488363Y306500D01*
X488030Y306542D01*
X487697Y306750D01*
X487488Y307000D01*
X487447Y307250D01*
X487530Y307542D01*
X487822Y307750D01*
X488113Y307833D01*
X488488D01*
G01X488113D02*
X487863Y307958D01*
X487655Y308167D01*
X487572Y308417D01*
X487655Y308667D01*
X487863Y308875D01*
X488238Y309000D01*
X488613Y308958D01*
X488988Y308792D01*
G01X507180Y318833D02*
X506847Y318625D01*
X506472Y318500D01*
X506138D01*
X505805Y318625D01*
X505555Y318833D01*
X505430Y319125D01*
X505513Y319417D01*
X505722Y319667D01*
X506097Y319833D01*
X506597Y319917D01*
X506888Y320083D01*
X507013Y320375D01*
X506930Y320667D01*
X506722Y320875D01*
X506430Y321000D01*
X506138D01*
X505847Y320917D01*
X505597Y320708D01*
G01X502288Y320792D02*
X502538Y320917D01*
X502830Y321000D01*
X503163D01*
X503538Y320875D01*
X503830Y320667D01*
X504038Y320417D01*
X504205Y320000D01*
X504247Y319625D01*
X504163Y319250D01*
X504038Y319000D01*
X503788Y318750D01*
X503497Y318583D01*
X503205Y318500D01*
X502913D01*
X502622Y318583D01*
X502372Y318708D01*
X502163Y318875D01*
G01X500105Y318500D02*
Y321000D01*
X500605Y320500D01*
G01Y318500D02*
X499605D01*
G01X497005D02*
Y321000D01*
X497505Y320500D01*
G01Y318500D02*
X496505D01*
G01X494822Y318875D02*
X494572Y318667D01*
X494280Y318542D01*
X493905Y318500D01*
X493530Y318583D01*
X493238Y318750D01*
X493030Y319042D01*
X492988Y319375D01*
X493072Y319708D01*
X493280Y319917D01*
X493572Y320083D01*
X493863Y320125D01*
X494155Y320083D01*
X494530Y319917D01*
X494405Y321000D01*
X493280D01*
G01X491722Y319000D02*
X491472Y318708D01*
X491138Y318542D01*
X490763Y318500D01*
X490430Y318542D01*
X490097Y318750D01*
X489888Y319000D01*
X489847Y319250D01*
X489930Y319542D01*
X490222Y319750D01*
X490513Y319833D01*
X490888D01*
G01X490513D02*
X490263Y319958D01*
X490055Y320167D01*
X489972Y320417D01*
X490055Y320667D01*
X490263Y320875D01*
X490638Y321000D01*
X491013Y320958D01*
X491388Y320792D01*
G01X507180Y329333D02*
X506847Y329125D01*
X506472Y329000D01*
X506138D01*
X505805Y329125D01*
X505555Y329333D01*
X505430Y329625D01*
X505513Y329917D01*
X505722Y330167D01*
X506097Y330333D01*
X506597Y330417D01*
X506888Y330583D01*
X507013Y330875D01*
X506930Y331167D01*
X506722Y331375D01*
X506430Y331500D01*
X506138D01*
X505847Y331417D01*
X505597Y331208D01*
G01X502288Y331292D02*
X502538Y331417D01*
X502830Y331500D01*
X503163D01*
X503538Y331375D01*
X503830Y331167D01*
X504038Y330917D01*
X504205Y330500D01*
X504247Y330125D01*
X504163Y329750D01*
X504038Y329500D01*
X503788Y329250D01*
X503497Y329083D01*
X503205Y329000D01*
X502913D01*
X502622Y329083D01*
X502372Y329208D01*
X502163Y329375D01*
G01X500105Y329000D02*
Y331500D01*
X500605Y331000D01*
G01Y329000D02*
X499605D01*
G01X497005D02*
Y331500D01*
X497505Y331000D01*
G01Y329000D02*
X496505D01*
G01X494613Y329292D02*
X494322Y329083D01*
X493988Y329000D01*
X493655Y329083D01*
X493363Y329333D01*
X493155Y329708D01*
X493072Y330083D01*
Y330542D01*
X493155Y330917D01*
X493363Y331250D01*
X493613Y331417D01*
X493905Y331500D01*
X494238Y331417D01*
X494488Y331250D01*
X494655Y331000D01*
X494738Y330667D01*
X494655Y330375D01*
X494447Y330083D01*
X494197Y329917D01*
X493905Y329875D01*
X493572Y329958D01*
X493322Y330167D01*
X493072Y330542D01*
G01X491722Y329500D02*
X491472Y329208D01*
X491138Y329042D01*
X490763Y329000D01*
X490430Y329042D01*
X490097Y329250D01*
X489888Y329500D01*
X489847Y329750D01*
X489930Y330042D01*
X490222Y330250D01*
X490513Y330333D01*
X490888D01*
G01X490513D02*
X490263Y330458D01*
X490055Y330667D01*
X489972Y330917D01*
X490055Y331167D01*
X490263Y331375D01*
X490638Y331500D01*
X491013Y331458D01*
X491388Y331292D01*
G01X505130Y323833D02*
X504797Y323625D01*
X504422Y323500D01*
X504088D01*
X503755Y323625D01*
X503505Y323833D01*
X503380Y324125D01*
X503463Y324417D01*
X503672Y324667D01*
X504047Y324833D01*
X504547Y324917D01*
X504838Y325083D01*
X504963Y325375D01*
X504880Y325667D01*
X504672Y325875D01*
X504380Y326000D01*
X504088D01*
X503797Y325917D01*
X503547Y325708D01*
G01X501988Y323500D02*
Y326000D01*
X500947D01*
X500613Y325875D01*
X500405Y325708D01*
X500322Y325375D01*
X500405Y325042D01*
X500655Y324833D01*
X500947Y324708D01*
X501988D01*
G01X500947D02*
X500322Y323500D01*
G01X498055D02*
X497763Y323542D01*
X497430Y323667D01*
X497222Y323875D01*
X497138Y324167D01*
X497222Y324458D01*
X497472Y324708D01*
X497847Y324833D01*
X498263D01*
X498513Y324917D01*
X498722Y325125D01*
X498805Y325417D01*
X498680Y325708D01*
X498388Y325917D01*
X498055Y326000D01*
X497722Y325917D01*
X497430Y325708D01*
X497305Y325417D01*
X497388Y325125D01*
X497597Y324917D01*
X497847Y324833D01*
X498263D01*
X498638Y324708D01*
X498888Y324458D01*
X498972Y324167D01*
X498888Y323875D01*
X498680Y323667D01*
X498347Y323542D01*
X498055Y323500D01*
G01X494955Y326000D02*
X495288Y325917D01*
X495538Y325708D01*
X495705Y325458D01*
X495830Y325125D01*
X495872Y324750D01*
X495830Y324375D01*
X495705Y324042D01*
X495538Y323792D01*
X495288Y323583D01*
X494955Y323500D01*
X494622Y323583D01*
X494372Y323792D01*
X494205Y324042D01*
X494080Y324375D01*
X494038Y324750D01*
X494080Y325125D01*
X494205Y325458D01*
X494372Y325708D01*
X494622Y325917D01*
X494955Y326000D01*
G01X492647Y325583D02*
X492397Y325833D01*
X492105Y325958D01*
X491772Y326000D01*
X491355Y325917D01*
X491063Y325708D01*
X490980Y325458D01*
X491022Y325208D01*
X491188Y325000D01*
X492022Y324583D01*
X492397Y324292D01*
X492647Y323875D01*
X492730Y323500D01*
X490980D01*
G01X486388Y351875D02*
X486180Y352208D01*
X486055Y352583D01*
Y352917D01*
X486180Y353250D01*
X486388Y353500D01*
X486680Y353625D01*
X486972Y353542D01*
X487222Y353333D01*
X487388Y352958D01*
X487472Y352458D01*
X487638Y352167D01*
X487930Y352042D01*
X488222Y352125D01*
X488430Y352333D01*
X488555Y352625D01*
Y352917D01*
X488472Y353208D01*
X488263Y353458D01*
G01X488347Y356767D02*
X488472Y356517D01*
X488555Y356225D01*
Y355892D01*
X488430Y355517D01*
X488222Y355225D01*
X487972Y355017D01*
X487555Y354850D01*
X487180Y354808D01*
X486805Y354892D01*
X486555Y355017D01*
X486305Y355267D01*
X486138Y355558D01*
X486055Y355850D01*
Y356142D01*
X486138Y356433D01*
X486263Y356683D01*
X486430Y356892D01*
G01X486055Y358950D02*
X488555D01*
X488055Y358450D01*
G01X486055D02*
Y359450D01*
G01Y362050D02*
X488555D01*
X488055Y361550D01*
G01X486055D02*
Y362550D01*
G01X486347Y364442D02*
X486138Y364733D01*
X486055Y365067D01*
X486138Y365400D01*
X486388Y365692D01*
X486763Y365900D01*
X487138Y365983D01*
X487597D01*
X487972Y365900D01*
X488305Y365692D01*
X488472Y365442D01*
X488555Y365150D01*
X488472Y364817D01*
X488305Y364567D01*
X488055Y364400D01*
X487722Y364317D01*
X487430Y364400D01*
X487138Y364608D01*
X486972Y364858D01*
X486930Y365150D01*
X487013Y365483D01*
X487222Y365733D01*
X487597Y365983D01*
G01X488138Y367458D02*
X488388Y367708D01*
X488513Y368000D01*
X488555Y368333D01*
X488472Y368750D01*
X488263Y369042D01*
X488013Y369125D01*
X487763Y369083D01*
X487555Y368917D01*
X487138Y368083D01*
X486847Y367708D01*
X486430Y367458D01*
X486055Y367375D01*
Y369125D01*
G01X482188Y352175D02*
X481980Y352508D01*
X481855Y352883D01*
Y353217D01*
X481980Y353550D01*
X482188Y353800D01*
X482480Y353925D01*
X482772Y353842D01*
X483022Y353633D01*
X483188Y353258D01*
X483272Y352758D01*
X483438Y352467D01*
X483730Y352342D01*
X484022Y352425D01*
X484230Y352633D01*
X484355Y352925D01*
Y353217D01*
X484272Y353508D01*
X484063Y353758D01*
G01X484147Y357067D02*
X484272Y356817D01*
X484355Y356525D01*
Y356192D01*
X484230Y355817D01*
X484022Y355525D01*
X483772Y355317D01*
X483355Y355150D01*
X482980Y355108D01*
X482605Y355192D01*
X482355Y355317D01*
X482105Y355567D01*
X481938Y355858D01*
X481855Y356150D01*
Y356442D01*
X481938Y356733D01*
X482063Y356983D01*
X482230Y357192D01*
G01X481855Y359250D02*
X484355D01*
X483855Y358750D01*
G01X481855D02*
Y359750D01*
G01Y362350D02*
X484355D01*
X483855Y361850D01*
G01X481855D02*
Y362850D01*
G01Y365950D02*
X484355D01*
X482563Y364408D01*
Y366492D01*
G01X482230Y367633D02*
X482022Y367883D01*
X481897Y368175D01*
X481855Y368550D01*
X481938Y368925D01*
X482105Y369217D01*
X482397Y369425D01*
X482730Y369467D01*
X483063Y369383D01*
X483272Y369175D01*
X483438Y368883D01*
X483480Y368592D01*
X483438Y368300D01*
X483272Y367925D01*
X484355Y368050D01*
Y369175D01*
G01X491888Y385375D02*
X491680Y385708D01*
X491555Y386083D01*
Y386417D01*
X491680Y386750D01*
X491888Y387000D01*
X492180Y387125D01*
X492472Y387042D01*
X492722Y386833D01*
X492888Y386458D01*
X492972Y385958D01*
X493138Y385667D01*
X493430Y385542D01*
X493722Y385625D01*
X493930Y385833D01*
X494055Y386125D01*
Y386417D01*
X493972Y386708D01*
X493763Y386958D01*
G01X493847Y390267D02*
X493972Y390017D01*
X494055Y389725D01*
Y389392D01*
X493930Y389017D01*
X493722Y388725D01*
X493472Y388517D01*
X493055Y388350D01*
X492680Y388308D01*
X492305Y388392D01*
X492055Y388517D01*
X491805Y388767D01*
X491638Y389058D01*
X491555Y389350D01*
Y389642D01*
X491638Y389933D01*
X491763Y390183D01*
X491930Y390392D01*
G01X491555Y392450D02*
X494055D01*
X493555Y391950D01*
G01X491555D02*
Y392950D01*
G01Y395550D02*
X494055D01*
X493555Y395050D01*
G01X491555D02*
Y396050D01*
G01X491847Y397942D02*
X491638Y398233D01*
X491555Y398567D01*
X491638Y398900D01*
X491888Y399192D01*
X492263Y399400D01*
X492638Y399483D01*
X493097D01*
X493472Y399400D01*
X493805Y399192D01*
X493972Y398942D01*
X494055Y398650D01*
X493972Y398317D01*
X493805Y398067D01*
X493555Y397900D01*
X493222Y397817D01*
X492930Y397900D01*
X492638Y398108D01*
X492472Y398358D01*
X492430Y398650D01*
X492513Y398983D01*
X492722Y399233D01*
X493097Y399483D01*
G01X491555Y401750D02*
X494055D01*
X493555Y401250D01*
G01X491555D02*
Y402250D01*
G01X494888Y408875D02*
X494680Y409208D01*
X494555Y409583D01*
Y409917D01*
X494680Y410250D01*
X494888Y410500D01*
X495180Y410625D01*
X495472Y410542D01*
X495722Y410333D01*
X495888Y409958D01*
X495972Y409458D01*
X496138Y409167D01*
X496430Y409042D01*
X496722Y409125D01*
X496930Y409333D01*
X497055Y409625D01*
Y409917D01*
X496972Y410208D01*
X496763Y410458D01*
G01X496847Y413767D02*
X496972Y413517D01*
X497055Y413225D01*
Y412892D01*
X496930Y412517D01*
X496722Y412225D01*
X496472Y412017D01*
X496055Y411850D01*
X495680Y411808D01*
X495305Y411892D01*
X495055Y412017D01*
X494805Y412267D01*
X494638Y412558D01*
X494555Y412850D01*
Y413142D01*
X494638Y413433D01*
X494763Y413683D01*
X494930Y413892D01*
G01X494555Y415950D02*
X497055D01*
X496555Y415450D01*
G01X494555D02*
Y416450D01*
G01Y419050D02*
X497055D01*
X496555Y418550D01*
G01X494555D02*
Y419550D01*
G01X495597Y421358D02*
X495888Y421650D01*
X496055Y421900D01*
X496138Y422233D01*
X496055Y422525D01*
X495888Y422733D01*
X495638Y422900D01*
X495347Y422942D01*
X495097Y422900D01*
X494847Y422733D01*
X494638Y422483D01*
X494555Y422192D01*
X494638Y421858D01*
X494888Y421567D01*
X495263Y421400D01*
X495680Y421358D01*
X496222Y421442D01*
X496513Y421567D01*
X496805Y421775D01*
X497013Y422067D01*
X497055Y422358D01*
X496972Y422650D01*
X496763Y422858D01*
G01X496638Y424458D02*
X496888Y424708D01*
X497013Y425000D01*
X497055Y425333D01*
X496972Y425750D01*
X496763Y426042D01*
X496513Y426125D01*
X496263Y426083D01*
X496055Y425917D01*
X495638Y425083D01*
X495347Y424708D01*
X494930Y424458D01*
X494555Y424375D01*
Y426125D01*
G01X485888Y434875D02*
X485680Y435208D01*
X485555Y435583D01*
Y435917D01*
X485680Y436250D01*
X485888Y436500D01*
X486180Y436625D01*
X486472Y436542D01*
X486722Y436333D01*
X486888Y435958D01*
X486972Y435458D01*
X487138Y435167D01*
X487430Y435042D01*
X487722Y435125D01*
X487930Y435333D01*
X488055Y435625D01*
Y435917D01*
X487972Y436208D01*
X487763Y436458D01*
G01X487847Y439767D02*
X487972Y439517D01*
X488055Y439225D01*
Y438892D01*
X487930Y438517D01*
X487722Y438225D01*
X487472Y438017D01*
X487055Y437850D01*
X486680Y437808D01*
X486305Y437892D01*
X486055Y438017D01*
X485805Y438267D01*
X485638Y438558D01*
X485555Y438850D01*
Y439142D01*
X485638Y439433D01*
X485763Y439683D01*
X485930Y439892D01*
G01X485555Y441950D02*
X488055D01*
X487555Y441450D01*
G01X485555D02*
Y442450D01*
G01Y445050D02*
X488055D01*
X487555Y444550D01*
G01X485555D02*
Y445550D01*
G01Y448067D02*
X486097Y448150D01*
X486555Y448275D01*
X486972Y448442D01*
X487430Y448650D01*
X488055Y448983D01*
Y447317D01*
G01X485555Y451250D02*
X485597Y451542D01*
X485722Y451875D01*
X485930Y452083D01*
X486222Y452167D01*
X486513Y452083D01*
X486763Y451833D01*
X486888Y451458D01*
Y451042D01*
X486972Y450792D01*
X487180Y450583D01*
X487472Y450500D01*
X487763Y450625D01*
X487972Y450917D01*
X488055Y451250D01*
X487972Y451583D01*
X487763Y451875D01*
X487472Y452000D01*
X487180Y451917D01*
X486972Y451708D01*
X486888Y451458D01*
Y451042D01*
X486763Y450667D01*
X486513Y450417D01*
X486222Y450333D01*
X485930Y450417D01*
X485722Y450625D01*
X485597Y450958D01*
X485555Y451250D01*
G01X479888Y434875D02*
X479680Y435208D01*
X479555Y435583D01*
Y435917D01*
X479680Y436250D01*
X479888Y436500D01*
X480180Y436625D01*
X480472Y436542D01*
X480722Y436333D01*
X480888Y435958D01*
X480972Y435458D01*
X481138Y435167D01*
X481430Y435042D01*
X481722Y435125D01*
X481930Y435333D01*
X482055Y435625D01*
Y435917D01*
X481972Y436208D01*
X481763Y436458D01*
G01X481847Y439767D02*
X481972Y439517D01*
X482055Y439225D01*
Y438892D01*
X481930Y438517D01*
X481722Y438225D01*
X481472Y438017D01*
X481055Y437850D01*
X480680Y437808D01*
X480305Y437892D01*
X480055Y438017D01*
X479805Y438267D01*
X479638Y438558D01*
X479555Y438850D01*
Y439142D01*
X479638Y439433D01*
X479763Y439683D01*
X479930Y439892D01*
G01X479555Y441950D02*
X482055D01*
X481555Y441450D01*
G01X479555D02*
Y442450D01*
G01Y445050D02*
X482055D01*
X481555Y444550D01*
G01X479555D02*
Y445550D01*
G01Y448150D02*
X479597Y448442D01*
X479722Y448775D01*
X479930Y448983D01*
X480222Y449067D01*
X480513Y448983D01*
X480763Y448733D01*
X480888Y448358D01*
Y447942D01*
X480972Y447692D01*
X481180Y447483D01*
X481472Y447400D01*
X481763Y447525D01*
X481972Y447817D01*
X482055Y448150D01*
X481972Y448483D01*
X481763Y448775D01*
X481472Y448900D01*
X481180Y448817D01*
X480972Y448608D01*
X480888Y448358D01*
Y447942D01*
X480763Y447567D01*
X480513Y447317D01*
X480222Y447233D01*
X479930Y447317D01*
X479722Y447525D01*
X479597Y447858D01*
X479555Y448150D01*
G01X482055Y451250D02*
X481972Y450917D01*
X481763Y450667D01*
X481513Y450500D01*
X481180Y450375D01*
X480805Y450333D01*
X480430Y450375D01*
X480097Y450500D01*
X479847Y450667D01*
X479638Y450917D01*
X479555Y451250D01*
X479638Y451583D01*
X479847Y451833D01*
X480097Y452000D01*
X480430Y452125D01*
X480805Y452167D01*
X481180Y452125D01*
X481513Y452000D01*
X481763Y451833D01*
X481972Y451583D01*
X482055Y451250D01*
G01X479856Y455658D02*
X479648Y455991D01*
X479523Y456366D01*
Y456700D01*
X479648Y457033D01*
X479856Y457283D01*
X480148Y457408D01*
X480440Y457325D01*
X480690Y457116D01*
X480856Y456741D01*
X480940Y456241D01*
X481106Y455950D01*
X481398Y455825D01*
X481690Y455908D01*
X481898Y456116D01*
X482023Y456408D01*
Y456700D01*
X481940Y456991D01*
X481731Y457241D01*
G01X481815Y460550D02*
X481940Y460300D01*
X482023Y460008D01*
Y459675D01*
X481898Y459300D01*
X481690Y459008D01*
X481440Y458800D01*
X481023Y458633D01*
X480648Y458591D01*
X480273Y458675D01*
X480023Y458800D01*
X479773Y459050D01*
X479606Y459341D01*
X479523Y459633D01*
Y459925D01*
X479606Y460216D01*
X479731Y460466D01*
X479898Y460675D01*
G01X479523Y462733D02*
X482023D01*
X481523Y462233D01*
G01X479523D02*
Y463233D01*
G01Y465833D02*
X482023D01*
X481523Y465333D01*
G01X479523D02*
Y466333D01*
G01Y468850D02*
X480065Y468933D01*
X480523Y469058D01*
X480940Y469225D01*
X481398Y469433D01*
X482023Y469766D01*
Y468100D01*
G01X479523Y471950D02*
X480065Y472033D01*
X480523Y472158D01*
X480940Y472325D01*
X481398Y472533D01*
X482023Y472866D01*
Y471200D01*
G01X485888Y455875D02*
X485680Y456208D01*
X485555Y456583D01*
Y456917D01*
X485680Y457250D01*
X485888Y457500D01*
X486180Y457625D01*
X486472Y457542D01*
X486722Y457333D01*
X486888Y456958D01*
X486972Y456458D01*
X487138Y456167D01*
X487430Y456042D01*
X487722Y456125D01*
X487930Y456333D01*
X488055Y456625D01*
Y456917D01*
X487972Y457208D01*
X487763Y457458D01*
G01X487847Y460767D02*
X487972Y460517D01*
X488055Y460225D01*
Y459892D01*
X487930Y459517D01*
X487722Y459225D01*
X487472Y459017D01*
X487055Y458850D01*
X486680Y458808D01*
X486305Y458892D01*
X486055Y459017D01*
X485805Y459267D01*
X485638Y459558D01*
X485555Y459850D01*
Y460142D01*
X485638Y460433D01*
X485763Y460683D01*
X485930Y460892D01*
G01X485555Y462950D02*
X488055D01*
X487555Y462450D01*
G01X485555D02*
Y463450D01*
G01Y466050D02*
X488055D01*
X487555Y465550D01*
G01X485555D02*
Y466550D01*
G01Y469067D02*
X486097Y469150D01*
X486555Y469275D01*
X486972Y469442D01*
X487430Y469650D01*
X488055Y469983D01*
Y468317D01*
G01X486055Y471333D02*
X485763Y471583D01*
X485597Y471917D01*
X485555Y472292D01*
X485597Y472625D01*
X485805Y472958D01*
X486055Y473167D01*
X486305Y473208D01*
X486597Y473125D01*
X486805Y472833D01*
X486888Y472542D01*
Y472167D01*
G01Y472542D02*
X487013Y472792D01*
X487222Y473000D01*
X487472Y473083D01*
X487722Y473000D01*
X487930Y472792D01*
X488055Y472417D01*
X488013Y472042D01*
X487847Y471667D01*
G01X486078Y842000D02*
Y846000D01*
X493478D01*
G01X486078Y834000D02*
Y838000D01*
X493478D01*
G01X486078D02*
Y842000D01*
X493478D01*
G01Y859000D02*
Y855000D01*
X486078D01*
G01X493478Y854500D02*
Y850500D01*
X486078D01*
G01Y846500D02*
Y850500D01*
X493478D01*
G01Y863500D02*
Y859500D01*
X486078D01*
G01X496978Y872000D02*
X489178D01*
G01X483578D02*
Y879000D01*
G01X489978Y872000D02*
X483578D01*
G01X496978Y879000D02*
X491778D01*
G01X483578D02*
X492278D01*
G01X515904Y112833D02*
X515571Y112625D01*
X515196Y112500D01*
X514862D01*
X514529Y112625D01*
X514279Y112833D01*
X514154Y113125D01*
X514237Y113417D01*
X514446Y113667D01*
X514821Y113833D01*
X515321Y113917D01*
X515612Y114083D01*
X515737Y114375D01*
X515654Y114667D01*
X515446Y114875D01*
X515154Y115000D01*
X514862D01*
X514571Y114917D01*
X514321Y114708D01*
G01X511929Y112500D02*
X512262Y112542D01*
X512554Y112708D01*
X512804Y112958D01*
X512971Y113250D01*
X513054Y113583D01*
Y113917D01*
X512971Y114250D01*
X512804Y114542D01*
X512554Y114792D01*
X512262Y114958D01*
X511929Y115000D01*
X511596Y114958D01*
X511304Y114792D01*
X511054Y114542D01*
X510887Y114250D01*
X510804Y113917D01*
Y113583D01*
X510887Y113250D01*
X511054Y112958D01*
X511304Y112708D01*
X511596Y112542D01*
X511929Y112500D01*
G01X511596Y113167D02*
X511096Y112500D01*
G01X509746Y113000D02*
X509496Y112708D01*
X509162Y112542D01*
X508787Y112500D01*
X508454Y112542D01*
X508121Y112750D01*
X507912Y113000D01*
X507871Y113250D01*
X507954Y113542D01*
X508246Y113750D01*
X508537Y113833D01*
X508912D01*
G01X508537D02*
X508287Y113958D01*
X508079Y114167D01*
X507996Y114417D01*
X508079Y114667D01*
X508287Y114875D01*
X508662Y115000D01*
X509037Y114958D01*
X509412Y114792D01*
G01X506929Y119000D02*
Y132000D01*
G01X520929Y119000D02*
X506929D01*
G01X497262Y108925D02*
X497054Y109258D01*
X496929Y109633D01*
Y109967D01*
X497054Y110300D01*
X497262Y110550D01*
X497554Y110675D01*
X497846Y110592D01*
X498096Y110383D01*
X498262Y110008D01*
X498346Y109508D01*
X498512Y109217D01*
X498804Y109092D01*
X499096Y109175D01*
X499304Y109383D01*
X499429Y109675D01*
Y109967D01*
X499346Y110258D01*
X499137Y110508D01*
G01X499221Y113817D02*
X499346Y113567D01*
X499429Y113275D01*
Y112942D01*
X499304Y112567D01*
X499096Y112275D01*
X498846Y112067D01*
X498429Y111900D01*
X498054Y111858D01*
X497679Y111942D01*
X497429Y112067D01*
X497179Y112317D01*
X497012Y112608D01*
X496929Y112900D01*
Y113192D01*
X497012Y113483D01*
X497137Y113733D01*
X497304Y113942D01*
G01X497221Y115292D02*
X497012Y115583D01*
X496929Y115917D01*
X497012Y116250D01*
X497262Y116542D01*
X497637Y116750D01*
X498012Y116833D01*
X498471D01*
X498846Y116750D01*
X499179Y116542D01*
X499346Y116292D01*
X499429Y116000D01*
X499346Y115667D01*
X499179Y115417D01*
X498929Y115250D01*
X498596Y115167D01*
X498304Y115250D01*
X498012Y115458D01*
X497846Y115708D01*
X497804Y116000D01*
X497887Y116333D01*
X498096Y116583D01*
X498471Y116833D01*
G01X497429Y118183D02*
X497137Y118433D01*
X496971Y118767D01*
X496929Y119142D01*
X496971Y119475D01*
X497179Y119808D01*
X497429Y120017D01*
X497679Y120058D01*
X497971Y119975D01*
X498179Y119683D01*
X498262Y119392D01*
Y119017D01*
G01Y119392D02*
X498387Y119642D01*
X498596Y119850D01*
X498846Y119933D01*
X499096Y119850D01*
X499304Y119642D01*
X499429Y119267D01*
X499387Y118892D01*
X499221Y118517D01*
G01X499012Y121408D02*
X499262Y121658D01*
X499387Y121950D01*
X499429Y122283D01*
X499346Y122700D01*
X499137Y122992D01*
X498887Y123075D01*
X498637Y123033D01*
X498429Y122867D01*
X498012Y122033D01*
X497721Y121658D01*
X497304Y121408D01*
X496929Y121325D01*
Y123075D01*
G01X503729Y144500D02*
Y137500D01*
X517129D01*
Y144500D01*
X503729D01*
G01X513629Y137000D02*
Y133000D01*
X506229D01*
G01X506929Y132000D02*
X520929D01*
G01X506975Y149833D02*
X506642Y149625D01*
X506267Y149500D01*
X505933D01*
X505600Y149625D01*
X505350Y149833D01*
X505225Y150125D01*
X505308Y150417D01*
X505517Y150667D01*
X505892Y150833D01*
X506392Y150917D01*
X506683Y151083D01*
X506808Y151375D01*
X506725Y151667D01*
X506517Y151875D01*
X506225Y152000D01*
X505933D01*
X505642Y151917D01*
X505392Y151708D01*
G01X503000Y149500D02*
X503333Y149542D01*
X503625Y149708D01*
X503875Y149958D01*
X504042Y150250D01*
X504125Y150583D01*
Y150917D01*
X504042Y151250D01*
X503875Y151542D01*
X503625Y151792D01*
X503333Y151958D01*
X503000Y152000D01*
X502667Y151958D01*
X502375Y151792D01*
X502125Y151542D01*
X501958Y151250D01*
X501875Y150917D01*
Y150583D01*
X501958Y150250D01*
X502125Y149958D01*
X502375Y149708D01*
X502667Y149542D01*
X503000Y149500D01*
G01X502667Y150167D02*
X502167Y149500D01*
G01X499900D02*
Y152000D01*
X500400Y151500D01*
G01Y149500D02*
X499400D01*
G01X520575Y154333D02*
X520242Y154125D01*
X519867Y154000D01*
X519533D01*
X519200Y154125D01*
X518950Y154333D01*
X518825Y154625D01*
X518908Y154917D01*
X519117Y155167D01*
X519492Y155333D01*
X519992Y155417D01*
X520283Y155583D01*
X520408Y155875D01*
X520325Y156167D01*
X520117Y156375D01*
X519825Y156500D01*
X519533D01*
X519242Y156417D01*
X518992Y156208D01*
G01X517433Y154000D02*
Y156500D01*
X516392D01*
X516058Y156375D01*
X515850Y156208D01*
X515767Y155875D01*
X515850Y155542D01*
X516100Y155333D01*
X516392Y155208D01*
X517433D01*
G01X516392D02*
X515767Y154000D01*
G01X513583D02*
X513500Y154542D01*
X513375Y155000D01*
X513208Y155417D01*
X513000Y155875D01*
X512667Y156500D01*
X514333D01*
G01X510400Y154000D02*
Y156500D01*
X510900Y156000D01*
G01Y154000D02*
X509900D01*
G01X508217Y154500D02*
X507967Y154208D01*
X507633Y154042D01*
X507258Y154000D01*
X506925Y154042D01*
X506592Y154250D01*
X506383Y154500D01*
X506342Y154750D01*
X506425Y155042D01*
X506717Y155250D01*
X507008Y155333D01*
X507383D01*
G01X507008D02*
X506758Y155458D01*
X506550Y155667D01*
X506467Y155917D01*
X506550Y156167D01*
X506758Y156375D01*
X507133Y156500D01*
X507508Y156458D01*
X507883Y156292D01*
G01X516629Y153000D02*
Y149000D01*
X509229D01*
G01X520575Y162833D02*
X520242Y162625D01*
X519867Y162500D01*
X519533D01*
X519200Y162625D01*
X518950Y162833D01*
X518825Y163125D01*
X518908Y163417D01*
X519117Y163667D01*
X519492Y163833D01*
X519992Y163917D01*
X520283Y164083D01*
X520408Y164375D01*
X520325Y164667D01*
X520117Y164875D01*
X519825Y165000D01*
X519533D01*
X519242Y164917D01*
X518992Y164708D01*
G01X517433Y162500D02*
Y165000D01*
X516392D01*
X516058Y164875D01*
X515850Y164708D01*
X515767Y164375D01*
X515850Y164042D01*
X516100Y163833D01*
X516392Y163708D01*
X517433D01*
G01X516392D02*
X515767Y162500D01*
G01X514292Y163542D02*
X514000Y163833D01*
X513750Y164000D01*
X513417Y164083D01*
X513125Y164000D01*
X512917Y163833D01*
X512750Y163583D01*
X512708Y163292D01*
X512750Y163042D01*
X512917Y162792D01*
X513167Y162583D01*
X513458Y162500D01*
X513792Y162583D01*
X514083Y162833D01*
X514250Y163208D01*
X514292Y163625D01*
X514208Y164167D01*
X514083Y164458D01*
X513875Y164750D01*
X513583Y164958D01*
X513292Y165000D01*
X513000Y164917D01*
X512792Y164708D01*
G01X511317Y162875D02*
X511067Y162667D01*
X510775Y162542D01*
X510400Y162500D01*
X510025Y162583D01*
X509733Y162750D01*
X509525Y163042D01*
X509483Y163375D01*
X509567Y163708D01*
X509775Y163917D01*
X510067Y164083D01*
X510358Y164125D01*
X510650Y164083D01*
X511025Y163917D01*
X510900Y165000D01*
X509775D01*
G01X507300Y162500D02*
Y165000D01*
X507800Y164500D01*
G01Y162500D02*
X506800D01*
G01X503500Y202500D02*
X520500D01*
Y173000D01*
X501500D01*
Y202500D01*
X503500D01*
G01X518075Y175333D02*
X517742Y175125D01*
X517367Y175000D01*
X517033D01*
X516700Y175125D01*
X516450Y175333D01*
X516325Y175625D01*
X516408Y175917D01*
X516617Y176167D01*
X516992Y176333D01*
X517492Y176417D01*
X517783Y176583D01*
X517908Y176875D01*
X517825Y177167D01*
X517617Y177375D01*
X517325Y177500D01*
X517033D01*
X516742Y177417D01*
X516492Y177208D01*
G01X514933Y175000D02*
Y177500D01*
X513892D01*
X513558Y177375D01*
X513350Y177208D01*
X513267Y176875D01*
X513350Y176542D01*
X513600Y176333D01*
X513892Y176208D01*
X514933D01*
G01X513892D02*
X513267Y175000D01*
G01X511792Y176042D02*
X511500Y176333D01*
X511250Y176500D01*
X510917Y176583D01*
X510625Y176500D01*
X510417Y176333D01*
X510250Y176083D01*
X510208Y175792D01*
X510250Y175542D01*
X510417Y175292D01*
X510667Y175083D01*
X510958Y175000D01*
X511292Y175083D01*
X511583Y175333D01*
X511750Y175708D01*
X511792Y176125D01*
X511708Y176667D01*
X511583Y176958D01*
X511375Y177250D01*
X511083Y177458D01*
X510792Y177500D01*
X510500Y177417D01*
X510292Y177208D01*
G01X507900Y175000D02*
Y177500D01*
X508400Y177000D01*
G01Y175000D02*
X507400D01*
G01X505592Y176042D02*
X505300Y176333D01*
X505050Y176500D01*
X504717Y176583D01*
X504425Y176500D01*
X504217Y176333D01*
X504050Y176083D01*
X504008Y175792D01*
X504050Y175542D01*
X504217Y175292D01*
X504467Y175083D01*
X504758Y175000D01*
X505092Y175083D01*
X505383Y175333D01*
X505550Y175708D01*
X505592Y176125D01*
X505508Y176667D01*
X505383Y176958D01*
X505175Y177250D01*
X504883Y177458D01*
X504592Y177500D01*
X504300Y177417D01*
X504092Y177208D01*
G01X518075Y184333D02*
X517742Y184125D01*
X517367Y184000D01*
X517033D01*
X516700Y184125D01*
X516450Y184333D01*
X516325Y184625D01*
X516408Y184917D01*
X516617Y185167D01*
X516992Y185333D01*
X517492Y185417D01*
X517783Y185583D01*
X517908Y185875D01*
X517825Y186167D01*
X517617Y186375D01*
X517325Y186500D01*
X517033D01*
X516742Y186417D01*
X516492Y186208D01*
G01X514933Y184000D02*
Y186500D01*
X513892D01*
X513558Y186375D01*
X513350Y186208D01*
X513267Y185875D01*
X513350Y185542D01*
X513600Y185333D01*
X513892Y185208D01*
X514933D01*
G01X513892D02*
X513267Y184000D01*
G01X511792Y185042D02*
X511500Y185333D01*
X511250Y185500D01*
X510917Y185583D01*
X510625Y185500D01*
X510417Y185333D01*
X510250Y185083D01*
X510208Y184792D01*
X510250Y184542D01*
X510417Y184292D01*
X510667Y184083D01*
X510958Y184000D01*
X511292Y184083D01*
X511583Y184333D01*
X511750Y184708D01*
X511792Y185125D01*
X511708Y185667D01*
X511583Y185958D01*
X511375Y186250D01*
X511083Y186458D01*
X510792Y186500D01*
X510500Y186417D01*
X510292Y186208D01*
G01X508692Y186083D02*
X508442Y186333D01*
X508150Y186458D01*
X507817Y186500D01*
X507400Y186417D01*
X507108Y186208D01*
X507025Y185958D01*
X507067Y185708D01*
X507233Y185500D01*
X508067Y185083D01*
X508442Y184792D01*
X508692Y184375D01*
X508775Y184000D01*
X507025D01*
G01X504800Y186500D02*
X505133Y186417D01*
X505383Y186208D01*
X505550Y185958D01*
X505675Y185625D01*
X505717Y185250D01*
X505675Y184875D01*
X505550Y184542D01*
X505383Y184292D01*
X505133Y184083D01*
X504800Y184000D01*
X504467Y184083D01*
X504217Y184292D01*
X504050Y184542D01*
X503925Y184875D01*
X503883Y185250D01*
X503925Y185625D01*
X504050Y185958D01*
X504217Y186208D01*
X504467Y186417D01*
X504800Y186500D01*
G01X518075Y188833D02*
X517742Y188625D01*
X517367Y188500D01*
X517033D01*
X516700Y188625D01*
X516450Y188833D01*
X516325Y189125D01*
X516408Y189417D01*
X516617Y189667D01*
X516992Y189833D01*
X517492Y189917D01*
X517783Y190083D01*
X517908Y190375D01*
X517825Y190667D01*
X517617Y190875D01*
X517325Y191000D01*
X517033D01*
X516742Y190917D01*
X516492Y190708D01*
G01X514933Y188500D02*
Y191000D01*
X513892D01*
X513558Y190875D01*
X513350Y190708D01*
X513267Y190375D01*
X513350Y190042D01*
X513600Y189833D01*
X513892Y189708D01*
X514933D01*
G01X513892D02*
X513267Y188500D01*
G01X511792Y189542D02*
X511500Y189833D01*
X511250Y190000D01*
X510917Y190083D01*
X510625Y190000D01*
X510417Y189833D01*
X510250Y189583D01*
X510208Y189292D01*
X510250Y189042D01*
X510417Y188792D01*
X510667Y188583D01*
X510958Y188500D01*
X511292Y188583D01*
X511583Y188833D01*
X511750Y189208D01*
X511792Y189625D01*
X511708Y190167D01*
X511583Y190458D01*
X511375Y190750D01*
X511083Y190958D01*
X510792Y191000D01*
X510500Y190917D01*
X510292Y190708D01*
G01X508692Y190583D02*
X508442Y190833D01*
X508150Y190958D01*
X507817Y191000D01*
X507400Y190917D01*
X507108Y190708D01*
X507025Y190458D01*
X507067Y190208D01*
X507233Y190000D01*
X508067Y189583D01*
X508442Y189292D01*
X508692Y188875D01*
X508775Y188500D01*
X507025D01*
G01X504800D02*
Y191000D01*
X505300Y190500D01*
G01Y188500D02*
X504300D01*
G01X518075Y179833D02*
X517742Y179625D01*
X517367Y179500D01*
X517033D01*
X516700Y179625D01*
X516450Y179833D01*
X516325Y180125D01*
X516408Y180417D01*
X516617Y180667D01*
X516992Y180833D01*
X517492Y180917D01*
X517783Y181083D01*
X517908Y181375D01*
X517825Y181667D01*
X517617Y181875D01*
X517325Y182000D01*
X517033D01*
X516742Y181917D01*
X516492Y181708D01*
G01X514933Y179500D02*
Y182000D01*
X513892D01*
X513558Y181875D01*
X513350Y181708D01*
X513267Y181375D01*
X513350Y181042D01*
X513600Y180833D01*
X513892Y180708D01*
X514933D01*
G01X513892D02*
X513267Y179500D01*
G01X511792Y180542D02*
X511500Y180833D01*
X511250Y181000D01*
X510917Y181083D01*
X510625Y181000D01*
X510417Y180833D01*
X510250Y180583D01*
X510208Y180292D01*
X510250Y180042D01*
X510417Y179792D01*
X510667Y179583D01*
X510958Y179500D01*
X511292Y179583D01*
X511583Y179833D01*
X511750Y180208D01*
X511792Y180625D01*
X511708Y181167D01*
X511583Y181458D01*
X511375Y181750D01*
X511083Y181958D01*
X510792Y182000D01*
X510500Y181917D01*
X510292Y181708D01*
G01X508692Y181583D02*
X508442Y181833D01*
X508150Y181958D01*
X507817Y182000D01*
X507400Y181917D01*
X507108Y181708D01*
X507025Y181458D01*
X507067Y181208D01*
X507233Y181000D01*
X508067Y180583D01*
X508442Y180292D01*
X508692Y179875D01*
X508775Y179500D01*
X507025D01*
G01X504300D02*
Y182000D01*
X505842Y180208D01*
X503758D01*
G01X518075Y193333D02*
X517742Y193125D01*
X517367Y193000D01*
X517033D01*
X516700Y193125D01*
X516450Y193333D01*
X516325Y193625D01*
X516408Y193917D01*
X516617Y194167D01*
X516992Y194333D01*
X517492Y194417D01*
X517783Y194583D01*
X517908Y194875D01*
X517825Y195167D01*
X517617Y195375D01*
X517325Y195500D01*
X517033D01*
X516742Y195417D01*
X516492Y195208D01*
G01X514933Y193000D02*
Y195500D01*
X513892D01*
X513558Y195375D01*
X513350Y195208D01*
X513267Y194875D01*
X513350Y194542D01*
X513600Y194333D01*
X513892Y194208D01*
X514933D01*
G01X513892D02*
X513267Y193000D01*
G01X511792Y194042D02*
X511500Y194333D01*
X511250Y194500D01*
X510917Y194583D01*
X510625Y194500D01*
X510417Y194333D01*
X510250Y194083D01*
X510208Y193792D01*
X510250Y193542D01*
X510417Y193292D01*
X510667Y193083D01*
X510958Y193000D01*
X511292Y193083D01*
X511583Y193333D01*
X511750Y193708D01*
X511792Y194125D01*
X511708Y194667D01*
X511583Y194958D01*
X511375Y195250D01*
X511083Y195458D01*
X510792Y195500D01*
X510500Y195417D01*
X510292Y195208D01*
G01X507900Y193000D02*
Y195500D01*
X508400Y195000D01*
G01Y193000D02*
X507400D01*
G01X505508Y193292D02*
X505217Y193083D01*
X504883Y193000D01*
X504550Y193083D01*
X504258Y193333D01*
X504050Y193708D01*
X503967Y194083D01*
Y194542D01*
X504050Y194917D01*
X504258Y195250D01*
X504508Y195417D01*
X504800Y195500D01*
X505133Y195417D01*
X505383Y195250D01*
X505550Y195000D01*
X505633Y194667D01*
X505550Y194375D01*
X505342Y194083D01*
X505092Y193917D01*
X504800Y193875D01*
X504467Y193958D01*
X504217Y194167D01*
X503967Y194542D01*
G01X518075Y197833D02*
X517742Y197625D01*
X517367Y197500D01*
X517033D01*
X516700Y197625D01*
X516450Y197833D01*
X516325Y198125D01*
X516408Y198417D01*
X516617Y198667D01*
X516992Y198833D01*
X517492Y198917D01*
X517783Y199083D01*
X517908Y199375D01*
X517825Y199667D01*
X517617Y199875D01*
X517325Y200000D01*
X517033D01*
X516742Y199917D01*
X516492Y199708D01*
G01X514933Y197500D02*
Y200000D01*
X513892D01*
X513558Y199875D01*
X513350Y199708D01*
X513267Y199375D01*
X513350Y199042D01*
X513600Y198833D01*
X513892Y198708D01*
X514933D01*
G01X513892D02*
X513267Y197500D01*
G01X511792Y198542D02*
X511500Y198833D01*
X511250Y199000D01*
X510917Y199083D01*
X510625Y199000D01*
X510417Y198833D01*
X510250Y198583D01*
X510208Y198292D01*
X510250Y198042D01*
X510417Y197792D01*
X510667Y197583D01*
X510958Y197500D01*
X511292Y197583D01*
X511583Y197833D01*
X511750Y198208D01*
X511792Y198625D01*
X511708Y199167D01*
X511583Y199458D01*
X511375Y199750D01*
X511083Y199958D01*
X510792Y200000D01*
X510500Y199917D01*
X510292Y199708D01*
G01X508692Y199583D02*
X508442Y199833D01*
X508150Y199958D01*
X507817Y200000D01*
X507400Y199917D01*
X507108Y199708D01*
X507025Y199458D01*
X507067Y199208D01*
X507233Y199000D01*
X508067Y198583D01*
X508442Y198292D01*
X508692Y197875D01*
X508775Y197500D01*
X507025D01*
G01X505717Y198000D02*
X505467Y197708D01*
X505133Y197542D01*
X504758Y197500D01*
X504425Y197542D01*
X504092Y197750D01*
X503883Y198000D01*
X503842Y198250D01*
X503925Y198542D01*
X504217Y198750D01*
X504508Y198833D01*
X504883D01*
G01X504508D02*
X504258Y198958D01*
X504050Y199167D01*
X503967Y199417D01*
X504050Y199667D01*
X504258Y199875D01*
X504633Y200000D01*
X505008Y199958D01*
X505383Y199792D01*
G01X519125Y307333D02*
X518792Y307125D01*
X518417Y307000D01*
X518083D01*
X517750Y307125D01*
X517500Y307333D01*
X517375Y307625D01*
X517458Y307917D01*
X517667Y308167D01*
X518042Y308333D01*
X518542Y308417D01*
X518833Y308583D01*
X518958Y308875D01*
X518875Y309167D01*
X518667Y309375D01*
X518375Y309500D01*
X518083D01*
X517792Y309417D01*
X517542Y309208D01*
G01X514233Y309292D02*
X514483Y309417D01*
X514775Y309500D01*
X515108D01*
X515483Y309375D01*
X515775Y309167D01*
X515983Y308917D01*
X516150Y308500D01*
X516192Y308125D01*
X516108Y307750D01*
X515983Y307500D01*
X515733Y307250D01*
X515442Y307083D01*
X515150Y307000D01*
X514858D01*
X514567Y307083D01*
X514317Y307208D01*
X514108Y307375D01*
G01X512050Y307000D02*
Y309500D01*
X512550Y309000D01*
G01Y307000D02*
X511550D01*
G01X508950D02*
Y309500D01*
X509450Y309000D01*
G01Y307000D02*
X508450D01*
G01X506767Y307375D02*
X506517Y307167D01*
X506225Y307042D01*
X505850Y307000D01*
X505475Y307083D01*
X505183Y307250D01*
X504975Y307542D01*
X504933Y307875D01*
X505017Y308208D01*
X505225Y308417D01*
X505517Y308583D01*
X505808Y308625D01*
X506100Y308583D01*
X506475Y308417D01*
X506350Y309500D01*
X505225D01*
G01X502750Y307000D02*
Y309500D01*
X503250Y309000D01*
G01Y307000D02*
X502250D01*
G01X522680Y349333D02*
X522347Y349125D01*
X521972Y349000D01*
X521638D01*
X521305Y349125D01*
X521055Y349333D01*
X520930Y349625D01*
X521013Y349917D01*
X521222Y350167D01*
X521597Y350333D01*
X522097Y350417D01*
X522388Y350583D01*
X522513Y350875D01*
X522430Y351167D01*
X522222Y351375D01*
X521930Y351500D01*
X521638D01*
X521347Y351417D01*
X521097Y351208D01*
G01X517788Y351292D02*
X518038Y351417D01*
X518330Y351500D01*
X518663D01*
X519038Y351375D01*
X519330Y351167D01*
X519538Y350917D01*
X519705Y350500D01*
X519747Y350125D01*
X519663Y349750D01*
X519538Y349500D01*
X519288Y349250D01*
X518997Y349083D01*
X518705Y349000D01*
X518413D01*
X518122Y349083D01*
X517872Y349208D01*
X517663Y349375D01*
G01X515605Y349000D02*
Y351500D01*
X516105Y351000D01*
G01Y349000D02*
X515105D01*
G01X512505D02*
Y351500D01*
X513005Y351000D01*
G01Y349000D02*
X512005D01*
G01X510197Y350042D02*
X509905Y350333D01*
X509655Y350500D01*
X509322Y350583D01*
X509030Y350500D01*
X508822Y350333D01*
X508655Y350083D01*
X508613Y349792D01*
X508655Y349542D01*
X508822Y349292D01*
X509072Y349083D01*
X509363Y349000D01*
X509697Y349083D01*
X509988Y349333D01*
X510155Y349708D01*
X510197Y350125D01*
X510113Y350667D01*
X509988Y350958D01*
X509780Y351250D01*
X509488Y351458D01*
X509197Y351500D01*
X508905Y351417D01*
X508697Y351208D01*
G01X506305Y351500D02*
X506638Y351417D01*
X506888Y351208D01*
X507055Y350958D01*
X507180Y350625D01*
X507222Y350250D01*
X507180Y349875D01*
X507055Y349542D01*
X506888Y349292D01*
X506638Y349083D01*
X506305Y349000D01*
X505972Y349083D01*
X505722Y349292D01*
X505555Y349542D01*
X505430Y349875D01*
X505388Y350250D01*
X505430Y350625D01*
X505555Y350958D01*
X505722Y351208D01*
X505972Y351417D01*
X506305Y351500D01*
G01X522580Y353333D02*
X522247Y353125D01*
X521872Y353000D01*
X521538D01*
X521205Y353125D01*
X520955Y353333D01*
X520830Y353625D01*
X520913Y353917D01*
X521122Y354167D01*
X521497Y354333D01*
X521997Y354417D01*
X522288Y354583D01*
X522413Y354875D01*
X522330Y355167D01*
X522122Y355375D01*
X521830Y355500D01*
X521538D01*
X521247Y355417D01*
X520997Y355208D01*
G01X517688Y355292D02*
X517938Y355417D01*
X518230Y355500D01*
X518563D01*
X518938Y355375D01*
X519230Y355167D01*
X519438Y354917D01*
X519605Y354500D01*
X519647Y354125D01*
X519563Y353750D01*
X519438Y353500D01*
X519188Y353250D01*
X518897Y353083D01*
X518605Y353000D01*
X518313D01*
X518022Y353083D01*
X517772Y353208D01*
X517563Y353375D01*
G01X515505Y353000D02*
Y355500D01*
X516005Y355000D01*
G01Y353000D02*
X515005D01*
G01X512405D02*
Y355500D01*
X512905Y355000D01*
G01Y353000D02*
X511905D01*
G01X509388D02*
X509305Y353542D01*
X509180Y354000D01*
X509013Y354417D01*
X508805Y354875D01*
X508472Y355500D01*
X510138D01*
G01X507122Y353375D02*
X506872Y353167D01*
X506580Y353042D01*
X506205Y353000D01*
X505830Y353083D01*
X505538Y353250D01*
X505330Y353542D01*
X505288Y353875D01*
X505372Y354208D01*
X505580Y354417D01*
X505872Y354583D01*
X506163Y354625D01*
X506455Y354583D01*
X506830Y354417D01*
X506705Y355500D01*
X505580D01*
G01X522580Y357333D02*
X522247Y357125D01*
X521872Y357000D01*
X521538D01*
X521205Y357125D01*
X520955Y357333D01*
X520830Y357625D01*
X520913Y357917D01*
X521122Y358167D01*
X521497Y358333D01*
X521997Y358417D01*
X522288Y358583D01*
X522413Y358875D01*
X522330Y359167D01*
X522122Y359375D01*
X521830Y359500D01*
X521538D01*
X521247Y359417D01*
X520997Y359208D01*
G01X517688Y359292D02*
X517938Y359417D01*
X518230Y359500D01*
X518563D01*
X518938Y359375D01*
X519230Y359167D01*
X519438Y358917D01*
X519605Y358500D01*
X519647Y358125D01*
X519563Y357750D01*
X519438Y357500D01*
X519188Y357250D01*
X518897Y357083D01*
X518605Y357000D01*
X518313D01*
X518022Y357083D01*
X517772Y357208D01*
X517563Y357375D01*
G01X515505Y357000D02*
Y359500D01*
X516005Y359000D01*
G01Y357000D02*
X515005D01*
G01X512405D02*
Y359500D01*
X512905Y359000D01*
G01Y357000D02*
X511905D01*
G01X509388D02*
X509305Y357542D01*
X509180Y358000D01*
X509013Y358417D01*
X508805Y358875D01*
X508472Y359500D01*
X510138D01*
G01X505705Y357000D02*
Y359500D01*
X507247Y357708D01*
X505163D01*
G01X515680Y370833D02*
X515347Y370625D01*
X514972Y370500D01*
X514638D01*
X514305Y370625D01*
X514055Y370833D01*
X513930Y371125D01*
X514013Y371417D01*
X514222Y371667D01*
X514597Y371833D01*
X515097Y371917D01*
X515388Y372083D01*
X515513Y372375D01*
X515430Y372667D01*
X515222Y372875D01*
X514930Y373000D01*
X514638D01*
X514347Y372917D01*
X514097Y372708D01*
G01X510788Y372792D02*
X511038Y372917D01*
X511330Y373000D01*
X511663D01*
X512038Y372875D01*
X512330Y372667D01*
X512538Y372417D01*
X512705Y372000D01*
X512747Y371625D01*
X512663Y371250D01*
X512538Y371000D01*
X512288Y370750D01*
X511997Y370583D01*
X511705Y370500D01*
X511413D01*
X511122Y370583D01*
X510872Y370708D01*
X510663Y370875D01*
G01X508605Y370500D02*
Y373000D01*
X509105Y372500D01*
G01Y370500D02*
X508105D01*
G01X505505D02*
Y373000D01*
X506005Y372500D01*
G01Y370500D02*
X505005D01*
G01X503113Y370792D02*
X502822Y370583D01*
X502488Y370500D01*
X502155Y370583D01*
X501863Y370833D01*
X501655Y371208D01*
X501572Y371583D01*
Y372042D01*
X501655Y372417D01*
X501863Y372750D01*
X502113Y372917D01*
X502405Y373000D01*
X502738Y372917D01*
X502988Y372750D01*
X503155Y372500D01*
X503238Y372167D01*
X503155Y371875D01*
X502947Y371583D01*
X502697Y371417D01*
X502405Y371375D01*
X502072Y371458D01*
X501822Y371667D01*
X501572Y372042D01*
G01X499305Y373000D02*
X499638Y372917D01*
X499888Y372708D01*
X500055Y372458D01*
X500180Y372125D01*
X500222Y371750D01*
X500180Y371375D01*
X500055Y371042D01*
X499888Y370792D01*
X499638Y370583D01*
X499305Y370500D01*
X498972Y370583D01*
X498722Y370792D01*
X498555Y371042D01*
X498430Y371375D01*
X498388Y371750D01*
X498430Y372125D01*
X498555Y372458D01*
X498722Y372708D01*
X498972Y372917D01*
X499305Y373000D01*
G01X515680Y375333D02*
X515347Y375125D01*
X514972Y375000D01*
X514638D01*
X514305Y375125D01*
X514055Y375333D01*
X513930Y375625D01*
X514013Y375917D01*
X514222Y376167D01*
X514597Y376333D01*
X515097Y376417D01*
X515388Y376583D01*
X515513Y376875D01*
X515430Y377167D01*
X515222Y377375D01*
X514930Y377500D01*
X514638D01*
X514347Y377417D01*
X514097Y377208D01*
G01X510788Y377292D02*
X511038Y377417D01*
X511330Y377500D01*
X511663D01*
X512038Y377375D01*
X512330Y377167D01*
X512538Y376917D01*
X512705Y376500D01*
X512747Y376125D01*
X512663Y375750D01*
X512538Y375500D01*
X512288Y375250D01*
X511997Y375083D01*
X511705Y375000D01*
X511413D01*
X511122Y375083D01*
X510872Y375208D01*
X510663Y375375D01*
G01X508605Y375000D02*
Y377500D01*
X509105Y377000D01*
G01Y375000D02*
X508105D01*
G01X505505D02*
Y377500D01*
X506005Y377000D01*
G01Y375000D02*
X505005D01*
G01X502405D02*
X502113Y375042D01*
X501780Y375167D01*
X501572Y375375D01*
X501488Y375667D01*
X501572Y375958D01*
X501822Y376208D01*
X502197Y376333D01*
X502613D01*
X502863Y376417D01*
X503072Y376625D01*
X503155Y376917D01*
X503030Y377208D01*
X502738Y377417D01*
X502405Y377500D01*
X502072Y377417D01*
X501780Y377208D01*
X501655Y376917D01*
X501738Y376625D01*
X501947Y376417D01*
X502197Y376333D01*
X502613D01*
X502988Y376208D01*
X503238Y375958D01*
X503322Y375667D01*
X503238Y375375D01*
X503030Y375167D01*
X502697Y375042D01*
X502405Y375000D01*
G01X499388D02*
X499305Y375542D01*
X499180Y376000D01*
X499013Y376417D01*
X498805Y376875D01*
X498472Y377500D01*
X500138D01*
G01X522180Y391333D02*
X521847Y391125D01*
X521472Y391000D01*
X521138D01*
X520805Y391125D01*
X520555Y391333D01*
X520430Y391625D01*
X520513Y391917D01*
X520722Y392167D01*
X521097Y392333D01*
X521597Y392417D01*
X521888Y392583D01*
X522013Y392875D01*
X521930Y393167D01*
X521722Y393375D01*
X521430Y393500D01*
X521138D01*
X520847Y393417D01*
X520597Y393208D01*
G01X517288Y393292D02*
X517538Y393417D01*
X517830Y393500D01*
X518163D01*
X518538Y393375D01*
X518830Y393167D01*
X519038Y392917D01*
X519205Y392500D01*
X519247Y392125D01*
X519163Y391750D01*
X519038Y391500D01*
X518788Y391250D01*
X518497Y391083D01*
X518205Y391000D01*
X517913D01*
X517622Y391083D01*
X517372Y391208D01*
X517163Y391375D01*
G01X515105Y391000D02*
Y393500D01*
X515605Y393000D01*
G01Y391000D02*
X514605D01*
G01X512005D02*
Y393500D01*
X512505Y393000D01*
G01Y391000D02*
X511505D01*
G01X509697Y392042D02*
X509405Y392333D01*
X509155Y392500D01*
X508822Y392583D01*
X508530Y392500D01*
X508322Y392333D01*
X508155Y392083D01*
X508113Y391792D01*
X508155Y391542D01*
X508322Y391292D01*
X508572Y391083D01*
X508863Y391000D01*
X509197Y391083D01*
X509488Y391333D01*
X509655Y391708D01*
X509697Y392125D01*
X509613Y392667D01*
X509488Y392958D01*
X509280Y393250D01*
X508988Y393458D01*
X508697Y393500D01*
X508405Y393417D01*
X508197Y393208D01*
G01X505888Y391000D02*
X505805Y391542D01*
X505680Y392000D01*
X505513Y392417D01*
X505305Y392875D01*
X504972Y393500D01*
X506638D01*
G01X511555Y414800D02*
X507555D01*
Y422200D01*
G01X516853Y842333D02*
X516520Y842125D01*
X516145Y842000D01*
X515811D01*
X515478Y842125D01*
X515228Y842333D01*
X515103Y842625D01*
X515186Y842917D01*
X515395Y843167D01*
X515770Y843333D01*
X516270Y843417D01*
X516561Y843583D01*
X516686Y843875D01*
X516603Y844167D01*
X516395Y844375D01*
X516103Y844500D01*
X515811D01*
X515520Y844417D01*
X515270Y844208D01*
G01X513711Y842000D02*
Y844500D01*
X512670D01*
X512336Y844375D01*
X512128Y844208D01*
X512045Y843875D01*
X512128Y843542D01*
X512378Y843333D01*
X512670Y843208D01*
X513711D01*
G01X512670D02*
X512045Y842000D01*
G01X510486Y842292D02*
X510195Y842083D01*
X509861Y842000D01*
X509528Y842083D01*
X509236Y842333D01*
X509028Y842708D01*
X508945Y843083D01*
Y843542D01*
X509028Y843917D01*
X509236Y844250D01*
X509486Y844417D01*
X509778Y844500D01*
X510111Y844417D01*
X510361Y844250D01*
X510528Y844000D01*
X510611Y843667D01*
X510528Y843375D01*
X510320Y843083D01*
X510070Y842917D01*
X509778Y842875D01*
X509445Y842958D01*
X509195Y843167D01*
X508945Y843542D01*
G01X506678Y844500D02*
X507011Y844417D01*
X507261Y844208D01*
X507428Y843958D01*
X507553Y843625D01*
X507595Y843250D01*
X507553Y842875D01*
X507428Y842542D01*
X507261Y842292D01*
X507011Y842083D01*
X506678Y842000D01*
X506345Y842083D01*
X506095Y842292D01*
X505928Y842542D01*
X505803Y842875D01*
X505761Y843250D01*
X505803Y843625D01*
X505928Y843958D01*
X506095Y844208D01*
X506345Y844417D01*
X506678Y844500D01*
G01X503078Y842000D02*
Y844500D01*
X504620Y842708D01*
X502536D01*
G01X516853Y834333D02*
X516520Y834125D01*
X516145Y834000D01*
X515811D01*
X515478Y834125D01*
X515228Y834333D01*
X515103Y834625D01*
X515186Y834917D01*
X515395Y835167D01*
X515770Y835333D01*
X516270Y835417D01*
X516561Y835583D01*
X516686Y835875D01*
X516603Y836167D01*
X516395Y836375D01*
X516103Y836500D01*
X515811D01*
X515520Y836417D01*
X515270Y836208D01*
G01X513711Y834000D02*
Y836500D01*
X512670D01*
X512336Y836375D01*
X512128Y836208D01*
X512045Y835875D01*
X512128Y835542D01*
X512378Y835333D01*
X512670Y835208D01*
X513711D01*
G01X512670D02*
X512045Y834000D01*
G01X510486Y834292D02*
X510195Y834083D01*
X509861Y834000D01*
X509528Y834083D01*
X509236Y834333D01*
X509028Y834708D01*
X508945Y835083D01*
Y835542D01*
X509028Y835917D01*
X509236Y836250D01*
X509486Y836417D01*
X509778Y836500D01*
X510111Y836417D01*
X510361Y836250D01*
X510528Y836000D01*
X510611Y835667D01*
X510528Y835375D01*
X510320Y835083D01*
X510070Y834917D01*
X509778Y834875D01*
X509445Y834958D01*
X509195Y835167D01*
X508945Y835542D01*
G01X506678Y834000D02*
Y836500D01*
X507178Y836000D01*
G01Y834000D02*
X506178D01*
G01X503578Y836500D02*
X503911Y836417D01*
X504161Y836208D01*
X504328Y835958D01*
X504453Y835625D01*
X504495Y835250D01*
X504453Y834875D01*
X504328Y834542D01*
X504161Y834292D01*
X503911Y834083D01*
X503578Y834000D01*
X503245Y834083D01*
X502995Y834292D01*
X502828Y834542D01*
X502703Y834875D01*
X502661Y835250D01*
X502703Y835625D01*
X502828Y835958D01*
X502995Y836208D01*
X503245Y836417D01*
X503578Y836500D01*
G01X516853Y838333D02*
X516520Y838125D01*
X516145Y838000D01*
X515811D01*
X515478Y838125D01*
X515228Y838333D01*
X515103Y838625D01*
X515186Y838917D01*
X515395Y839167D01*
X515770Y839333D01*
X516270Y839417D01*
X516561Y839583D01*
X516686Y839875D01*
X516603Y840167D01*
X516395Y840375D01*
X516103Y840500D01*
X515811D01*
X515520Y840417D01*
X515270Y840208D01*
G01X513711Y838000D02*
Y840500D01*
X512670D01*
X512336Y840375D01*
X512128Y840208D01*
X512045Y839875D01*
X512128Y839542D01*
X512378Y839333D01*
X512670Y839208D01*
X513711D01*
G01X512670D02*
X512045Y838000D01*
G01X510486Y838292D02*
X510195Y838083D01*
X509861Y838000D01*
X509528Y838083D01*
X509236Y838333D01*
X509028Y838708D01*
X508945Y839083D01*
Y839542D01*
X509028Y839917D01*
X509236Y840250D01*
X509486Y840417D01*
X509778Y840500D01*
X510111Y840417D01*
X510361Y840250D01*
X510528Y840000D01*
X510611Y839667D01*
X510528Y839375D01*
X510320Y839083D01*
X510070Y838917D01*
X509778Y838875D01*
X509445Y838958D01*
X509195Y839167D01*
X508945Y839542D01*
G01X506678Y838000D02*
Y840500D01*
X507178Y840000D01*
G01Y838000D02*
X506178D01*
G01X503578D02*
Y840500D01*
X504078Y840000D01*
G01Y838000D02*
X503078D01*
G01X518403Y830333D02*
X518070Y830125D01*
X517695Y830000D01*
X517361D01*
X517028Y830125D01*
X516778Y830333D01*
X516653Y830625D01*
X516736Y830917D01*
X516945Y831167D01*
X517320Y831333D01*
X517820Y831417D01*
X518111Y831583D01*
X518236Y831875D01*
X518153Y832167D01*
X517945Y832375D01*
X517653Y832500D01*
X517361D01*
X517070Y832417D01*
X516820Y832208D01*
G01X513511Y832292D02*
X513761Y832417D01*
X514053Y832500D01*
X514386D01*
X514761Y832375D01*
X515053Y832167D01*
X515261Y831917D01*
X515428Y831500D01*
X515470Y831125D01*
X515386Y830750D01*
X515261Y830500D01*
X515011Y830250D01*
X514720Y830083D01*
X514428Y830000D01*
X514136D01*
X513845Y830083D01*
X513595Y830208D01*
X513386Y830375D01*
G01X511328Y830000D02*
Y832500D01*
X511828Y832000D01*
G01Y830000D02*
X510828D01*
G01X509020Y832083D02*
X508770Y832333D01*
X508478Y832458D01*
X508145Y832500D01*
X507728Y832417D01*
X507436Y832208D01*
X507353Y831958D01*
X507395Y831708D01*
X507561Y831500D01*
X508395Y831083D01*
X508770Y830792D01*
X509020Y830375D01*
X509103Y830000D01*
X507353D01*
G01X505836Y830292D02*
X505545Y830083D01*
X505211Y830000D01*
X504878Y830083D01*
X504586Y830333D01*
X504378Y830708D01*
X504295Y831083D01*
Y831542D01*
X504378Y831917D01*
X504586Y832250D01*
X504836Y832417D01*
X505128Y832500D01*
X505461Y832417D01*
X505711Y832250D01*
X505878Y832000D01*
X505961Y831667D01*
X505878Y831375D01*
X505670Y831083D01*
X505420Y830917D01*
X505128Y830875D01*
X504795Y830958D01*
X504545Y831167D01*
X504295Y831542D01*
G01X502028Y830000D02*
Y832500D01*
X502528Y832000D01*
G01Y830000D02*
X501528D01*
G01X518403Y855333D02*
X518070Y855125D01*
X517695Y855000D01*
X517361D01*
X517028Y855125D01*
X516778Y855333D01*
X516653Y855625D01*
X516736Y855917D01*
X516945Y856167D01*
X517320Y856333D01*
X517820Y856417D01*
X518111Y856583D01*
X518236Y856875D01*
X518153Y857167D01*
X517945Y857375D01*
X517653Y857500D01*
X517361D01*
X517070Y857417D01*
X516820Y857208D01*
G01X515261Y855000D02*
Y857500D01*
X514220D01*
X513886Y857375D01*
X513678Y857208D01*
X513595Y856875D01*
X513678Y856542D01*
X513928Y856333D01*
X514220Y856208D01*
X515261D01*
G01X514220D02*
X513595Y855000D01*
G01X511328D02*
Y857500D01*
X511828Y857000D01*
G01Y855000D02*
X510828D01*
G01X509020Y857083D02*
X508770Y857333D01*
X508478Y857458D01*
X508145Y857500D01*
X507728Y857417D01*
X507436Y857208D01*
X507353Y856958D01*
X507395Y856708D01*
X507561Y856500D01*
X508395Y856083D01*
X508770Y855792D01*
X509020Y855375D01*
X509103Y855000D01*
X507353D01*
G01X505920Y856042D02*
X505628Y856333D01*
X505378Y856500D01*
X505045Y856583D01*
X504753Y856500D01*
X504545Y856333D01*
X504378Y856083D01*
X504336Y855792D01*
X504378Y855542D01*
X504545Y855292D01*
X504795Y855083D01*
X505086Y855000D01*
X505420Y855083D01*
X505711Y855333D01*
X505878Y855708D01*
X505920Y856125D01*
X505836Y856667D01*
X505711Y856958D01*
X505503Y857250D01*
X505211Y857458D01*
X504920Y857500D01*
X504628Y857417D01*
X504420Y857208D01*
G01X502028Y855000D02*
Y857500D01*
X502528Y857000D01*
G01Y855000D02*
X501528D01*
G01X518403Y850833D02*
X518070Y850625D01*
X517695Y850500D01*
X517361D01*
X517028Y850625D01*
X516778Y850833D01*
X516653Y851125D01*
X516736Y851417D01*
X516945Y851667D01*
X517320Y851833D01*
X517820Y851917D01*
X518111Y852083D01*
X518236Y852375D01*
X518153Y852667D01*
X517945Y852875D01*
X517653Y853000D01*
X517361D01*
X517070Y852917D01*
X516820Y852708D01*
G01X515261Y850500D02*
Y853000D01*
X514220D01*
X513886Y852875D01*
X513678Y852708D01*
X513595Y852375D01*
X513678Y852042D01*
X513928Y851833D01*
X514220Y851708D01*
X515261D01*
G01X514220D02*
X513595Y850500D01*
G01X511328D02*
Y853000D01*
X511828Y852500D01*
G01Y850500D02*
X510828D01*
G01X509020Y852583D02*
X508770Y852833D01*
X508478Y852958D01*
X508145Y853000D01*
X507728Y852917D01*
X507436Y852708D01*
X507353Y852458D01*
X507395Y852208D01*
X507561Y852000D01*
X508395Y851583D01*
X508770Y851292D01*
X509020Y850875D01*
X509103Y850500D01*
X507353D01*
G01X505211D02*
X505128Y851042D01*
X505003Y851500D01*
X504836Y851917D01*
X504628Y852375D01*
X504295Y853000D01*
X505961D01*
G01X502028Y850500D02*
Y853000D01*
X502528Y852500D01*
G01Y850500D02*
X501528D01*
G01X516853Y846833D02*
X516520Y846625D01*
X516145Y846500D01*
X515811D01*
X515478Y846625D01*
X515228Y846833D01*
X515103Y847125D01*
X515186Y847417D01*
X515395Y847667D01*
X515770Y847833D01*
X516270Y847917D01*
X516561Y848083D01*
X516686Y848375D01*
X516603Y848667D01*
X516395Y848875D01*
X516103Y849000D01*
X515811D01*
X515520Y848917D01*
X515270Y848708D01*
G01X513711Y846500D02*
Y849000D01*
X512670D01*
X512336Y848875D01*
X512128Y848708D01*
X512045Y848375D01*
X512128Y848042D01*
X512378Y847833D01*
X512670Y847708D01*
X513711D01*
G01X512670D02*
X512045Y846500D01*
G01X510486Y846792D02*
X510195Y846583D01*
X509861Y846500D01*
X509528Y846583D01*
X509236Y846833D01*
X509028Y847208D01*
X508945Y847583D01*
Y848042D01*
X509028Y848417D01*
X509236Y848750D01*
X509486Y848917D01*
X509778Y849000D01*
X510111Y848917D01*
X510361Y848750D01*
X510528Y848500D01*
X510611Y848167D01*
X510528Y847875D01*
X510320Y847583D01*
X510070Y847417D01*
X509778Y847375D01*
X509445Y847458D01*
X509195Y847667D01*
X508945Y848042D01*
G01X506678Y849000D02*
X507011Y848917D01*
X507261Y848708D01*
X507428Y848458D01*
X507553Y848125D01*
X507595Y847750D01*
X507553Y847375D01*
X507428Y847042D01*
X507261Y846792D01*
X507011Y846583D01*
X506678Y846500D01*
X506345Y846583D01*
X506095Y846792D01*
X505928Y847042D01*
X505803Y847375D01*
X505761Y847750D01*
X505803Y848125D01*
X505928Y848458D01*
X506095Y848708D01*
X506345Y848917D01*
X506678Y849000D01*
G01X504495Y846875D02*
X504245Y846667D01*
X503953Y846542D01*
X503578Y846500D01*
X503203Y846583D01*
X502911Y846750D01*
X502703Y847042D01*
X502661Y847375D01*
X502745Y847708D01*
X502953Y847917D01*
X503245Y848083D01*
X503536Y848125D01*
X503828Y848083D01*
X504203Y847917D01*
X504078Y849000D01*
X502953D01*
G01X516853Y859833D02*
X516520Y859625D01*
X516145Y859500D01*
X515811D01*
X515478Y859625D01*
X515228Y859833D01*
X515103Y860125D01*
X515186Y860417D01*
X515395Y860667D01*
X515770Y860833D01*
X516270Y860917D01*
X516561Y861083D01*
X516686Y861375D01*
X516603Y861667D01*
X516395Y861875D01*
X516103Y862000D01*
X515811D01*
X515520Y861917D01*
X515270Y861708D01*
G01X513711Y859500D02*
Y862000D01*
X512670D01*
X512336Y861875D01*
X512128Y861708D01*
X512045Y861375D01*
X512128Y861042D01*
X512378Y860833D01*
X512670Y860708D01*
X513711D01*
G01X512670D02*
X512045Y859500D01*
G01X510486Y859792D02*
X510195Y859583D01*
X509861Y859500D01*
X509528Y859583D01*
X509236Y859833D01*
X509028Y860208D01*
X508945Y860583D01*
Y861042D01*
X509028Y861417D01*
X509236Y861750D01*
X509486Y861917D01*
X509778Y862000D01*
X510111Y861917D01*
X510361Y861750D01*
X510528Y861500D01*
X510611Y861167D01*
X510528Y860875D01*
X510320Y860583D01*
X510070Y860417D01*
X509778Y860375D01*
X509445Y860458D01*
X509195Y860667D01*
X508945Y861042D01*
G01X506678Y862000D02*
X507011Y861917D01*
X507261Y861708D01*
X507428Y861458D01*
X507553Y861125D01*
X507595Y860750D01*
X507553Y860375D01*
X507428Y860042D01*
X507261Y859792D01*
X507011Y859583D01*
X506678Y859500D01*
X506345Y859583D01*
X506095Y859792D01*
X505928Y860042D01*
X505803Y860375D01*
X505761Y860750D01*
X505803Y861125D01*
X505928Y861458D01*
X506095Y861708D01*
X506345Y861917D01*
X506678Y862000D01*
G01X504286Y859792D02*
X503995Y859583D01*
X503661Y859500D01*
X503328Y859583D01*
X503036Y859833D01*
X502828Y860208D01*
X502745Y860583D01*
Y861042D01*
X502828Y861417D01*
X503036Y861750D01*
X503286Y861917D01*
X503578Y862000D01*
X503911Y861917D01*
X504161Y861750D01*
X504328Y861500D01*
X504411Y861167D01*
X504328Y860875D01*
X504120Y860583D01*
X503870Y860417D01*
X503578Y860375D01*
X503245Y860458D01*
X502995Y860667D01*
X502745Y861042D01*
G01X517353Y874833D02*
X517020Y874625D01*
X516645Y874500D01*
X516311D01*
X515978Y874625D01*
X515728Y874833D01*
X515603Y875125D01*
X515686Y875417D01*
X515895Y875667D01*
X516270Y875833D01*
X516770Y875917D01*
X517061Y876083D01*
X517186Y876375D01*
X517103Y876667D01*
X516895Y876875D01*
X516603Y877000D01*
X516311D01*
X516020Y876917D01*
X515770Y876708D01*
G01X514211Y874500D02*
Y877000D01*
X513170D01*
X512836Y876875D01*
X512628Y876708D01*
X512545Y876375D01*
X512628Y876042D01*
X512878Y875833D01*
X513170Y875708D01*
X514211D01*
G01X513170D02*
X512545Y874500D01*
G01X510278D02*
X509986Y874542D01*
X509653Y874667D01*
X509445Y874875D01*
X509361Y875167D01*
X509445Y875458D01*
X509695Y875708D01*
X510070Y875833D01*
X510486D01*
X510736Y875917D01*
X510945Y876125D01*
X511028Y876417D01*
X510903Y876708D01*
X510611Y876917D01*
X510278Y877000D01*
X509945Y876917D01*
X509653Y876708D01*
X509528Y876417D01*
X509611Y876125D01*
X509820Y875917D01*
X510070Y875833D01*
X510486D01*
X510861Y875708D01*
X511111Y875458D01*
X511195Y875167D01*
X511111Y874875D01*
X510903Y874667D01*
X510570Y874542D01*
X510278Y874500D01*
G01X507261D02*
X507178Y875042D01*
X507053Y875500D01*
X506886Y875917D01*
X506678Y876375D01*
X506345Y877000D01*
X508011D01*
G01X504078D02*
X504411Y876917D01*
X504661Y876708D01*
X504828Y876458D01*
X504953Y876125D01*
X504995Y875750D01*
X504953Y875375D01*
X504828Y875042D01*
X504661Y874792D01*
X504411Y874583D01*
X504078Y874500D01*
X503745Y874583D01*
X503495Y874792D01*
X503328Y875042D01*
X503203Y875375D01*
X503161Y875750D01*
X503203Y876125D01*
X503328Y876458D01*
X503495Y876708D01*
X503745Y876917D01*
X504078Y877000D01*
G01X496978Y879000D02*
Y872000D01*
G01X518625Y868333D02*
X518292Y868125D01*
X517917Y868000D01*
X517583D01*
X517250Y868125D01*
X517000Y868333D01*
X516875Y868625D01*
X516958Y868917D01*
X517167Y869167D01*
X517542Y869333D01*
X518042Y869417D01*
X518333Y869583D01*
X518458Y869875D01*
X518375Y870167D01*
X518167Y870375D01*
X517875Y870500D01*
X517583D01*
X517292Y870417D01*
X517042Y870208D01*
G01X513733Y870292D02*
X513983Y870417D01*
X514275Y870500D01*
X514608D01*
X514983Y870375D01*
X515275Y870167D01*
X515483Y869917D01*
X515650Y869500D01*
X515692Y869125D01*
X515608Y868750D01*
X515483Y868500D01*
X515233Y868250D01*
X514942Y868083D01*
X514650Y868000D01*
X514358D01*
X514067Y868083D01*
X513817Y868208D01*
X513608Y868375D01*
G01X511550Y868000D02*
Y870500D01*
X512050Y870000D01*
G01Y868000D02*
X511050D01*
G01X509242Y870083D02*
X508992Y870333D01*
X508700Y870458D01*
X508367Y870500D01*
X507950Y870417D01*
X507658Y870208D01*
X507575Y869958D01*
X507617Y869708D01*
X507783Y869500D01*
X508617Y869083D01*
X508992Y868792D01*
X509242Y868375D01*
X509325Y868000D01*
X507575D01*
G01X505350D02*
X505058Y868042D01*
X504725Y868167D01*
X504517Y868375D01*
X504433Y868667D01*
X504517Y868958D01*
X504767Y869208D01*
X505142Y869333D01*
X505558D01*
X505808Y869417D01*
X506017Y869625D01*
X506100Y869917D01*
X505975Y870208D01*
X505683Y870417D01*
X505350Y870500D01*
X505017Y870417D01*
X504725Y870208D01*
X504600Y869917D01*
X504683Y869625D01*
X504892Y869417D01*
X505142Y869333D01*
X505558D01*
X505933Y869208D01*
X506183Y868958D01*
X506267Y868667D01*
X506183Y868375D01*
X505975Y868167D01*
X505642Y868042D01*
X505350Y868000D01*
G01X502250D02*
X501958Y868042D01*
X501625Y868167D01*
X501417Y868375D01*
X501333Y868667D01*
X501417Y868958D01*
X501667Y869208D01*
X502042Y869333D01*
X502458D01*
X502708Y869417D01*
X502917Y869625D01*
X503000Y869917D01*
X502875Y870208D01*
X502583Y870417D01*
X502250Y870500D01*
X501917Y870417D01*
X501625Y870208D01*
X501500Y869917D01*
X501583Y869625D01*
X501792Y869417D01*
X502042Y869333D01*
X502458D01*
X502833Y869208D01*
X503083Y868958D01*
X503167Y868667D01*
X503083Y868375D01*
X502875Y868167D01*
X502542Y868042D01*
X502250Y868000D01*
G01X520929Y132000D02*
Y119000D01*
G01X533004Y112833D02*
X532671Y112625D01*
X532296Y112500D01*
X531962D01*
X531629Y112625D01*
X531379Y112833D01*
X531254Y113125D01*
X531337Y113417D01*
X531546Y113667D01*
X531921Y113833D01*
X532421Y113917D01*
X532712Y114083D01*
X532837Y114375D01*
X532754Y114667D01*
X532546Y114875D01*
X532254Y115000D01*
X531962D01*
X531671Y114917D01*
X531421Y114708D01*
G01X529862Y112500D02*
Y115000D01*
X528821D01*
X528487Y114875D01*
X528279Y114708D01*
X528196Y114375D01*
X528279Y114042D01*
X528529Y113833D01*
X528821Y113708D01*
X529862D01*
G01X528821D02*
X528196Y112500D01*
G01X526721Y113542D02*
X526429Y113833D01*
X526179Y114000D01*
X525846Y114083D01*
X525554Y114000D01*
X525346Y113833D01*
X525179Y113583D01*
X525137Y113292D01*
X525179Y113042D01*
X525346Y112792D01*
X525596Y112583D01*
X525887Y112500D01*
X526221Y112583D01*
X526512Y112833D01*
X526679Y113208D01*
X526721Y113625D01*
X526637Y114167D01*
X526512Y114458D01*
X526304Y114750D01*
X526012Y114958D01*
X525721Y115000D01*
X525429Y114917D01*
X525221Y114708D01*
G01X523746Y112875D02*
X523496Y112667D01*
X523204Y112542D01*
X522829Y112500D01*
X522454Y112583D01*
X522162Y112750D01*
X521954Y113042D01*
X521912Y113375D01*
X521996Y113708D01*
X522204Y113917D01*
X522496Y114083D01*
X522787Y114125D01*
X523079Y114083D01*
X523454Y113917D01*
X523329Y115000D01*
X522204D01*
G01X519812Y112500D02*
X519729Y113042D01*
X519604Y113500D01*
X519437Y113917D01*
X519229Y114375D01*
X518896Y115000D01*
X520562D01*
G01X533004Y108333D02*
X532671Y108125D01*
X532296Y108000D01*
X531962D01*
X531629Y108125D01*
X531379Y108333D01*
X531254Y108625D01*
X531337Y108917D01*
X531546Y109167D01*
X531921Y109333D01*
X532421Y109417D01*
X532712Y109583D01*
X532837Y109875D01*
X532754Y110167D01*
X532546Y110375D01*
X532254Y110500D01*
X531962D01*
X531671Y110417D01*
X531421Y110208D01*
G01X529862Y108000D02*
Y110500D01*
X528821D01*
X528487Y110375D01*
X528279Y110208D01*
X528196Y109875D01*
X528279Y109542D01*
X528529Y109333D01*
X528821Y109208D01*
X529862D01*
G01X528821D02*
X528196Y108000D01*
G01X526721Y109042D02*
X526429Y109333D01*
X526179Y109500D01*
X525846Y109583D01*
X525554Y109500D01*
X525346Y109333D01*
X525179Y109083D01*
X525137Y108792D01*
X525179Y108542D01*
X525346Y108292D01*
X525596Y108083D01*
X525887Y108000D01*
X526221Y108083D01*
X526512Y108333D01*
X526679Y108708D01*
X526721Y109125D01*
X526637Y109667D01*
X526512Y109958D01*
X526304Y110250D01*
X526012Y110458D01*
X525721Y110500D01*
X525429Y110417D01*
X525221Y110208D01*
G01X523746Y108375D02*
X523496Y108167D01*
X523204Y108042D01*
X522829Y108000D01*
X522454Y108083D01*
X522162Y108250D01*
X521954Y108542D01*
X521912Y108875D01*
X521996Y109208D01*
X522204Y109417D01*
X522496Y109583D01*
X522787Y109625D01*
X523079Y109583D01*
X523454Y109417D01*
X523329Y110500D01*
X522204D01*
G01X520646Y108375D02*
X520396Y108167D01*
X520104Y108042D01*
X519729Y108000D01*
X519354Y108083D01*
X519062Y108250D01*
X518854Y108542D01*
X518812Y108875D01*
X518896Y109208D01*
X519104Y109417D01*
X519396Y109583D01*
X519687Y109625D01*
X519979Y109583D01*
X520354Y109417D01*
X520229Y110500D01*
X519104D01*
G01X529629Y131000D02*
Y127000D01*
X522229D01*
G01Y122500D02*
Y126500D01*
X529629D01*
G01X523333Y148925D02*
X523125Y149258D01*
X523000Y149633D01*
Y149967D01*
X523125Y150300D01*
X523333Y150550D01*
X523625Y150675D01*
X523917Y150592D01*
X524167Y150383D01*
X524333Y150008D01*
X524417Y149508D01*
X524583Y149217D01*
X524875Y149092D01*
X525167Y149175D01*
X525375Y149383D01*
X525500Y149675D01*
Y149967D01*
X525417Y150258D01*
X525208Y150508D01*
G01X525292Y153817D02*
X525417Y153567D01*
X525500Y153275D01*
Y152942D01*
X525375Y152567D01*
X525167Y152275D01*
X524917Y152067D01*
X524500Y151900D01*
X524125Y151858D01*
X523750Y151942D01*
X523500Y152067D01*
X523250Y152317D01*
X523083Y152608D01*
X523000Y152900D01*
Y153192D01*
X523083Y153483D01*
X523208Y153733D01*
X523375Y153942D01*
G01X523292Y155292D02*
X523083Y155583D01*
X523000Y155917D01*
X523083Y156250D01*
X523333Y156542D01*
X523708Y156750D01*
X524083Y156833D01*
X524542D01*
X524917Y156750D01*
X525250Y156542D01*
X525417Y156292D01*
X525500Y156000D01*
X525417Y155667D01*
X525250Y155417D01*
X525000Y155250D01*
X524667Y155167D01*
X524375Y155250D01*
X524083Y155458D01*
X523917Y155708D01*
X523875Y156000D01*
X523958Y156333D01*
X524167Y156583D01*
X524542Y156833D01*
G01X523000Y159017D02*
X523542Y159100D01*
X524000Y159225D01*
X524417Y159392D01*
X524875Y159600D01*
X525500Y159933D01*
Y158267D01*
G01X524042Y161408D02*
X524333Y161700D01*
X524500Y161950D01*
X524583Y162283D01*
X524500Y162575D01*
X524333Y162783D01*
X524083Y162950D01*
X523792Y162992D01*
X523542Y162950D01*
X523292Y162783D01*
X523083Y162533D01*
X523000Y162242D01*
X523083Y161908D01*
X523333Y161617D01*
X523708Y161450D01*
X524125Y161408D01*
X524667Y161492D01*
X524958Y161617D01*
X525250Y161825D01*
X525458Y162117D01*
X525500Y162408D01*
X525417Y162700D01*
X525208Y162908D01*
G01X518975Y158833D02*
X518642Y158625D01*
X518267Y158500D01*
X517933D01*
X517600Y158625D01*
X517350Y158833D01*
X517225Y159125D01*
X517308Y159417D01*
X517517Y159667D01*
X517892Y159833D01*
X518392Y159917D01*
X518683Y160083D01*
X518808Y160375D01*
X518725Y160667D01*
X518517Y160875D01*
X518225Y161000D01*
X517933D01*
X517642Y160917D01*
X517392Y160708D01*
G01X515833Y161000D02*
Y158500D01*
X514167D01*
G01X512692Y159542D02*
X512400Y159833D01*
X512150Y160000D01*
X511817Y160083D01*
X511525Y160000D01*
X511317Y159833D01*
X511150Y159583D01*
X511108Y159292D01*
X511150Y159042D01*
X511317Y158792D01*
X511567Y158583D01*
X511858Y158500D01*
X512192Y158583D01*
X512483Y158833D01*
X512650Y159208D01*
X512692Y159625D01*
X512608Y160167D01*
X512483Y160458D01*
X512275Y160750D01*
X511983Y160958D01*
X511692Y161000D01*
X511400Y160917D01*
X511192Y160708D01*
G01X529180Y336333D02*
X528847Y336125D01*
X528472Y336000D01*
X528138D01*
X527805Y336125D01*
X527555Y336333D01*
X527430Y336625D01*
X527513Y336917D01*
X527722Y337167D01*
X528097Y337333D01*
X528597Y337417D01*
X528888Y337583D01*
X529013Y337875D01*
X528930Y338167D01*
X528722Y338375D01*
X528430Y338500D01*
X528138D01*
X527847Y338417D01*
X527597Y338208D01*
G01X524288Y338292D02*
X524538Y338417D01*
X524830Y338500D01*
X525163D01*
X525538Y338375D01*
X525830Y338167D01*
X526038Y337917D01*
X526205Y337500D01*
X526247Y337125D01*
X526163Y336750D01*
X526038Y336500D01*
X525788Y336250D01*
X525497Y336083D01*
X525205Y336000D01*
X524913D01*
X524622Y336083D01*
X524372Y336208D01*
X524163Y336375D01*
G01X522105Y336000D02*
Y338500D01*
X522605Y338000D01*
G01Y336000D02*
X521605D01*
G01X519005D02*
Y338500D01*
X519505Y338000D01*
G01Y336000D02*
X518505D01*
G01X516822Y336375D02*
X516572Y336167D01*
X516280Y336042D01*
X515905Y336000D01*
X515530Y336083D01*
X515238Y336250D01*
X515030Y336542D01*
X514988Y336875D01*
X515072Y337208D01*
X515280Y337417D01*
X515572Y337583D01*
X515863Y337625D01*
X516155Y337583D01*
X516530Y337417D01*
X516405Y338500D01*
X515280D01*
G01X513513Y336292D02*
X513222Y336083D01*
X512888Y336000D01*
X512555Y336083D01*
X512263Y336333D01*
X512055Y336708D01*
X511972Y337083D01*
Y337542D01*
X512055Y337917D01*
X512263Y338250D01*
X512513Y338417D01*
X512805Y338500D01*
X513138Y338417D01*
X513388Y338250D01*
X513555Y338000D01*
X513638Y337667D01*
X513555Y337375D01*
X513347Y337083D01*
X513097Y336917D01*
X512805Y336875D01*
X512472Y336958D01*
X512222Y337167D01*
X511972Y337542D01*
G01X530180Y383333D02*
X529847Y383125D01*
X529472Y383000D01*
X529138D01*
X528805Y383125D01*
X528555Y383333D01*
X528430Y383625D01*
X528513Y383917D01*
X528722Y384167D01*
X529097Y384333D01*
X529597Y384417D01*
X529888Y384583D01*
X530013Y384875D01*
X529930Y385167D01*
X529722Y385375D01*
X529430Y385500D01*
X529138D01*
X528847Y385417D01*
X528597Y385208D01*
G01X525288Y385292D02*
X525538Y385417D01*
X525830Y385500D01*
X526163D01*
X526538Y385375D01*
X526830Y385167D01*
X527038Y384917D01*
X527205Y384500D01*
X527247Y384125D01*
X527163Y383750D01*
X527038Y383500D01*
X526788Y383250D01*
X526497Y383083D01*
X526205Y383000D01*
X525913D01*
X525622Y383083D01*
X525372Y383208D01*
X525163Y383375D01*
G01X523105Y383000D02*
Y385500D01*
X523605Y385000D01*
G01Y383000D02*
X522605D01*
G01X520005D02*
Y385500D01*
X520505Y385000D01*
G01Y383000D02*
X519505D01*
G01X516905D02*
X516613Y383042D01*
X516280Y383167D01*
X516072Y383375D01*
X515988Y383667D01*
X516072Y383958D01*
X516322Y384208D01*
X516697Y384333D01*
X517113D01*
X517363Y384417D01*
X517572Y384625D01*
X517655Y384917D01*
X517530Y385208D01*
X517238Y385417D01*
X516905Y385500D01*
X516572Y385417D01*
X516280Y385208D01*
X516155Y384917D01*
X516238Y384625D01*
X516447Y384417D01*
X516697Y384333D01*
X517113D01*
X517488Y384208D01*
X517738Y383958D01*
X517822Y383667D01*
X517738Y383375D01*
X517530Y383167D01*
X517197Y383042D01*
X516905Y383000D01*
G01X513305D02*
Y385500D01*
X514847Y383708D01*
X512763D01*
G01X536180Y370833D02*
X535847Y370625D01*
X535472Y370500D01*
X535138D01*
X534805Y370625D01*
X534555Y370833D01*
X534430Y371125D01*
X534513Y371417D01*
X534722Y371667D01*
X535097Y371833D01*
X535597Y371917D01*
X535888Y372083D01*
X536013Y372375D01*
X535930Y372667D01*
X535722Y372875D01*
X535430Y373000D01*
X535138D01*
X534847Y372917D01*
X534597Y372708D01*
G01X531288Y372792D02*
X531538Y372917D01*
X531830Y373000D01*
X532163D01*
X532538Y372875D01*
X532830Y372667D01*
X533038Y372417D01*
X533205Y372000D01*
X533247Y371625D01*
X533163Y371250D01*
X533038Y371000D01*
X532788Y370750D01*
X532497Y370583D01*
X532205Y370500D01*
X531913D01*
X531622Y370583D01*
X531372Y370708D01*
X531163Y370875D01*
G01X529105Y370500D02*
Y373000D01*
X529605Y372500D01*
G01Y370500D02*
X528605D01*
G01X526005D02*
Y373000D01*
X526505Y372500D01*
G01Y370500D02*
X525505D01*
G01X523697Y371542D02*
X523405Y371833D01*
X523155Y372000D01*
X522822Y372083D01*
X522530Y372000D01*
X522322Y371833D01*
X522155Y371583D01*
X522113Y371292D01*
X522155Y371042D01*
X522322Y370792D01*
X522572Y370583D01*
X522863Y370500D01*
X523197Y370583D01*
X523488Y370833D01*
X523655Y371208D01*
X523697Y371625D01*
X523613Y372167D01*
X523488Y372458D01*
X523280Y372750D01*
X522988Y372958D01*
X522697Y373000D01*
X522405Y372917D01*
X522197Y372708D01*
G01X520597Y371542D02*
X520305Y371833D01*
X520055Y372000D01*
X519722Y372083D01*
X519430Y372000D01*
X519222Y371833D01*
X519055Y371583D01*
X519013Y371292D01*
X519055Y371042D01*
X519222Y370792D01*
X519472Y370583D01*
X519763Y370500D01*
X520097Y370583D01*
X520388Y370833D01*
X520555Y371208D01*
X520597Y371625D01*
X520513Y372167D01*
X520388Y372458D01*
X520180Y372750D01*
X519888Y372958D01*
X519597Y373000D01*
X519305Y372917D01*
X519097Y372708D01*
G01X536180Y375333D02*
X535847Y375125D01*
X535472Y375000D01*
X535138D01*
X534805Y375125D01*
X534555Y375333D01*
X534430Y375625D01*
X534513Y375917D01*
X534722Y376167D01*
X535097Y376333D01*
X535597Y376417D01*
X535888Y376583D01*
X536013Y376875D01*
X535930Y377167D01*
X535722Y377375D01*
X535430Y377500D01*
X535138D01*
X534847Y377417D01*
X534597Y377208D01*
G01X531288Y377292D02*
X531538Y377417D01*
X531830Y377500D01*
X532163D01*
X532538Y377375D01*
X532830Y377167D01*
X533038Y376917D01*
X533205Y376500D01*
X533247Y376125D01*
X533163Y375750D01*
X533038Y375500D01*
X532788Y375250D01*
X532497Y375083D01*
X532205Y375000D01*
X531913D01*
X531622Y375083D01*
X531372Y375208D01*
X531163Y375375D01*
G01X529105Y375000D02*
Y377500D01*
X529605Y377000D01*
G01Y375000D02*
X528605D01*
G01X526005D02*
Y377500D01*
X526505Y377000D01*
G01Y375000D02*
X525505D01*
G01X523697Y376042D02*
X523405Y376333D01*
X523155Y376500D01*
X522822Y376583D01*
X522530Y376500D01*
X522322Y376333D01*
X522155Y376083D01*
X522113Y375792D01*
X522155Y375542D01*
X522322Y375292D01*
X522572Y375083D01*
X522863Y375000D01*
X523197Y375083D01*
X523488Y375333D01*
X523655Y375708D01*
X523697Y376125D01*
X523613Y376667D01*
X523488Y376958D01*
X523280Y377250D01*
X522988Y377458D01*
X522697Y377500D01*
X522405Y377417D01*
X522197Y377208D01*
G01X519805Y375000D02*
Y377500D01*
X520305Y377000D01*
G01Y375000D02*
X519305D01*
G01X529680Y399833D02*
X529347Y399625D01*
X528972Y399500D01*
X528638D01*
X528305Y399625D01*
X528055Y399833D01*
X527930Y400125D01*
X528013Y400417D01*
X528222Y400667D01*
X528597Y400833D01*
X529097Y400917D01*
X529388Y401083D01*
X529513Y401375D01*
X529430Y401667D01*
X529222Y401875D01*
X528930Y402000D01*
X528638D01*
X528347Y401917D01*
X528097Y401708D01*
G01X524788Y401792D02*
X525038Y401917D01*
X525330Y402000D01*
X525663D01*
X526038Y401875D01*
X526330Y401667D01*
X526538Y401417D01*
X526705Y401000D01*
X526747Y400625D01*
X526663Y400250D01*
X526538Y400000D01*
X526288Y399750D01*
X525997Y399583D01*
X525705Y399500D01*
X525413D01*
X525122Y399583D01*
X524872Y399708D01*
X524663Y399875D01*
G01X522605Y399500D02*
Y402000D01*
X523105Y401500D01*
G01Y399500D02*
X522105D01*
G01X519505D02*
Y402000D01*
X520005Y401500D01*
G01Y399500D02*
X519005D01*
G01X516405D02*
X516113Y399542D01*
X515780Y399667D01*
X515572Y399875D01*
X515488Y400167D01*
X515572Y400458D01*
X515822Y400708D01*
X516197Y400833D01*
X516613D01*
X516863Y400917D01*
X517072Y401125D01*
X517155Y401417D01*
X517030Y401708D01*
X516738Y401917D01*
X516405Y402000D01*
X516072Y401917D01*
X515780Y401708D01*
X515655Y401417D01*
X515738Y401125D01*
X515947Y400917D01*
X516197Y400833D01*
X516613D01*
X516988Y400708D01*
X517238Y400458D01*
X517322Y400167D01*
X517238Y399875D01*
X517030Y399667D01*
X516697Y399542D01*
X516405Y399500D01*
G01X514222Y400000D02*
X513972Y399708D01*
X513638Y399542D01*
X513263Y399500D01*
X512930Y399542D01*
X512597Y399750D01*
X512388Y400000D01*
X512347Y400250D01*
X512430Y400542D01*
X512722Y400750D01*
X513013Y400833D01*
X513388D01*
G01X513013D02*
X512763Y400958D01*
X512555Y401167D01*
X512472Y401417D01*
X512555Y401667D01*
X512763Y401875D01*
X513138Y402000D01*
X513513Y401958D01*
X513888Y401792D01*
G01X527130Y417833D02*
X526797Y417625D01*
X526422Y417500D01*
X526088D01*
X525755Y417625D01*
X525505Y417833D01*
X525380Y418125D01*
X525463Y418417D01*
X525672Y418667D01*
X526047Y418833D01*
X526547Y418917D01*
X526838Y419083D01*
X526963Y419375D01*
X526880Y419667D01*
X526672Y419875D01*
X526380Y420000D01*
X526088D01*
X525797Y419917D01*
X525547Y419708D01*
G01X523988Y417500D02*
Y420000D01*
X522947D01*
X522613Y419875D01*
X522405Y419708D01*
X522322Y419375D01*
X522405Y419042D01*
X522655Y418833D01*
X522947Y418708D01*
X523988D01*
G01X522947D02*
X522322Y417500D01*
G01X520138D02*
X520055Y418042D01*
X519930Y418500D01*
X519763Y418917D01*
X519555Y419375D01*
X519222Y420000D01*
X520888D01*
G01X517872Y417875D02*
X517622Y417667D01*
X517330Y417542D01*
X516955Y417500D01*
X516580Y417583D01*
X516288Y417750D01*
X516080Y418042D01*
X516038Y418375D01*
X516122Y418708D01*
X516330Y418917D01*
X516622Y419083D01*
X516913Y419125D01*
X517205Y419083D01*
X517580Y418917D01*
X517455Y420000D01*
X516330D01*
G01X513938Y417500D02*
X513855Y418042D01*
X513730Y418500D01*
X513563Y418917D01*
X513355Y419375D01*
X513022Y420000D01*
X514688D01*
G01X529180Y410333D02*
X528847Y410125D01*
X528472Y410000D01*
X528138D01*
X527805Y410125D01*
X527555Y410333D01*
X527430Y410625D01*
X527513Y410917D01*
X527722Y411167D01*
X528097Y411333D01*
X528597Y411417D01*
X528888Y411583D01*
X529013Y411875D01*
X528930Y412167D01*
X528722Y412375D01*
X528430Y412500D01*
X528138D01*
X527847Y412417D01*
X527597Y412208D01*
G01X524288Y412292D02*
X524538Y412417D01*
X524830Y412500D01*
X525163D01*
X525538Y412375D01*
X525830Y412167D01*
X526038Y411917D01*
X526205Y411500D01*
X526247Y411125D01*
X526163Y410750D01*
X526038Y410500D01*
X525788Y410250D01*
X525497Y410083D01*
X525205Y410000D01*
X524913D01*
X524622Y410083D01*
X524372Y410208D01*
X524163Y410375D01*
G01X522105Y410000D02*
Y412500D01*
X522605Y412000D01*
G01Y410000D02*
X521605D01*
G01X519005D02*
Y412500D01*
X519505Y412000D01*
G01Y410000D02*
X518505D01*
G01X515988D02*
X515905Y410542D01*
X515780Y411000D01*
X515613Y411417D01*
X515405Y411875D01*
X515072Y412500D01*
X516738D01*
G01X513597Y412083D02*
X513347Y412333D01*
X513055Y412458D01*
X512722Y412500D01*
X512305Y412417D01*
X512013Y412208D01*
X511930Y411958D01*
X511972Y411708D01*
X512138Y411500D01*
X512972Y411083D01*
X513347Y410792D01*
X513597Y410375D01*
X513680Y410000D01*
X511930D01*
G01X551475Y138833D02*
X551142Y138625D01*
X550767Y138500D01*
X550433D01*
X550100Y138625D01*
X549850Y138833D01*
X549725Y139125D01*
X549808Y139417D01*
X550017Y139667D01*
X550392Y139833D01*
X550892Y139917D01*
X551183Y140083D01*
X551308Y140375D01*
X551225Y140667D01*
X551017Y140875D01*
X550725Y141000D01*
X550433D01*
X550142Y140917D01*
X549892Y140708D01*
G01X547500Y138500D02*
X547833Y138542D01*
X548125Y138708D01*
X548375Y138958D01*
X548542Y139250D01*
X548625Y139583D01*
Y139917D01*
X548542Y140250D01*
X548375Y140542D01*
X548125Y140792D01*
X547833Y140958D01*
X547500Y141000D01*
X547167Y140958D01*
X546875Y140792D01*
X546625Y140542D01*
X546458Y140250D01*
X546375Y139917D01*
Y139583D01*
X546458Y139250D01*
X546625Y138958D01*
X546875Y138708D01*
X547167Y138542D01*
X547500Y138500D01*
G01X547167Y139167D02*
X546667Y138500D01*
G01X543900D02*
Y141000D01*
X545442Y139208D01*
X543358D01*
G01X528500Y131500D02*
Y145500D01*
G01X541500Y131500D02*
X528500D01*
G01X541500Y145500D02*
Y131500D01*
G01X528500Y145500D02*
X541500D01*
G01X547075Y154833D02*
X546742Y154625D01*
X546367Y154500D01*
X546033D01*
X545700Y154625D01*
X545450Y154833D01*
X545325Y155125D01*
X545408Y155417D01*
X545617Y155667D01*
X545992Y155833D01*
X546492Y155917D01*
X546783Y156083D01*
X546908Y156375D01*
X546825Y156667D01*
X546617Y156875D01*
X546325Y157000D01*
X546033D01*
X545742Y156917D01*
X545492Y156708D01*
G01X543933Y154500D02*
Y157000D01*
X542892D01*
X542558Y156875D01*
X542350Y156708D01*
X542267Y156375D01*
X542350Y156042D01*
X542600Y155833D01*
X542892Y155708D01*
X543933D01*
G01X542892D02*
X542267Y154500D01*
G01X540792Y155542D02*
X540500Y155833D01*
X540250Y156000D01*
X539917Y156083D01*
X539625Y156000D01*
X539417Y155833D01*
X539250Y155583D01*
X539208Y155292D01*
X539250Y155042D01*
X539417Y154792D01*
X539667Y154583D01*
X539958Y154500D01*
X540292Y154583D01*
X540583Y154833D01*
X540750Y155208D01*
X540792Y155625D01*
X540708Y156167D01*
X540583Y156458D01*
X540375Y156750D01*
X540083Y156958D01*
X539792Y157000D01*
X539500Y156917D01*
X539292Y156708D01*
G01X537692Y155542D02*
X537400Y155833D01*
X537150Y156000D01*
X536817Y156083D01*
X536525Y156000D01*
X536317Y155833D01*
X536150Y155583D01*
X536108Y155292D01*
X536150Y155042D01*
X536317Y154792D01*
X536567Y154583D01*
X536858Y154500D01*
X537192Y154583D01*
X537483Y154833D01*
X537650Y155208D01*
X537692Y155625D01*
X537608Y156167D01*
X537483Y156458D01*
X537275Y156750D01*
X536983Y156958D01*
X536692Y157000D01*
X536400Y156917D01*
X536192Y156708D01*
G01X533800Y157000D02*
X534133Y156917D01*
X534383Y156708D01*
X534550Y156458D01*
X534675Y156125D01*
X534717Y155750D01*
X534675Y155375D01*
X534550Y155042D01*
X534383Y154792D01*
X534133Y154583D01*
X533800Y154500D01*
X533467Y154583D01*
X533217Y154792D01*
X533050Y155042D01*
X532925Y155375D01*
X532883Y155750D01*
X532925Y156125D01*
X533050Y156458D01*
X533217Y156708D01*
X533467Y156917D01*
X533800Y157000D01*
G01X529300Y146500D02*
Y150500D01*
X536700D01*
G01X550680Y383333D02*
X550347Y383125D01*
X549972Y383000D01*
X549638D01*
X549305Y383125D01*
X549055Y383333D01*
X548930Y383625D01*
X549013Y383917D01*
X549222Y384167D01*
X549597Y384333D01*
X550097Y384417D01*
X550388Y384583D01*
X550513Y384875D01*
X550430Y385167D01*
X550222Y385375D01*
X549930Y385500D01*
X549638D01*
X549347Y385417D01*
X549097Y385208D01*
G01X545788Y385292D02*
X546038Y385417D01*
X546330Y385500D01*
X546663D01*
X547038Y385375D01*
X547330Y385167D01*
X547538Y384917D01*
X547705Y384500D01*
X547747Y384125D01*
X547663Y383750D01*
X547538Y383500D01*
X547288Y383250D01*
X546997Y383083D01*
X546705Y383000D01*
X546413D01*
X546122Y383083D01*
X545872Y383208D01*
X545663Y383375D01*
G01X543605Y383000D02*
Y385500D01*
X544105Y385000D01*
G01Y383000D02*
X543105D01*
G01X540505D02*
Y385500D01*
X541005Y385000D01*
G01Y383000D02*
X540005D01*
G01X538197Y384042D02*
X537905Y384333D01*
X537655Y384500D01*
X537322Y384583D01*
X537030Y384500D01*
X536822Y384333D01*
X536655Y384083D01*
X536613Y383792D01*
X536655Y383542D01*
X536822Y383292D01*
X537072Y383083D01*
X537363Y383000D01*
X537697Y383083D01*
X537988Y383333D01*
X538155Y383708D01*
X538197Y384125D01*
X538113Y384667D01*
X537988Y384958D01*
X537780Y385250D01*
X537488Y385458D01*
X537197Y385500D01*
X536905Y385417D01*
X536697Y385208D01*
G01X535222Y383375D02*
X534972Y383167D01*
X534680Y383042D01*
X534305Y383000D01*
X533930Y383083D01*
X533638Y383250D01*
X533430Y383542D01*
X533388Y383875D01*
X533472Y384208D01*
X533680Y384417D01*
X533972Y384583D01*
X534263Y384625D01*
X534555Y384583D01*
X534930Y384417D01*
X534805Y385500D01*
X533680D01*
G01X542178Y970200D02*
X546178D01*
Y962800D01*
G01X562500Y153500D02*
X608000D01*
Y85500D01*
X544500D01*
Y134500D01*
X559000D01*
Y153500D01*
X562500D01*
G01X558297Y93748D02*
X557964Y93540D01*
X557589Y93415D01*
X557255D01*
X556922Y93540D01*
X556672Y93748D01*
X556547Y94040D01*
X556630Y94332D01*
X556839Y94582D01*
X557214Y94748D01*
X557714Y94832D01*
X558005Y94998D01*
X558130Y95290D01*
X558047Y95582D01*
X557839Y95790D01*
X557547Y95915D01*
X557255D01*
X556964Y95832D01*
X556714Y95623D01*
G01X554322Y95915D02*
Y93415D01*
G01X555280Y95915D02*
X553364D01*
G01X552055Y93415D02*
Y95915D01*
X551055D01*
X550722Y95790D01*
X550472Y95498D01*
X550389Y95165D01*
X550472Y94832D01*
X550680Y94582D01*
X551055Y94457D01*
X552055D01*
G01X548914Y95498D02*
X548664Y95748D01*
X548372Y95873D01*
X548039Y95915D01*
X547622Y95832D01*
X547330Y95623D01*
X547247Y95373D01*
X547289Y95123D01*
X547455Y94915D01*
X548289Y94498D01*
X548664Y94207D01*
X548914Y93790D01*
X548997Y93415D01*
X547247D01*
G01X564280Y99591D02*
X563947Y99383D01*
X563572Y99258D01*
X563238D01*
X562905Y99383D01*
X562655Y99591D01*
X562530Y99883D01*
X562613Y100175D01*
X562822Y100425D01*
X563197Y100591D01*
X563697Y100675D01*
X563988Y100841D01*
X564113Y101133D01*
X564030Y101425D01*
X563822Y101633D01*
X563530Y101758D01*
X563238D01*
X562947Y101675D01*
X562697Y101466D01*
G01X560305Y101758D02*
Y99258D01*
G01X561263Y101758D02*
X559347D01*
G01X558038Y99258D02*
Y101758D01*
X557038D01*
X556705Y101633D01*
X556455Y101341D01*
X556372Y101008D01*
X556455Y100675D01*
X556663Y100425D01*
X557038Y100300D01*
X558038D01*
G01X553605Y99258D02*
Y101758D01*
X555147Y99966D01*
X553063D01*
G01X568454Y106333D02*
X568121Y106125D01*
X567746Y106000D01*
X567412D01*
X567079Y106125D01*
X566829Y106333D01*
X566704Y106625D01*
X566787Y106917D01*
X566996Y107167D01*
X567371Y107333D01*
X567871Y107417D01*
X568162Y107583D01*
X568287Y107875D01*
X568204Y108167D01*
X567996Y108375D01*
X567704Y108500D01*
X567412D01*
X567121Y108417D01*
X566871Y108208D01*
G01X564479Y108500D02*
Y106000D01*
G01X565437Y108500D02*
X563521D01*
G01X562212Y106000D02*
Y108500D01*
X561212D01*
X560879Y108375D01*
X560629Y108083D01*
X560546Y107750D01*
X560629Y107417D01*
X560837Y107167D01*
X561212Y107042D01*
X562212D01*
G01X559071D02*
X558779Y107333D01*
X558529Y107500D01*
X558196Y107583D01*
X557904Y107500D01*
X557696Y107333D01*
X557529Y107083D01*
X557487Y106792D01*
X557529Y106542D01*
X557696Y106292D01*
X557946Y106083D01*
X558237Y106000D01*
X558571Y106083D01*
X558862Y106333D01*
X559029Y106708D01*
X559071Y107125D01*
X558987Y107667D01*
X558862Y107958D01*
X558654Y108250D01*
X558362Y108458D01*
X558071Y108500D01*
X557779Y108417D01*
X557571Y108208D01*
G01X568004Y111833D02*
X567671Y111625D01*
X567296Y111500D01*
X566962D01*
X566629Y111625D01*
X566379Y111833D01*
X566254Y112125D01*
X566337Y112417D01*
X566546Y112667D01*
X566921Y112833D01*
X567421Y112917D01*
X567712Y113083D01*
X567837Y113375D01*
X567754Y113667D01*
X567546Y113875D01*
X567254Y114000D01*
X566962D01*
X566671Y113917D01*
X566421Y113708D01*
G01X564029Y114000D02*
Y111500D01*
G01X564987Y114000D02*
X563071D01*
G01X561762Y111500D02*
Y114000D01*
X560762D01*
X560429Y113875D01*
X560179Y113583D01*
X560096Y113250D01*
X560179Y112917D01*
X560387Y112667D01*
X560762Y112542D01*
X561762D01*
G01X557829Y111500D02*
Y114000D01*
X558329Y113500D01*
G01Y111500D02*
X557329D01*
G01X554729Y114000D02*
X555062Y113917D01*
X555312Y113708D01*
X555479Y113458D01*
X555604Y113125D01*
X555646Y112750D01*
X555604Y112375D01*
X555479Y112042D01*
X555312Y111792D01*
X555062Y111583D01*
X554729Y111500D01*
X554396Y111583D01*
X554146Y111792D01*
X553979Y112042D01*
X553854Y112375D01*
X553812Y112750D01*
X553854Y113125D01*
X553979Y113458D01*
X554146Y113708D01*
X554396Y113917D01*
X554729Y114000D01*
G01X567284Y120823D02*
X566951Y120615D01*
X566576Y120490D01*
X566242D01*
X565909Y120615D01*
X565659Y120823D01*
X565534Y121115D01*
X565617Y121407D01*
X565826Y121657D01*
X566201Y121823D01*
X566701Y121907D01*
X566992Y122073D01*
X567117Y122365D01*
X567034Y122657D01*
X566826Y122865D01*
X566534Y122990D01*
X566242D01*
X565951Y122907D01*
X565701Y122698D01*
G01X563309Y122990D02*
Y120490D01*
G01X564267Y122990D02*
X562351D01*
G01X561042Y120490D02*
Y122990D01*
X560042D01*
X559709Y122865D01*
X559459Y122573D01*
X559376Y122240D01*
X559459Y121907D01*
X559667Y121657D01*
X560042Y121532D01*
X561042D01*
G01X557901Y122573D02*
X557651Y122823D01*
X557359Y122948D01*
X557026Y122990D01*
X556609Y122907D01*
X556317Y122698D01*
X556234Y122448D01*
X556276Y122198D01*
X556442Y121990D01*
X557276Y121573D01*
X557651Y121282D01*
X557901Y120865D01*
X557984Y120490D01*
X556234D01*
G01X554801Y122573D02*
X554551Y122823D01*
X554259Y122948D01*
X553926Y122990D01*
X553509Y122907D01*
X553217Y122698D01*
X553134Y122448D01*
X553176Y122198D01*
X553342Y121990D01*
X554176Y121573D01*
X554551Y121282D01*
X554801Y120865D01*
X554884Y120490D01*
X553134D01*
G01X569504Y130333D02*
X569171Y130125D01*
X568796Y130000D01*
X568462D01*
X568129Y130125D01*
X567879Y130333D01*
X567754Y130625D01*
X567837Y130917D01*
X568046Y131167D01*
X568421Y131333D01*
X568921Y131417D01*
X569212Y131583D01*
X569337Y131875D01*
X569254Y132167D01*
X569046Y132375D01*
X568754Y132500D01*
X568462D01*
X568171Y132417D01*
X567921Y132208D01*
G01X565529Y132500D02*
Y130000D01*
G01X566487Y132500D02*
X564571D01*
G01X563262Y130000D02*
Y132500D01*
X562262D01*
X561929Y132375D01*
X561679Y132083D01*
X561596Y131750D01*
X561679Y131417D01*
X561887Y131167D01*
X562262Y131042D01*
X563262D01*
G01X560121Y132083D02*
X559871Y132333D01*
X559579Y132458D01*
X559246Y132500D01*
X558829Y132417D01*
X558537Y132208D01*
X558454Y131958D01*
X558496Y131708D01*
X558662Y131500D01*
X559496Y131083D01*
X559871Y130792D01*
X560121Y130375D01*
X560204Y130000D01*
X558454D01*
G01X555729D02*
Y132500D01*
X557271Y130708D01*
X555187D01*
G01X556833Y162875D02*
X556625Y163208D01*
X556500Y163583D01*
Y163917D01*
X556625Y164250D01*
X556833Y164500D01*
X557125Y164625D01*
X557417Y164542D01*
X557667Y164333D01*
X557833Y163958D01*
X557917Y163458D01*
X558083Y163167D01*
X558375Y163042D01*
X558667Y163125D01*
X558875Y163333D01*
X559000Y163625D01*
Y163917D01*
X558917Y164208D01*
X558708Y164458D01*
G01X559000Y166850D02*
X556500D01*
G01X559000Y165892D02*
Y167808D01*
G01X556500Y169117D02*
X559000D01*
Y170117D01*
X558875Y170450D01*
X558583Y170700D01*
X558250Y170783D01*
X557917Y170700D01*
X557667Y170492D01*
X557542Y170117D01*
Y169117D01*
G01X556500Y173050D02*
X559000D01*
X558500Y172550D01*
G01X556500D02*
Y173550D01*
G01X558583Y175358D02*
X558833Y175608D01*
X558958Y175900D01*
X559000Y176233D01*
X558917Y176650D01*
X558708Y176942D01*
X558458Y177025D01*
X558208Y176983D01*
X558000Y176817D01*
X557583Y175983D01*
X557292Y175608D01*
X556875Y175358D01*
X556500Y175275D01*
Y177025D01*
G01Y179250D02*
X559000D01*
X558500Y178750D01*
G01X556500D02*
Y179750D01*
G01X551055Y349517D02*
X553555D01*
Y350558D01*
X553430Y350892D01*
X553263Y351100D01*
X552930Y351183D01*
X552597Y351100D01*
X552388Y350850D01*
X552263Y350558D01*
Y349517D01*
G01Y350558D02*
X551055Y351183D01*
G01Y353450D02*
X553555D01*
X553055Y352950D01*
G01X551055D02*
Y353950D01*
G01Y356467D02*
X551597Y356550D01*
X552055Y356675D01*
X552472Y356842D01*
X552930Y357050D01*
X553555Y357383D01*
Y355717D01*
G01X551430Y358733D02*
X551222Y358983D01*
X551097Y359275D01*
X551055Y359650D01*
X551138Y360025D01*
X551305Y360317D01*
X551597Y360525D01*
X551930Y360567D01*
X552263Y360483D01*
X552472Y360275D01*
X552638Y359983D01*
X552680Y359692D01*
X552638Y359400D01*
X552472Y359025D01*
X553555Y359150D01*
Y360275D01*
G01X554555Y339800D02*
X550555D01*
Y347200D01*
G01X555055Y349517D02*
X557555D01*
Y350558D01*
X557430Y350892D01*
X557263Y351100D01*
X556930Y351183D01*
X556597Y351100D01*
X556388Y350850D01*
X556263Y350558D01*
Y349517D01*
G01Y350558D02*
X555055Y351183D01*
G01Y353450D02*
X557555D01*
X557055Y352950D01*
G01X555055D02*
Y353950D01*
G01Y356467D02*
X555597Y356550D01*
X556055Y356675D01*
X556472Y356842D01*
X556930Y357050D01*
X557555Y357383D01*
Y355717D01*
G01X556097Y358858D02*
X556388Y359150D01*
X556555Y359400D01*
X556638Y359733D01*
X556555Y360025D01*
X556388Y360233D01*
X556138Y360400D01*
X555847Y360442D01*
X555597Y360400D01*
X555347Y360233D01*
X555138Y359983D01*
X555055Y359692D01*
X555138Y359358D01*
X555388Y359067D01*
X555763Y358900D01*
X556180Y358858D01*
X556722Y358942D01*
X557013Y359067D01*
X557305Y359275D01*
X557513Y359567D01*
X557555Y359858D01*
X557472Y360150D01*
X557263Y360358D01*
G01X558555Y339800D02*
X554555D01*
Y347200D01*
G01X547055Y349517D02*
X549555D01*
Y350558D01*
X549430Y350892D01*
X549263Y351100D01*
X548930Y351183D01*
X548597Y351100D01*
X548388Y350850D01*
X548263Y350558D01*
Y349517D01*
G01Y350558D02*
X547055Y351183D01*
G01X547430Y352533D02*
X547222Y352783D01*
X547097Y353075D01*
X547055Y353450D01*
X547138Y353825D01*
X547305Y354117D01*
X547597Y354325D01*
X547930Y354367D01*
X548263Y354283D01*
X548472Y354075D01*
X548638Y353783D01*
X548680Y353492D01*
X548638Y353200D01*
X548472Y352825D01*
X549555Y352950D01*
Y354075D01*
G01X547347Y355842D02*
X547138Y356133D01*
X547055Y356467D01*
X547138Y356800D01*
X547388Y357092D01*
X547763Y357300D01*
X548138Y357383D01*
X548597D01*
X548972Y357300D01*
X549305Y357092D01*
X549472Y356842D01*
X549555Y356550D01*
X549472Y356217D01*
X549305Y355967D01*
X549055Y355800D01*
X548722Y355717D01*
X548430Y355800D01*
X548138Y356008D01*
X547972Y356258D01*
X547930Y356550D01*
X548013Y356883D01*
X548222Y357133D01*
X548597Y357383D01*
G01X547055Y359567D02*
X547597Y359650D01*
X548055Y359775D01*
X548472Y359942D01*
X548930Y360150D01*
X549555Y360483D01*
Y358817D01*
G01X546555Y347200D02*
X550555D01*
Y339800D01*
G01X552955Y373600D02*
X556955D01*
Y366200D01*
G01Y373600D02*
X560955D01*
Y366200D01*
G01X548178Y958517D02*
X550678D01*
Y959558D01*
X550553Y959892D01*
X550386Y960100D01*
X550053Y960183D01*
X549720Y960100D01*
X549511Y959850D01*
X549386Y959558D01*
Y958517D01*
G01Y959558D02*
X548178Y960183D01*
G01Y962450D02*
X550678D01*
X550178Y961950D01*
G01X548178D02*
Y962950D01*
G01Y966050D02*
X550678D01*
X548886Y964508D01*
Y966592D01*
G01X548178Y968650D02*
X548220Y968942D01*
X548345Y969275D01*
X548553Y969483D01*
X548845Y969567D01*
X549136Y969483D01*
X549386Y969233D01*
X549511Y968858D01*
Y968442D01*
X549595Y968192D01*
X549803Y967983D01*
X550095Y967900D01*
X550386Y968025D01*
X550595Y968317D01*
X550678Y968650D01*
X550595Y968983D01*
X550386Y969275D01*
X550095Y969400D01*
X549803Y969317D01*
X549595Y969108D01*
X549511Y968858D01*
Y968442D01*
X549386Y968067D01*
X549136Y967817D01*
X548845Y967733D01*
X548553Y967817D01*
X548345Y968025D01*
X548220Y968358D01*
X548178Y968650D01*
G01X581125Y88333D02*
X580792Y88125D01*
X580417Y88000D01*
X580083D01*
X579750Y88125D01*
X579500Y88333D01*
X579375Y88625D01*
X579458Y88917D01*
X579667Y89167D01*
X580042Y89333D01*
X580542Y89417D01*
X580833Y89583D01*
X580958Y89875D01*
X580875Y90167D01*
X580667Y90375D01*
X580375Y90500D01*
X580083D01*
X579792Y90417D01*
X579542Y90208D01*
G01X577150Y90500D02*
Y88000D01*
G01X578108Y90500D02*
X576192D01*
G01X574883Y88000D02*
Y90500D01*
X573883D01*
X573550Y90375D01*
X573300Y90083D01*
X573217Y89750D01*
X573300Y89417D01*
X573508Y89167D01*
X573883Y89042D01*
X574883D01*
G01X570950Y88000D02*
Y90500D01*
X571450Y90000D01*
G01Y88000D02*
X570450D01*
G01X568767Y88500D02*
X568517Y88208D01*
X568183Y88042D01*
X567808Y88000D01*
X567475Y88042D01*
X567142Y88250D01*
X566933Y88500D01*
X566892Y88750D01*
X566975Y89042D01*
X567267Y89250D01*
X567558Y89333D01*
X567933D01*
G01X567558D02*
X567308Y89458D01*
X567100Y89667D01*
X567017Y89917D01*
X567100Y90167D01*
X567308Y90375D01*
X567683Y90500D01*
X568058Y90458D01*
X568433Y90292D01*
G01X565542Y89042D02*
X565250Y89333D01*
X565000Y89500D01*
X564667Y89583D01*
X564375Y89500D01*
X564167Y89333D01*
X564000Y89083D01*
X563958Y88792D01*
X564000Y88542D01*
X564167Y88292D01*
X564417Y88083D01*
X564708Y88000D01*
X565042Y88083D01*
X565333Y88333D01*
X565500Y88708D01*
X565542Y89125D01*
X565458Y89667D01*
X565333Y89958D01*
X565125Y90250D01*
X564833Y90458D01*
X564542Y90500D01*
X564250Y90417D01*
X564042Y90208D01*
G01X585504Y92833D02*
X585171Y92625D01*
X584796Y92500D01*
X584462D01*
X584129Y92625D01*
X583879Y92833D01*
X583754Y93125D01*
X583837Y93417D01*
X584046Y93667D01*
X584421Y93833D01*
X584921Y93917D01*
X585212Y94083D01*
X585337Y94375D01*
X585254Y94667D01*
X585046Y94875D01*
X584754Y95000D01*
X584462D01*
X584171Y94917D01*
X583921Y94708D01*
G01X581529Y95000D02*
Y92500D01*
G01X582487Y95000D02*
X580571D01*
G01X579262Y92500D02*
Y95000D01*
X578262D01*
X577929Y94875D01*
X577679Y94583D01*
X577596Y94250D01*
X577679Y93917D01*
X577887Y93667D01*
X578262Y93542D01*
X579262D01*
G01X575329Y92500D02*
Y95000D01*
X575829Y94500D01*
G01Y92500D02*
X574829D01*
G01X572229D02*
Y95000D01*
X572729Y94500D01*
G01Y92500D02*
X571729D01*
G01X589004Y102833D02*
X588671Y102625D01*
X588296Y102500D01*
X587962D01*
X587629Y102625D01*
X587379Y102833D01*
X587254Y103125D01*
X587337Y103417D01*
X587546Y103667D01*
X587921Y103833D01*
X588421Y103917D01*
X588712Y104083D01*
X588837Y104375D01*
X588754Y104667D01*
X588546Y104875D01*
X588254Y105000D01*
X587962D01*
X587671Y104917D01*
X587421Y104708D01*
G01X585029Y105000D02*
Y102500D01*
G01X585987Y105000D02*
X584071D01*
G01X582762Y102500D02*
Y105000D01*
X581762D01*
X581429Y104875D01*
X581179Y104583D01*
X581096Y104250D01*
X581179Y103917D01*
X581387Y103667D01*
X581762Y103542D01*
X582762D01*
G01X579746Y102875D02*
X579496Y102667D01*
X579204Y102542D01*
X578829Y102500D01*
X578454Y102583D01*
X578162Y102750D01*
X577954Y103042D01*
X577912Y103375D01*
X577996Y103708D01*
X578204Y103917D01*
X578496Y104083D01*
X578787Y104125D01*
X579079Y104083D01*
X579454Y103917D01*
X579329Y105000D01*
X578204D01*
G01X575229Y102500D02*
Y105000D01*
X576771Y103208D01*
X574687D01*
G01X589054Y97833D02*
X588721Y97625D01*
X588346Y97500D01*
X588012D01*
X587679Y97625D01*
X587429Y97833D01*
X587304Y98125D01*
X587387Y98417D01*
X587596Y98667D01*
X587971Y98833D01*
X588471Y98917D01*
X588762Y99083D01*
X588887Y99375D01*
X588804Y99667D01*
X588596Y99875D01*
X588304Y100000D01*
X588012D01*
X587721Y99917D01*
X587471Y99708D01*
G01X585079Y100000D02*
Y97500D01*
G01X586037Y100000D02*
X584121D01*
G01X582812Y97500D02*
Y100000D01*
X581812D01*
X581479Y99875D01*
X581229Y99583D01*
X581146Y99250D01*
X581229Y98917D01*
X581437Y98667D01*
X581812Y98542D01*
X582812D01*
G01X578879Y97500D02*
Y100000D01*
X579379Y99500D01*
G01Y97500D02*
X578379D01*
G01X576696Y98000D02*
X576446Y97708D01*
X576112Y97542D01*
X575737Y97500D01*
X575404Y97542D01*
X575071Y97750D01*
X574862Y98000D01*
X574821Y98250D01*
X574904Y98542D01*
X575196Y98750D01*
X575487Y98833D01*
X575862D01*
G01X575487D02*
X575237Y98958D01*
X575029Y99167D01*
X574946Y99417D01*
X575029Y99667D01*
X575237Y99875D01*
X575612Y100000D01*
X575987Y99958D01*
X576362Y99792D01*
G01X573596Y97875D02*
X573346Y97667D01*
X573054Y97542D01*
X572679Y97500D01*
X572304Y97583D01*
X572012Y97750D01*
X571804Y98042D01*
X571762Y98375D01*
X571846Y98708D01*
X572054Y98917D01*
X572346Y99083D01*
X572637Y99125D01*
X572929Y99083D01*
X573304Y98917D01*
X573179Y100000D01*
X572054D01*
G01X585504Y121333D02*
X585171Y121125D01*
X584796Y121000D01*
X584462D01*
X584129Y121125D01*
X583879Y121333D01*
X583754Y121625D01*
X583837Y121917D01*
X584046Y122167D01*
X584421Y122333D01*
X584921Y122417D01*
X585212Y122583D01*
X585337Y122875D01*
X585254Y123167D01*
X585046Y123375D01*
X584754Y123500D01*
X584462D01*
X584171Y123417D01*
X583921Y123208D01*
G01X581529Y123500D02*
Y121000D01*
G01X582487Y123500D02*
X580571D01*
G01X579262Y121000D02*
Y123500D01*
X578262D01*
X577929Y123375D01*
X577679Y123083D01*
X577596Y122750D01*
X577679Y122417D01*
X577887Y122167D01*
X578262Y122042D01*
X579262D01*
G01X575329Y121000D02*
Y123500D01*
X575829Y123000D01*
G01Y121000D02*
X574829D01*
G01X572312D02*
X572229Y121542D01*
X572104Y122000D01*
X571937Y122417D01*
X571729Y122875D01*
X571396Y123500D01*
X573062D01*
G01X576504Y116833D02*
X576171Y116625D01*
X575796Y116500D01*
X575462D01*
X575129Y116625D01*
X574879Y116833D01*
X574754Y117125D01*
X574837Y117417D01*
X575046Y117667D01*
X575421Y117833D01*
X575921Y117917D01*
X576212Y118083D01*
X576337Y118375D01*
X576254Y118667D01*
X576046Y118875D01*
X575754Y119000D01*
X575462D01*
X575171Y118917D01*
X574921Y118708D01*
G01X572529Y119000D02*
Y116500D01*
G01X573487Y119000D02*
X571571D01*
G01X570262Y116500D02*
Y119000D01*
X569262D01*
X568929Y118875D01*
X568679Y118583D01*
X568596Y118250D01*
X568679Y117917D01*
X568887Y117667D01*
X569262Y117542D01*
X570262D01*
G01X566329Y116500D02*
Y119000D01*
X566829Y118500D01*
G01Y116500D02*
X565829D01*
G01X563937Y116792D02*
X563646Y116583D01*
X563312Y116500D01*
X562979Y116583D01*
X562687Y116833D01*
X562479Y117208D01*
X562396Y117583D01*
Y118042D01*
X562479Y118417D01*
X562687Y118750D01*
X562937Y118917D01*
X563229Y119000D01*
X563562Y118917D01*
X563812Y118750D01*
X563979Y118500D01*
X564062Y118167D01*
X563979Y117875D01*
X563771Y117583D01*
X563521Y117417D01*
X563229Y117375D01*
X562896Y117458D01*
X562646Y117667D01*
X562396Y118042D01*
G01X586504Y107333D02*
X586171Y107125D01*
X585796Y107000D01*
X585462D01*
X585129Y107125D01*
X584879Y107333D01*
X584754Y107625D01*
X584837Y107917D01*
X585046Y108167D01*
X585421Y108333D01*
X585921Y108417D01*
X586212Y108583D01*
X586337Y108875D01*
X586254Y109167D01*
X586046Y109375D01*
X585754Y109500D01*
X585462D01*
X585171Y109417D01*
X584921Y109208D01*
G01X582529Y109500D02*
Y107000D01*
G01X583487Y109500D02*
X581571D01*
G01X580262Y107000D02*
Y109500D01*
X579262D01*
X578929Y109375D01*
X578679Y109083D01*
X578596Y108750D01*
X578679Y108417D01*
X578887Y108167D01*
X579262Y108042D01*
X580262D01*
G01X577121Y109083D02*
X576871Y109333D01*
X576579Y109458D01*
X576246Y109500D01*
X575829Y109417D01*
X575537Y109208D01*
X575454Y108958D01*
X575496Y108708D01*
X575662Y108500D01*
X576496Y108083D01*
X576871Y107792D01*
X577121Y107375D01*
X577204Y107000D01*
X575454D01*
G01X574146Y107500D02*
X573896Y107208D01*
X573562Y107042D01*
X573187Y107000D01*
X572854Y107042D01*
X572521Y107250D01*
X572312Y107500D01*
X572271Y107750D01*
X572354Y108042D01*
X572646Y108250D01*
X572937Y108333D01*
X573312D01*
G01X572937D02*
X572687Y108458D01*
X572479Y108667D01*
X572396Y108917D01*
X572479Y109167D01*
X572687Y109375D01*
X573062Y109500D01*
X573437Y109458D01*
X573812Y109292D01*
G01X581954Y112333D02*
X581621Y112125D01*
X581246Y112000D01*
X580912D01*
X580579Y112125D01*
X580329Y112333D01*
X580204Y112625D01*
X580287Y112917D01*
X580496Y113167D01*
X580871Y113333D01*
X581371Y113417D01*
X581662Y113583D01*
X581787Y113875D01*
X581704Y114167D01*
X581496Y114375D01*
X581204Y114500D01*
X580912D01*
X580621Y114417D01*
X580371Y114208D01*
G01X577979Y114500D02*
Y112000D01*
G01X578937Y114500D02*
X577021D01*
G01X575712Y112000D02*
Y114500D01*
X574712D01*
X574379Y114375D01*
X574129Y114083D01*
X574046Y113750D01*
X574129Y113417D01*
X574337Y113167D01*
X574712Y113042D01*
X575712D01*
G01X571779Y112000D02*
X571487Y112042D01*
X571154Y112167D01*
X570946Y112375D01*
X570862Y112667D01*
X570946Y112958D01*
X571196Y113208D01*
X571571Y113333D01*
X571987D01*
X572237Y113417D01*
X572446Y113625D01*
X572529Y113917D01*
X572404Y114208D01*
X572112Y114417D01*
X571779Y114500D01*
X571446Y114417D01*
X571154Y114208D01*
X571029Y113917D01*
X571112Y113625D01*
X571321Y113417D01*
X571571Y113333D01*
X571987D01*
X572362Y113208D01*
X572612Y112958D01*
X572696Y112667D01*
X572612Y112375D01*
X572404Y112167D01*
X572071Y112042D01*
X571779Y112000D01*
G01X584454Y130333D02*
X584121Y130125D01*
X583746Y130000D01*
X583412D01*
X583079Y130125D01*
X582829Y130333D01*
X582704Y130625D01*
X582787Y130917D01*
X582996Y131167D01*
X583371Y131333D01*
X583871Y131417D01*
X584162Y131583D01*
X584287Y131875D01*
X584204Y132167D01*
X583996Y132375D01*
X583704Y132500D01*
X583412D01*
X583121Y132417D01*
X582871Y132208D01*
G01X580479Y132500D02*
Y130000D01*
G01X581437Y132500D02*
X579521D01*
G01X578212Y130000D02*
Y132500D01*
X577212D01*
X576879Y132375D01*
X576629Y132083D01*
X576546Y131750D01*
X576629Y131417D01*
X576837Y131167D01*
X577212Y131042D01*
X578212D01*
G01X574279Y130000D02*
Y132500D01*
X574779Y132000D01*
G01Y130000D02*
X573779D01*
G01X579004Y125833D02*
X578671Y125625D01*
X578296Y125500D01*
X577962D01*
X577629Y125625D01*
X577379Y125833D01*
X577254Y126125D01*
X577337Y126417D01*
X577546Y126667D01*
X577921Y126833D01*
X578421Y126917D01*
X578712Y127083D01*
X578837Y127375D01*
X578754Y127667D01*
X578546Y127875D01*
X578254Y128000D01*
X577962D01*
X577671Y127917D01*
X577421Y127708D01*
G01X575029Y128000D02*
Y125500D01*
G01X575987Y128000D02*
X574071D01*
G01X572762Y125500D02*
Y128000D01*
X571762D01*
X571429Y127875D01*
X571179Y127583D01*
X571096Y127250D01*
X571179Y126917D01*
X571387Y126667D01*
X571762Y126542D01*
X572762D01*
G01X569621Y127583D02*
X569371Y127833D01*
X569079Y127958D01*
X568746Y128000D01*
X568329Y127917D01*
X568037Y127708D01*
X567954Y127458D01*
X567996Y127208D01*
X568162Y127000D01*
X568996Y126583D01*
X569371Y126292D01*
X569621Y125875D01*
X569704Y125500D01*
X567954D01*
G01X565729Y128000D02*
X566062Y127917D01*
X566312Y127708D01*
X566479Y127458D01*
X566604Y127125D01*
X566646Y126750D01*
X566604Y126375D01*
X566479Y126042D01*
X566312Y125792D01*
X566062Y125583D01*
X565729Y125500D01*
X565396Y125583D01*
X565146Y125792D01*
X564979Y126042D01*
X564854Y126375D01*
X564812Y126750D01*
X564854Y127125D01*
X564979Y127458D01*
X565146Y127708D01*
X565396Y127917D01*
X565729Y128000D01*
G01X577504Y139333D02*
X577171Y139125D01*
X576796Y139000D01*
X576462D01*
X576129Y139125D01*
X575879Y139333D01*
X575754Y139625D01*
X575837Y139917D01*
X576046Y140167D01*
X576421Y140333D01*
X576921Y140417D01*
X577212Y140583D01*
X577337Y140875D01*
X577254Y141167D01*
X577046Y141375D01*
X576754Y141500D01*
X576462D01*
X576171Y141417D01*
X575921Y141208D01*
G01X574362Y139000D02*
Y141500D01*
X573321D01*
X572987Y141375D01*
X572779Y141208D01*
X572696Y140875D01*
X572779Y140542D01*
X573029Y140333D01*
X573321Y140208D01*
X574362D01*
G01X573321D02*
X572696Y139000D01*
G01X571346Y139375D02*
X571096Y139167D01*
X570804Y139042D01*
X570429Y139000D01*
X570054Y139083D01*
X569762Y139250D01*
X569554Y139542D01*
X569512Y139875D01*
X569596Y140208D01*
X569804Y140417D01*
X570096Y140583D01*
X570387Y140625D01*
X570679Y140583D01*
X571054Y140417D01*
X570929Y141500D01*
X569804D01*
G01X567329Y139000D02*
X567037Y139042D01*
X566704Y139167D01*
X566496Y139375D01*
X566412Y139667D01*
X566496Y139958D01*
X566746Y140208D01*
X567121Y140333D01*
X567537D01*
X567787Y140417D01*
X567996Y140625D01*
X568079Y140917D01*
X567954Y141208D01*
X567662Y141417D01*
X567329Y141500D01*
X566996Y141417D01*
X566704Y141208D01*
X566579Y140917D01*
X566662Y140625D01*
X566871Y140417D01*
X567121Y140333D01*
X567537D01*
X567912Y140208D01*
X568162Y139958D01*
X568246Y139667D01*
X568162Y139375D01*
X567954Y139167D01*
X567621Y139042D01*
X567329Y139000D01*
G01X563729D02*
Y141500D01*
X565271Y139708D01*
X563187D01*
G01X577504Y135333D02*
X577171Y135125D01*
X576796Y135000D01*
X576462D01*
X576129Y135125D01*
X575879Y135333D01*
X575754Y135625D01*
X575837Y135917D01*
X576046Y136167D01*
X576421Y136333D01*
X576921Y136417D01*
X577212Y136583D01*
X577337Y136875D01*
X577254Y137167D01*
X577046Y137375D01*
X576754Y137500D01*
X576462D01*
X576171Y137417D01*
X575921Y137208D01*
G01X574362Y135000D02*
Y137500D01*
X573321D01*
X572987Y137375D01*
X572779Y137208D01*
X572696Y136875D01*
X572779Y136542D01*
X573029Y136333D01*
X573321Y136208D01*
X574362D01*
G01X573321D02*
X572696Y135000D01*
G01X571346Y135375D02*
X571096Y135167D01*
X570804Y135042D01*
X570429Y135000D01*
X570054Y135083D01*
X569762Y135250D01*
X569554Y135542D01*
X569512Y135875D01*
X569596Y136208D01*
X569804Y136417D01*
X570096Y136583D01*
X570387Y136625D01*
X570679Y136583D01*
X571054Y136417D01*
X570929Y137500D01*
X569804D01*
G01X567329Y135000D02*
X567037Y135042D01*
X566704Y135167D01*
X566496Y135375D01*
X566412Y135667D01*
X566496Y135958D01*
X566746Y136208D01*
X567121Y136333D01*
X567537D01*
X567787Y136417D01*
X567996Y136625D01*
X568079Y136917D01*
X567954Y137208D01*
X567662Y137417D01*
X567329Y137500D01*
X566996Y137417D01*
X566704Y137208D01*
X566579Y136917D01*
X566662Y136625D01*
X566871Y136417D01*
X567121Y136333D01*
X567537D01*
X567912Y136208D01*
X568162Y135958D01*
X568246Y135667D01*
X568162Y135375D01*
X567954Y135167D01*
X567621Y135042D01*
X567329Y135000D01*
G01X564312D02*
X564229Y135542D01*
X564104Y136000D01*
X563937Y136417D01*
X563729Y136875D01*
X563396Y137500D01*
X565062D01*
G01X608000Y153500D02*
X638000D01*
Y280500D01*
X574500D01*
Y153500D01*
G01X577504Y148333D02*
X577171Y148125D01*
X576796Y148000D01*
X576462D01*
X576129Y148125D01*
X575879Y148333D01*
X575754Y148625D01*
X575837Y148917D01*
X576046Y149167D01*
X576421Y149333D01*
X576921Y149417D01*
X577212Y149583D01*
X577337Y149875D01*
X577254Y150167D01*
X577046Y150375D01*
X576754Y150500D01*
X576462D01*
X576171Y150417D01*
X575921Y150208D01*
G01X574362Y148000D02*
Y150500D01*
X573321D01*
X572987Y150375D01*
X572779Y150208D01*
X572696Y149875D01*
X572779Y149542D01*
X573029Y149333D01*
X573321Y149208D01*
X574362D01*
G01X573321D02*
X572696Y148000D01*
G01X571221Y149042D02*
X570929Y149333D01*
X570679Y149500D01*
X570346Y149583D01*
X570054Y149500D01*
X569846Y149333D01*
X569679Y149083D01*
X569637Y148792D01*
X569679Y148542D01*
X569846Y148292D01*
X570096Y148083D01*
X570387Y148000D01*
X570721Y148083D01*
X571012Y148333D01*
X571179Y148708D01*
X571221Y149125D01*
X571137Y149667D01*
X571012Y149958D01*
X570804Y150250D01*
X570512Y150458D01*
X570221Y150500D01*
X569929Y150417D01*
X569721Y150208D01*
G01X568121Y150083D02*
X567871Y150333D01*
X567579Y150458D01*
X567246Y150500D01*
X566829Y150417D01*
X566537Y150208D01*
X566454Y149958D01*
X566496Y149708D01*
X566662Y149500D01*
X567496Y149083D01*
X567871Y148792D01*
X568121Y148375D01*
X568204Y148000D01*
X566454D01*
G01X565021Y150083D02*
X564771Y150333D01*
X564479Y150458D01*
X564146Y150500D01*
X563729Y150417D01*
X563437Y150208D01*
X563354Y149958D01*
X563396Y149708D01*
X563562Y149500D01*
X564396Y149083D01*
X564771Y148792D01*
X565021Y148375D01*
X565104Y148000D01*
X563354D01*
G01X577504Y143833D02*
X577171Y143625D01*
X576796Y143500D01*
X576462D01*
X576129Y143625D01*
X575879Y143833D01*
X575754Y144125D01*
X575837Y144417D01*
X576046Y144667D01*
X576421Y144833D01*
X576921Y144917D01*
X577212Y145083D01*
X577337Y145375D01*
X577254Y145667D01*
X577046Y145875D01*
X576754Y146000D01*
X576462D01*
X576171Y145917D01*
X575921Y145708D01*
G01X574362Y143500D02*
Y146000D01*
X573321D01*
X572987Y145875D01*
X572779Y145708D01*
X572696Y145375D01*
X572779Y145042D01*
X573029Y144833D01*
X573321Y144708D01*
X574362D01*
G01X573321D02*
X572696Y143500D01*
G01X571221Y144542D02*
X570929Y144833D01*
X570679Y145000D01*
X570346Y145083D01*
X570054Y145000D01*
X569846Y144833D01*
X569679Y144583D01*
X569637Y144292D01*
X569679Y144042D01*
X569846Y143792D01*
X570096Y143583D01*
X570387Y143500D01*
X570721Y143583D01*
X571012Y143833D01*
X571179Y144208D01*
X571221Y144625D01*
X571137Y145167D01*
X571012Y145458D01*
X570804Y145750D01*
X570512Y145958D01*
X570221Y146000D01*
X569929Y145917D01*
X569721Y145708D01*
G01X568121Y145583D02*
X567871Y145833D01*
X567579Y145958D01*
X567246Y146000D01*
X566829Y145917D01*
X566537Y145708D01*
X566454Y145458D01*
X566496Y145208D01*
X566662Y145000D01*
X567496Y144583D01*
X567871Y144292D01*
X568121Y143875D01*
X568204Y143500D01*
X566454D01*
G01X565146Y143875D02*
X564896Y143667D01*
X564604Y143542D01*
X564229Y143500D01*
X563854Y143583D01*
X563562Y143750D01*
X563354Y144042D01*
X563312Y144375D01*
X563396Y144708D01*
X563604Y144917D01*
X563896Y145083D01*
X564187Y145125D01*
X564479Y145083D01*
X564854Y144917D01*
X564729Y146000D01*
X563604D01*
G01X567833Y158375D02*
X567625Y158708D01*
X567500Y159083D01*
Y159417D01*
X567625Y159750D01*
X567833Y160000D01*
X568125Y160125D01*
X568417Y160042D01*
X568667Y159833D01*
X568833Y159458D01*
X568917Y158958D01*
X569083Y158667D01*
X569375Y158542D01*
X569667Y158625D01*
X569875Y158833D01*
X570000Y159125D01*
Y159417D01*
X569917Y159708D01*
X569708Y159958D01*
G01X570000Y162350D02*
X567500D01*
G01X570000Y161392D02*
Y163308D01*
G01X567500Y164617D02*
X570000D01*
Y165617D01*
X569875Y165950D01*
X569583Y166200D01*
X569250Y166283D01*
X568917Y166200D01*
X568667Y165992D01*
X568542Y165617D01*
Y164617D01*
G01X567500Y168550D02*
X570000D01*
X569500Y168050D01*
G01X567500D02*
Y169050D01*
G01Y171650D02*
X570000D01*
X569500Y171150D01*
G01X567500D02*
Y172150D01*
G01Y174750D02*
X567542Y175042D01*
X567667Y175375D01*
X567875Y175583D01*
X568167Y175667D01*
X568458Y175583D01*
X568708Y175333D01*
X568833Y174958D01*
Y174542D01*
X568917Y174292D01*
X569125Y174083D01*
X569417Y174000D01*
X569708Y174125D01*
X569917Y174417D01*
X570000Y174750D01*
X569917Y175083D01*
X569708Y175375D01*
X569417Y175500D01*
X569125Y175417D01*
X568917Y175208D01*
X568833Y174958D01*
Y174542D01*
X568708Y174167D01*
X568458Y173917D01*
X568167Y173833D01*
X567875Y173917D01*
X567667Y174125D01*
X567542Y174458D01*
X567500Y174750D01*
G01X563233Y175275D02*
X563025Y175608D01*
X562900Y175983D01*
Y176317D01*
X563025Y176650D01*
X563233Y176900D01*
X563525Y177025D01*
X563817Y176942D01*
X564067Y176733D01*
X564233Y176358D01*
X564317Y175858D01*
X564483Y175567D01*
X564775Y175442D01*
X565067Y175525D01*
X565275Y175733D01*
X565400Y176025D01*
Y176317D01*
X565317Y176608D01*
X565108Y176858D01*
G01X565400Y179250D02*
X562900D01*
G01X565400Y178292D02*
Y180208D01*
G01X562900Y181517D02*
X565400D01*
Y182517D01*
X565275Y182850D01*
X564983Y183100D01*
X564650Y183183D01*
X564317Y183100D01*
X564067Y182892D01*
X563942Y182517D01*
Y181517D01*
G01X562900Y185450D02*
X565400D01*
X564900Y184950D01*
G01X562900D02*
Y185950D01*
G01X564983Y187758D02*
X565233Y188008D01*
X565358Y188300D01*
X565400Y188633D01*
X565317Y189050D01*
X565108Y189342D01*
X564858Y189425D01*
X564608Y189383D01*
X564400Y189217D01*
X563983Y188383D01*
X563692Y188008D01*
X563275Y187758D01*
X562900Y187675D01*
Y189425D01*
G01X565400Y191650D02*
X565317Y191317D01*
X565108Y191067D01*
X564858Y190900D01*
X564525Y190775D01*
X564150Y190733D01*
X563775Y190775D01*
X563442Y190900D01*
X563192Y191067D01*
X562983Y191317D01*
X562900Y191650D01*
X562983Y191983D01*
X563192Y192233D01*
X563442Y192400D01*
X563775Y192525D01*
X564150Y192567D01*
X564525Y192525D01*
X564858Y192400D01*
X565108Y192233D01*
X565317Y191983D01*
X565400Y191650D01*
G01X576762Y259375D02*
X576554Y259708D01*
X576429Y260083D01*
Y260417D01*
X576554Y260750D01*
X576762Y261000D01*
X577054Y261125D01*
X577346Y261042D01*
X577596Y260833D01*
X577762Y260458D01*
X577846Y259958D01*
X578012Y259667D01*
X578304Y259542D01*
X578596Y259625D01*
X578804Y259833D01*
X578929Y260125D01*
Y260417D01*
X578846Y260708D01*
X578637Y260958D01*
G01X578721Y264267D02*
X578846Y264017D01*
X578929Y263725D01*
Y263392D01*
X578804Y263017D01*
X578596Y262725D01*
X578346Y262517D01*
X577929Y262350D01*
X577554Y262308D01*
X577179Y262392D01*
X576929Y262517D01*
X576679Y262767D01*
X576512Y263058D01*
X576429Y263350D01*
Y263642D01*
X576512Y263933D01*
X576637Y264183D01*
X576804Y264392D01*
G01X576429Y266450D02*
X578929D01*
X578429Y265950D01*
G01X576429D02*
Y266950D01*
G01X578929Y269550D02*
X578846Y269217D01*
X578637Y268967D01*
X578387Y268800D01*
X578054Y268675D01*
X577679Y268633D01*
X577304Y268675D01*
X576971Y268800D01*
X576721Y268967D01*
X576512Y269217D01*
X576429Y269550D01*
X576512Y269883D01*
X576721Y270133D01*
X576971Y270300D01*
X577304Y270425D01*
X577679Y270467D01*
X578054Y270425D01*
X578387Y270300D01*
X578637Y270133D01*
X578846Y269883D01*
X578929Y269550D01*
G01X578512Y271858D02*
X578762Y272108D01*
X578887Y272400D01*
X578929Y272733D01*
X578846Y273150D01*
X578637Y273442D01*
X578387Y273525D01*
X578137Y273483D01*
X577929Y273317D01*
X577512Y272483D01*
X577221Y272108D01*
X576804Y271858D01*
X576429Y271775D01*
Y273525D01*
G01X578929Y275750D02*
X578846Y275417D01*
X578637Y275167D01*
X578387Y275000D01*
X578054Y274875D01*
X577679Y274833D01*
X577304Y274875D01*
X576971Y275000D01*
X576721Y275167D01*
X576512Y275417D01*
X576429Y275750D01*
X576512Y276083D01*
X576721Y276333D01*
X576971Y276500D01*
X577304Y276625D01*
X577679Y276667D01*
X578054Y276625D01*
X578387Y276500D01*
X578637Y276333D01*
X578846Y276083D01*
X578929Y275750D01*
G01X563455Y362367D02*
X565955D01*
Y363408D01*
X565830Y363742D01*
X565663Y363950D01*
X565330Y364033D01*
X564997Y363950D01*
X564788Y363700D01*
X564663Y363408D01*
Y362367D01*
G01Y363408D02*
X563455Y364033D01*
G01X563830Y365383D02*
X563622Y365633D01*
X563497Y365925D01*
X563455Y366300D01*
X563538Y366675D01*
X563705Y366967D01*
X563997Y367175D01*
X564330Y367217D01*
X564663Y367133D01*
X564872Y366925D01*
X565038Y366633D01*
X565080Y366342D01*
X565038Y366050D01*
X564872Y365675D01*
X565955Y365800D01*
Y366925D01*
G01X563955Y368483D02*
X563663Y368733D01*
X563497Y369067D01*
X563455Y369442D01*
X563497Y369775D01*
X563705Y370108D01*
X563955Y370317D01*
X564205Y370358D01*
X564497Y370275D01*
X564705Y369983D01*
X564788Y369692D01*
Y369317D01*
G01Y369692D02*
X564913Y369942D01*
X565122Y370150D01*
X565372Y370233D01*
X565622Y370150D01*
X565830Y369942D01*
X565955Y369567D01*
X565913Y369192D01*
X565747Y368817D01*
G01X563455Y372500D02*
X565955D01*
X565455Y372000D01*
G01X563455D02*
Y373000D01*
G01Y376100D02*
X565955D01*
X564163Y374558D01*
Y376642D01*
G01X567455Y362367D02*
X569955D01*
Y363408D01*
X569830Y363742D01*
X569663Y363950D01*
X569330Y364033D01*
X568997Y363950D01*
X568788Y363700D01*
X568663Y363408D01*
Y362367D01*
G01Y363408D02*
X567455Y364033D01*
G01X567830Y365383D02*
X567622Y365633D01*
X567497Y365925D01*
X567455Y366300D01*
X567538Y366675D01*
X567705Y366967D01*
X567997Y367175D01*
X568330Y367217D01*
X568663Y367133D01*
X568872Y366925D01*
X569038Y366633D01*
X569080Y366342D01*
X569038Y366050D01*
X568872Y365675D01*
X569955Y365800D01*
Y366925D01*
G01X567955Y368483D02*
X567663Y368733D01*
X567497Y369067D01*
X567455Y369442D01*
X567497Y369775D01*
X567705Y370108D01*
X567955Y370317D01*
X568205Y370358D01*
X568497Y370275D01*
X568705Y369983D01*
X568788Y369692D01*
Y369317D01*
G01Y369692D02*
X568913Y369942D01*
X569122Y370150D01*
X569372Y370233D01*
X569622Y370150D01*
X569830Y369942D01*
X569955Y369567D01*
X569913Y369192D01*
X569747Y368817D01*
G01X567455Y372500D02*
X569955D01*
X569455Y372000D01*
G01X567455D02*
Y373000D01*
G01X567830Y374683D02*
X567622Y374933D01*
X567497Y375225D01*
X567455Y375600D01*
X567538Y375975D01*
X567705Y376267D01*
X567997Y376475D01*
X568330Y376517D01*
X568663Y376433D01*
X568872Y376225D01*
X569038Y375933D01*
X569080Y375642D01*
X569038Y375350D01*
X568872Y374975D01*
X569955Y375100D01*
Y376225D01*
G01X603125Y88333D02*
X602792Y88125D01*
X602417Y88000D01*
X602083D01*
X601750Y88125D01*
X601500Y88333D01*
X601375Y88625D01*
X601458Y88917D01*
X601667Y89167D01*
X602042Y89333D01*
X602542Y89417D01*
X602833Y89583D01*
X602958Y89875D01*
X602875Y90167D01*
X602667Y90375D01*
X602375Y90500D01*
X602083D01*
X601792Y90417D01*
X601542Y90208D01*
G01X599150Y90500D02*
Y88000D01*
G01X600108Y90500D02*
X598192D01*
G01X596883Y88000D02*
Y90500D01*
X595883D01*
X595550Y90375D01*
X595300Y90083D01*
X595217Y89750D01*
X595300Y89417D01*
X595508Y89167D01*
X595883Y89042D01*
X596883D01*
G01X592950Y88000D02*
Y90500D01*
X593450Y90000D01*
G01Y88000D02*
X592450D01*
G01X589350D02*
Y90500D01*
X590892Y88708D01*
X588808D01*
G01X587542Y90083D02*
X587292Y90333D01*
X587000Y90458D01*
X586667Y90500D01*
X586250Y90417D01*
X585958Y90208D01*
X585875Y89958D01*
X585917Y89708D01*
X586083Y89500D01*
X586917Y89083D01*
X587292Y88792D01*
X587542Y88375D01*
X587625Y88000D01*
X585875D01*
G01X602125Y112333D02*
X601792Y112125D01*
X601417Y112000D01*
X601083D01*
X600750Y112125D01*
X600500Y112333D01*
X600375Y112625D01*
X600458Y112917D01*
X600667Y113167D01*
X601042Y113333D01*
X601542Y113417D01*
X601833Y113583D01*
X601958Y113875D01*
X601875Y114167D01*
X601667Y114375D01*
X601375Y114500D01*
X601083D01*
X600792Y114417D01*
X600542Y114208D01*
G01X598150Y114500D02*
Y112000D01*
G01X599108Y114500D02*
X597192D01*
G01X595883Y112000D02*
Y114500D01*
X594883D01*
X594550Y114375D01*
X594300Y114083D01*
X594217Y113750D01*
X594300Y113417D01*
X594508Y113167D01*
X594883Y113042D01*
X595883D01*
G01X591950Y112000D02*
Y114500D01*
X592450Y114000D01*
G01Y112000D02*
X591450D01*
G01X589767Y112500D02*
X589517Y112208D01*
X589183Y112042D01*
X588808Y112000D01*
X588475Y112042D01*
X588142Y112250D01*
X587933Y112500D01*
X587892Y112750D01*
X587975Y113042D01*
X588267Y113250D01*
X588558Y113333D01*
X588933D01*
G01X588558D02*
X588308Y113458D01*
X588100Y113667D01*
X588017Y113917D01*
X588100Y114167D01*
X588308Y114375D01*
X588683Y114500D01*
X589058Y114458D01*
X589433Y114292D01*
G01X586542Y114083D02*
X586292Y114333D01*
X586000Y114458D01*
X585667Y114500D01*
X585250Y114417D01*
X584958Y114208D01*
X584875Y113958D01*
X584917Y113708D01*
X585083Y113500D01*
X585917Y113083D01*
X586292Y112792D01*
X586542Y112375D01*
X586625Y112000D01*
X584875D01*
G01X590862Y159375D02*
X590654Y159708D01*
X590529Y160083D01*
Y160417D01*
X590654Y160750D01*
X590862Y161000D01*
X591154Y161125D01*
X591446Y161042D01*
X591696Y160833D01*
X591862Y160458D01*
X591946Y159958D01*
X592112Y159667D01*
X592404Y159542D01*
X592696Y159625D01*
X592904Y159833D01*
X593029Y160125D01*
Y160417D01*
X592946Y160708D01*
X592737Y160958D01*
G01X592821Y164267D02*
X592946Y164017D01*
X593029Y163725D01*
Y163392D01*
X592904Y163017D01*
X592696Y162725D01*
X592446Y162517D01*
X592029Y162350D01*
X591654Y162308D01*
X591279Y162392D01*
X591029Y162517D01*
X590779Y162767D01*
X590612Y163058D01*
X590529Y163350D01*
Y163642D01*
X590612Y163933D01*
X590737Y164183D01*
X590904Y164392D01*
G01X590529Y166450D02*
X593029D01*
X592529Y165950D01*
G01X590529D02*
Y166950D01*
G01X593029Y169550D02*
X592946Y169217D01*
X592737Y168967D01*
X592487Y168800D01*
X592154Y168675D01*
X591779Y168633D01*
X591404Y168675D01*
X591071Y168800D01*
X590821Y168967D01*
X590612Y169217D01*
X590529Y169550D01*
X590612Y169883D01*
X590821Y170133D01*
X591071Y170300D01*
X591404Y170425D01*
X591779Y170467D01*
X592154Y170425D01*
X592487Y170300D01*
X592737Y170133D01*
X592946Y169883D01*
X593029Y169550D01*
G01X590904Y171733D02*
X590696Y171983D01*
X590571Y172275D01*
X590529Y172650D01*
X590612Y173025D01*
X590779Y173317D01*
X591071Y173525D01*
X591404Y173567D01*
X591737Y173483D01*
X591946Y173275D01*
X592112Y172983D01*
X592154Y172692D01*
X592112Y172400D01*
X591946Y172025D01*
X593029Y172150D01*
Y173275D01*
G01X590529Y175750D02*
X590571Y176042D01*
X590696Y176375D01*
X590904Y176583D01*
X591196Y176667D01*
X591487Y176583D01*
X591737Y176333D01*
X591862Y175958D01*
Y175542D01*
X591946Y175292D01*
X592154Y175083D01*
X592446Y175000D01*
X592737Y175125D01*
X592946Y175417D01*
X593029Y175750D01*
X592946Y176083D01*
X592737Y176375D01*
X592446Y176500D01*
X592154Y176417D01*
X591946Y176208D01*
X591862Y175958D01*
Y175542D01*
X591737Y175167D01*
X591487Y174917D01*
X591196Y174833D01*
X590904Y174917D01*
X590696Y175125D01*
X590571Y175458D01*
X590529Y175750D01*
G01X583362Y159375D02*
X583154Y159708D01*
X583029Y160083D01*
Y160417D01*
X583154Y160750D01*
X583362Y161000D01*
X583654Y161125D01*
X583946Y161042D01*
X584196Y160833D01*
X584362Y160458D01*
X584446Y159958D01*
X584612Y159667D01*
X584904Y159542D01*
X585196Y159625D01*
X585404Y159833D01*
X585529Y160125D01*
Y160417D01*
X585446Y160708D01*
X585237Y160958D01*
G01X585321Y164267D02*
X585446Y164017D01*
X585529Y163725D01*
Y163392D01*
X585404Y163017D01*
X585196Y162725D01*
X584946Y162517D01*
X584529Y162350D01*
X584154Y162308D01*
X583779Y162392D01*
X583529Y162517D01*
X583279Y162767D01*
X583112Y163058D01*
X583029Y163350D01*
Y163642D01*
X583112Y163933D01*
X583237Y164183D01*
X583404Y164392D01*
G01X583029Y166450D02*
X585529D01*
X585029Y165950D01*
G01X583029D02*
Y166950D01*
G01X585529Y169550D02*
X585446Y169217D01*
X585237Y168967D01*
X584987Y168800D01*
X584654Y168675D01*
X584279Y168633D01*
X583904Y168675D01*
X583571Y168800D01*
X583321Y168967D01*
X583112Y169217D01*
X583029Y169550D01*
X583112Y169883D01*
X583321Y170133D01*
X583571Y170300D01*
X583904Y170425D01*
X584279Y170467D01*
X584654Y170425D01*
X584987Y170300D01*
X585237Y170133D01*
X585446Y169883D01*
X585529Y169550D01*
G01X585112Y171858D02*
X585362Y172108D01*
X585487Y172400D01*
X585529Y172733D01*
X585446Y173150D01*
X585237Y173442D01*
X584987Y173525D01*
X584737Y173483D01*
X584529Y173317D01*
X584112Y172483D01*
X583821Y172108D01*
X583404Y171858D01*
X583029Y171775D01*
Y173525D01*
G01Y175667D02*
X583571Y175750D01*
X584029Y175875D01*
X584446Y176042D01*
X584904Y176250D01*
X585529Y176583D01*
Y174917D01*
G01X583262Y179375D02*
X583054Y179708D01*
X582929Y180083D01*
Y180417D01*
X583054Y180750D01*
X583262Y181000D01*
X583554Y181125D01*
X583846Y181042D01*
X584096Y180833D01*
X584262Y180458D01*
X584346Y179958D01*
X584512Y179667D01*
X584804Y179542D01*
X585096Y179625D01*
X585304Y179833D01*
X585429Y180125D01*
Y180417D01*
X585346Y180708D01*
X585137Y180958D01*
G01X585221Y184267D02*
X585346Y184017D01*
X585429Y183725D01*
Y183392D01*
X585304Y183017D01*
X585096Y182725D01*
X584846Y182517D01*
X584429Y182350D01*
X584054Y182308D01*
X583679Y182392D01*
X583429Y182517D01*
X583179Y182767D01*
X583012Y183058D01*
X582929Y183350D01*
Y183642D01*
X583012Y183933D01*
X583137Y184183D01*
X583304Y184392D01*
G01X582929Y186450D02*
X585429D01*
X584929Y185950D01*
G01X582929D02*
Y186950D01*
G01X585429Y189550D02*
X585346Y189217D01*
X585137Y188967D01*
X584887Y188800D01*
X584554Y188675D01*
X584179Y188633D01*
X583804Y188675D01*
X583471Y188800D01*
X583221Y188967D01*
X583012Y189217D01*
X582929Y189550D01*
X583012Y189883D01*
X583221Y190133D01*
X583471Y190300D01*
X583804Y190425D01*
X584179Y190467D01*
X584554Y190425D01*
X584887Y190300D01*
X585137Y190133D01*
X585346Y189883D01*
X585429Y189550D01*
G01X583971Y191858D02*
X584262Y192150D01*
X584429Y192400D01*
X584512Y192733D01*
X584429Y193025D01*
X584262Y193233D01*
X584012Y193400D01*
X583721Y193442D01*
X583471Y193400D01*
X583221Y193233D01*
X583012Y192983D01*
X582929Y192692D01*
X583012Y192358D01*
X583262Y192067D01*
X583637Y191900D01*
X584054Y191858D01*
X584596Y191942D01*
X584887Y192067D01*
X585179Y192275D01*
X585387Y192567D01*
X585429Y192858D01*
X585346Y193150D01*
X585137Y193358D01*
G01X582929Y195750D02*
X585429D01*
X584929Y195250D01*
G01X582929D02*
Y196250D01*
G01X590762Y179375D02*
X590554Y179708D01*
X590429Y180083D01*
Y180417D01*
X590554Y180750D01*
X590762Y181000D01*
X591054Y181125D01*
X591346Y181042D01*
X591596Y180833D01*
X591762Y180458D01*
X591846Y179958D01*
X592012Y179667D01*
X592304Y179542D01*
X592596Y179625D01*
X592804Y179833D01*
X592929Y180125D01*
Y180417D01*
X592846Y180708D01*
X592637Y180958D01*
G01X592721Y184267D02*
X592846Y184017D01*
X592929Y183725D01*
Y183392D01*
X592804Y183017D01*
X592596Y182725D01*
X592346Y182517D01*
X591929Y182350D01*
X591554Y182308D01*
X591179Y182392D01*
X590929Y182517D01*
X590679Y182767D01*
X590512Y183058D01*
X590429Y183350D01*
Y183642D01*
X590512Y183933D01*
X590637Y184183D01*
X590804Y184392D01*
G01X590429Y186450D02*
X592929D01*
X592429Y185950D01*
G01X590429D02*
Y186950D01*
G01X592929Y189550D02*
X592846Y189217D01*
X592637Y188967D01*
X592387Y188800D01*
X592054Y188675D01*
X591679Y188633D01*
X591304Y188675D01*
X590971Y188800D01*
X590721Y188967D01*
X590512Y189217D01*
X590429Y189550D01*
X590512Y189883D01*
X590721Y190133D01*
X590971Y190300D01*
X591304Y190425D01*
X591679Y190467D01*
X592054Y190425D01*
X592387Y190300D01*
X592637Y190133D01*
X592846Y189883D01*
X592929Y189550D01*
G01X592512Y191858D02*
X592762Y192108D01*
X592887Y192400D01*
X592929Y192733D01*
X592846Y193150D01*
X592637Y193442D01*
X592387Y193525D01*
X592137Y193483D01*
X591929Y193317D01*
X591512Y192483D01*
X591221Y192108D01*
X590804Y191858D01*
X590429Y191775D01*
Y193525D01*
G01Y195750D02*
X590471Y196042D01*
X590596Y196375D01*
X590804Y196583D01*
X591096Y196667D01*
X591387Y196583D01*
X591637Y196333D01*
X591762Y195958D01*
Y195542D01*
X591846Y195292D01*
X592054Y195083D01*
X592346Y195000D01*
X592637Y195125D01*
X592846Y195417D01*
X592929Y195750D01*
X592846Y196083D01*
X592637Y196375D01*
X592346Y196500D01*
X592054Y196417D01*
X591846Y196208D01*
X591762Y195958D01*
Y195542D01*
X591637Y195167D01*
X591387Y194917D01*
X591096Y194833D01*
X590804Y194917D01*
X590596Y195125D01*
X590471Y195458D01*
X590429Y195750D01*
G01X590762Y199375D02*
X590554Y199708D01*
X590429Y200083D01*
Y200417D01*
X590554Y200750D01*
X590762Y201000D01*
X591054Y201125D01*
X591346Y201042D01*
X591596Y200833D01*
X591762Y200458D01*
X591846Y199958D01*
X592012Y199667D01*
X592304Y199542D01*
X592596Y199625D01*
X592804Y199833D01*
X592929Y200125D01*
Y200417D01*
X592846Y200708D01*
X592637Y200958D01*
G01X592721Y204267D02*
X592846Y204017D01*
X592929Y203725D01*
Y203392D01*
X592804Y203017D01*
X592596Y202725D01*
X592346Y202517D01*
X591929Y202350D01*
X591554Y202308D01*
X591179Y202392D01*
X590929Y202517D01*
X590679Y202767D01*
X590512Y203058D01*
X590429Y203350D01*
Y203642D01*
X590512Y203933D01*
X590637Y204183D01*
X590804Y204392D01*
G01X590429Y206450D02*
X592929D01*
X592429Y205950D01*
G01X590429D02*
Y206950D01*
G01X592929Y209550D02*
X592846Y209217D01*
X592637Y208967D01*
X592387Y208800D01*
X592054Y208675D01*
X591679Y208633D01*
X591304Y208675D01*
X590971Y208800D01*
X590721Y208967D01*
X590512Y209217D01*
X590429Y209550D01*
X590512Y209883D01*
X590721Y210133D01*
X590971Y210300D01*
X591304Y210425D01*
X591679Y210467D01*
X592054Y210425D01*
X592387Y210300D01*
X592637Y210133D01*
X592846Y209883D01*
X592929Y209550D01*
G01X592512Y211858D02*
X592762Y212108D01*
X592887Y212400D01*
X592929Y212733D01*
X592846Y213150D01*
X592637Y213442D01*
X592387Y213525D01*
X592137Y213483D01*
X591929Y213317D01*
X591512Y212483D01*
X591221Y212108D01*
X590804Y211858D01*
X590429Y211775D01*
Y213525D01*
G01Y216250D02*
X592929D01*
X591137Y214708D01*
Y216792D01*
G01X583262Y199375D02*
X583054Y199708D01*
X582929Y200083D01*
Y200417D01*
X583054Y200750D01*
X583262Y201000D01*
X583554Y201125D01*
X583846Y201042D01*
X584096Y200833D01*
X584262Y200458D01*
X584346Y199958D01*
X584512Y199667D01*
X584804Y199542D01*
X585096Y199625D01*
X585304Y199833D01*
X585429Y200125D01*
Y200417D01*
X585346Y200708D01*
X585137Y200958D01*
G01X585221Y204267D02*
X585346Y204017D01*
X585429Y203725D01*
Y203392D01*
X585304Y203017D01*
X585096Y202725D01*
X584846Y202517D01*
X584429Y202350D01*
X584054Y202308D01*
X583679Y202392D01*
X583429Y202517D01*
X583179Y202767D01*
X583012Y203058D01*
X582929Y203350D01*
Y203642D01*
X583012Y203933D01*
X583137Y204183D01*
X583304Y204392D01*
G01X582929Y206450D02*
X585429D01*
X584929Y205950D01*
G01X582929D02*
Y206950D01*
G01X585429Y209550D02*
X585346Y209217D01*
X585137Y208967D01*
X584887Y208800D01*
X584554Y208675D01*
X584179Y208633D01*
X583804Y208675D01*
X583471Y208800D01*
X583221Y208967D01*
X583012Y209217D01*
X582929Y209550D01*
X583012Y209883D01*
X583221Y210133D01*
X583471Y210300D01*
X583804Y210425D01*
X584179Y210467D01*
X584554Y210425D01*
X584887Y210300D01*
X585137Y210133D01*
X585346Y209883D01*
X585429Y209550D01*
G01X585012Y211858D02*
X585262Y212108D01*
X585387Y212400D01*
X585429Y212733D01*
X585346Y213150D01*
X585137Y213442D01*
X584887Y213525D01*
X584637Y213483D01*
X584429Y213317D01*
X584012Y212483D01*
X583721Y212108D01*
X583304Y211858D01*
X582929Y211775D01*
Y213525D01*
G01X583304Y214833D02*
X583096Y215083D01*
X582971Y215375D01*
X582929Y215750D01*
X583012Y216125D01*
X583179Y216417D01*
X583471Y216625D01*
X583804Y216667D01*
X584137Y216583D01*
X584346Y216375D01*
X584512Y216083D01*
X584554Y215792D01*
X584512Y215500D01*
X584346Y215125D01*
X585429Y215250D01*
Y216375D01*
G01X590262Y219375D02*
X590054Y219708D01*
X589929Y220083D01*
Y220417D01*
X590054Y220750D01*
X590262Y221000D01*
X590554Y221125D01*
X590846Y221042D01*
X591096Y220833D01*
X591262Y220458D01*
X591346Y219958D01*
X591512Y219667D01*
X591804Y219542D01*
X592096Y219625D01*
X592304Y219833D01*
X592429Y220125D01*
Y220417D01*
X592346Y220708D01*
X592137Y220958D01*
G01X592221Y224267D02*
X592346Y224017D01*
X592429Y223725D01*
Y223392D01*
X592304Y223017D01*
X592096Y222725D01*
X591846Y222517D01*
X591429Y222350D01*
X591054Y222308D01*
X590679Y222392D01*
X590429Y222517D01*
X590179Y222767D01*
X590012Y223058D01*
X589929Y223350D01*
Y223642D01*
X590012Y223933D01*
X590137Y224183D01*
X590304Y224392D01*
G01X589929Y226450D02*
X592429D01*
X591929Y225950D01*
G01X589929D02*
Y226950D01*
G01X592429Y229550D02*
X592346Y229217D01*
X592137Y228967D01*
X591887Y228800D01*
X591554Y228675D01*
X591179Y228633D01*
X590804Y228675D01*
X590471Y228800D01*
X590221Y228967D01*
X590012Y229217D01*
X589929Y229550D01*
X590012Y229883D01*
X590221Y230133D01*
X590471Y230300D01*
X590804Y230425D01*
X591179Y230467D01*
X591554Y230425D01*
X591887Y230300D01*
X592137Y230133D01*
X592346Y229883D01*
X592429Y229550D01*
G01X592012Y231858D02*
X592262Y232108D01*
X592387Y232400D01*
X592429Y232733D01*
X592346Y233150D01*
X592137Y233442D01*
X591887Y233525D01*
X591637Y233483D01*
X591429Y233317D01*
X591012Y232483D01*
X590721Y232108D01*
X590304Y231858D01*
X589929Y231775D01*
Y233525D01*
G01X590429Y234833D02*
X590137Y235083D01*
X589971Y235417D01*
X589929Y235792D01*
X589971Y236125D01*
X590179Y236458D01*
X590429Y236667D01*
X590679Y236708D01*
X590971Y236625D01*
X591179Y236333D01*
X591262Y236042D01*
Y235667D01*
G01Y236042D02*
X591387Y236292D01*
X591596Y236500D01*
X591846Y236583D01*
X592096Y236500D01*
X592304Y236292D01*
X592429Y235917D01*
X592387Y235542D01*
X592221Y235167D01*
G01X582762Y218875D02*
X582554Y219208D01*
X582429Y219583D01*
Y219917D01*
X582554Y220250D01*
X582762Y220500D01*
X583054Y220625D01*
X583346Y220542D01*
X583596Y220333D01*
X583762Y219958D01*
X583846Y219458D01*
X584012Y219167D01*
X584304Y219042D01*
X584596Y219125D01*
X584804Y219333D01*
X584929Y219625D01*
Y219917D01*
X584846Y220208D01*
X584637Y220458D01*
G01X584721Y223767D02*
X584846Y223517D01*
X584929Y223225D01*
Y222892D01*
X584804Y222517D01*
X584596Y222225D01*
X584346Y222017D01*
X583929Y221850D01*
X583554Y221808D01*
X583179Y221892D01*
X582929Y222017D01*
X582679Y222267D01*
X582512Y222558D01*
X582429Y222850D01*
Y223142D01*
X582512Y223433D01*
X582637Y223683D01*
X582804Y223892D01*
G01X582429Y225950D02*
X584929D01*
X584429Y225450D01*
G01X582429D02*
Y226450D01*
G01X584929Y229050D02*
X584846Y228717D01*
X584637Y228467D01*
X584387Y228300D01*
X584054Y228175D01*
X583679Y228133D01*
X583304Y228175D01*
X582971Y228300D01*
X582721Y228467D01*
X582512Y228717D01*
X582429Y229050D01*
X582512Y229383D01*
X582721Y229633D01*
X582971Y229800D01*
X583304Y229925D01*
X583679Y229967D01*
X584054Y229925D01*
X584387Y229800D01*
X584637Y229633D01*
X584846Y229383D01*
X584929Y229050D01*
G01X582929Y231233D02*
X582637Y231483D01*
X582471Y231817D01*
X582429Y232192D01*
X582471Y232525D01*
X582679Y232858D01*
X582929Y233067D01*
X583179Y233108D01*
X583471Y233025D01*
X583679Y232733D01*
X583762Y232442D01*
Y232067D01*
G01Y232442D02*
X583887Y232692D01*
X584096Y232900D01*
X584346Y232983D01*
X584596Y232900D01*
X584804Y232692D01*
X584929Y232317D01*
X584887Y231942D01*
X584721Y231567D01*
G01X582429Y235750D02*
X584929D01*
X583137Y234208D01*
Y236292D01*
G01X578333Y238875D02*
X578125Y239208D01*
X578000Y239583D01*
Y239917D01*
X578125Y240250D01*
X578333Y240500D01*
X578625Y240625D01*
X578917Y240542D01*
X579167Y240333D01*
X579333Y239958D01*
X579417Y239458D01*
X579583Y239167D01*
X579875Y239042D01*
X580167Y239125D01*
X580375Y239333D01*
X580500Y239625D01*
Y239917D01*
X580417Y240208D01*
X580208Y240458D01*
G01X580292Y243767D02*
X580417Y243517D01*
X580500Y243225D01*
Y242892D01*
X580375Y242517D01*
X580167Y242225D01*
X579917Y242017D01*
X579500Y241850D01*
X579125Y241808D01*
X578750Y241892D01*
X578500Y242017D01*
X578250Y242267D01*
X578083Y242558D01*
X578000Y242850D01*
Y243142D01*
X578083Y243433D01*
X578208Y243683D01*
X578375Y243892D01*
G01X578000Y245950D02*
X580500D01*
X580000Y245450D01*
G01X578000D02*
Y246450D01*
G01X580500Y249050D02*
X580417Y248717D01*
X580208Y248467D01*
X579958Y248300D01*
X579625Y248175D01*
X579250Y248133D01*
X578875Y248175D01*
X578542Y248300D01*
X578292Y248467D01*
X578083Y248717D01*
X578000Y249050D01*
X578083Y249383D01*
X578292Y249633D01*
X578542Y249800D01*
X578875Y249925D01*
X579250Y249967D01*
X579625Y249925D01*
X579958Y249800D01*
X580208Y249633D01*
X580417Y249383D01*
X580500Y249050D01*
G01X578375Y251233D02*
X578167Y251483D01*
X578042Y251775D01*
X578000Y252150D01*
X578083Y252525D01*
X578250Y252817D01*
X578542Y253025D01*
X578875Y253067D01*
X579208Y252983D01*
X579417Y252775D01*
X579583Y252483D01*
X579625Y252192D01*
X579583Y251900D01*
X579417Y251525D01*
X580500Y251650D01*
Y252775D01*
G01X578000Y255750D02*
X580500D01*
X578708Y254208D01*
Y256292D01*
G01X590262Y238875D02*
X590054Y239208D01*
X589929Y239583D01*
Y239917D01*
X590054Y240250D01*
X590262Y240500D01*
X590554Y240625D01*
X590846Y240542D01*
X591096Y240333D01*
X591262Y239958D01*
X591346Y239458D01*
X591512Y239167D01*
X591804Y239042D01*
X592096Y239125D01*
X592304Y239333D01*
X592429Y239625D01*
Y239917D01*
X592346Y240208D01*
X592137Y240458D01*
G01X592221Y243767D02*
X592346Y243517D01*
X592429Y243225D01*
Y242892D01*
X592304Y242517D01*
X592096Y242225D01*
X591846Y242017D01*
X591429Y241850D01*
X591054Y241808D01*
X590679Y241892D01*
X590429Y242017D01*
X590179Y242267D01*
X590012Y242558D01*
X589929Y242850D01*
Y243142D01*
X590012Y243433D01*
X590137Y243683D01*
X590304Y243892D01*
G01X589929Y245950D02*
X592429D01*
X591929Y245450D01*
G01X589929D02*
Y246450D01*
G01X592429Y249050D02*
X592346Y248717D01*
X592137Y248467D01*
X591887Y248300D01*
X591554Y248175D01*
X591179Y248133D01*
X590804Y248175D01*
X590471Y248300D01*
X590221Y248467D01*
X590012Y248717D01*
X589929Y249050D01*
X590012Y249383D01*
X590221Y249633D01*
X590471Y249800D01*
X590804Y249925D01*
X591179Y249967D01*
X591554Y249925D01*
X591887Y249800D01*
X592137Y249633D01*
X592346Y249383D01*
X592429Y249050D01*
G01X590304Y251233D02*
X590096Y251483D01*
X589971Y251775D01*
X589929Y252150D01*
X590012Y252525D01*
X590179Y252817D01*
X590471Y253025D01*
X590804Y253067D01*
X591137Y252983D01*
X591346Y252775D01*
X591512Y252483D01*
X591554Y252192D01*
X591512Y251900D01*
X591346Y251525D01*
X592429Y251650D01*
Y252775D01*
G01X589929Y255167D02*
X590471Y255250D01*
X590929Y255375D01*
X591346Y255542D01*
X591804Y255750D01*
X592429Y256083D01*
Y254417D01*
G01X590762Y258875D02*
X590554Y259208D01*
X590429Y259583D01*
Y259917D01*
X590554Y260250D01*
X590762Y260500D01*
X591054Y260625D01*
X591346Y260542D01*
X591596Y260333D01*
X591762Y259958D01*
X591846Y259458D01*
X592012Y259167D01*
X592304Y259042D01*
X592596Y259125D01*
X592804Y259333D01*
X592929Y259625D01*
Y259917D01*
X592846Y260208D01*
X592637Y260458D01*
G01X592721Y263767D02*
X592846Y263517D01*
X592929Y263225D01*
Y262892D01*
X592804Y262517D01*
X592596Y262225D01*
X592346Y262017D01*
X591929Y261850D01*
X591554Y261808D01*
X591179Y261892D01*
X590929Y262017D01*
X590679Y262267D01*
X590512Y262558D01*
X590429Y262850D01*
Y263142D01*
X590512Y263433D01*
X590637Y263683D01*
X590804Y263892D01*
G01X590429Y265950D02*
X592929D01*
X592429Y265450D01*
G01X590429D02*
Y266450D01*
G01X592929Y269050D02*
X592846Y268717D01*
X592637Y268467D01*
X592387Y268300D01*
X592054Y268175D01*
X591679Y268133D01*
X591304Y268175D01*
X590971Y268300D01*
X590721Y268467D01*
X590512Y268717D01*
X590429Y269050D01*
X590512Y269383D01*
X590721Y269633D01*
X590971Y269800D01*
X591304Y269925D01*
X591679Y269967D01*
X592054Y269925D01*
X592387Y269800D01*
X592637Y269633D01*
X592846Y269383D01*
X592929Y269050D01*
G01X590429Y272150D02*
X592929D01*
X592429Y271650D01*
G01X590429D02*
Y272650D01*
G01Y275167D02*
X590971Y275250D01*
X591429Y275375D01*
X591846Y275542D01*
X592304Y275750D01*
X592929Y276083D01*
Y274417D01*
G01X585062Y258875D02*
X584854Y259208D01*
X584729Y259583D01*
Y259917D01*
X584854Y260250D01*
X585062Y260500D01*
X585354Y260625D01*
X585646Y260542D01*
X585896Y260333D01*
X586062Y259958D01*
X586146Y259458D01*
X586312Y259167D01*
X586604Y259042D01*
X586896Y259125D01*
X587104Y259333D01*
X587229Y259625D01*
Y259917D01*
X587146Y260208D01*
X586937Y260458D01*
G01X587021Y263767D02*
X587146Y263517D01*
X587229Y263225D01*
Y262892D01*
X587104Y262517D01*
X586896Y262225D01*
X586646Y262017D01*
X586229Y261850D01*
X585854Y261808D01*
X585479Y261892D01*
X585229Y262017D01*
X584979Y262267D01*
X584812Y262558D01*
X584729Y262850D01*
Y263142D01*
X584812Y263433D01*
X584937Y263683D01*
X585104Y263892D01*
G01X584729Y265950D02*
X587229D01*
X586729Y265450D01*
G01X584729D02*
Y266450D01*
G01X587229Y269050D02*
X587146Y268717D01*
X586937Y268467D01*
X586687Y268300D01*
X586354Y268175D01*
X585979Y268133D01*
X585604Y268175D01*
X585271Y268300D01*
X585021Y268467D01*
X584812Y268717D01*
X584729Y269050D01*
X584812Y269383D01*
X585021Y269633D01*
X585271Y269800D01*
X585604Y269925D01*
X585979Y269967D01*
X586354Y269925D01*
X586687Y269800D01*
X586937Y269633D01*
X587146Y269383D01*
X587229Y269050D01*
G01X585229Y271233D02*
X584937Y271483D01*
X584771Y271817D01*
X584729Y272192D01*
X584771Y272525D01*
X584979Y272858D01*
X585229Y273067D01*
X585479Y273108D01*
X585771Y273025D01*
X585979Y272733D01*
X586062Y272442D01*
Y272067D01*
G01Y272442D02*
X586187Y272692D01*
X586396Y272900D01*
X586646Y272983D01*
X586896Y272900D01*
X587104Y272692D01*
X587229Y272317D01*
X587187Y271942D01*
X587021Y271567D01*
G01X584729Y275167D02*
X585271Y275250D01*
X585729Y275375D01*
X586146Y275542D01*
X586604Y275750D01*
X587229Y276083D01*
Y274417D01*
G01X581047Y258925D02*
X580839Y259258D01*
X580714Y259633D01*
Y259967D01*
X580839Y260300D01*
X581047Y260550D01*
X581339Y260675D01*
X581631Y260592D01*
X581881Y260383D01*
X582047Y260008D01*
X582131Y259508D01*
X582297Y259217D01*
X582589Y259092D01*
X582881Y259175D01*
X583089Y259383D01*
X583214Y259675D01*
Y259967D01*
X583131Y260258D01*
X582922Y260508D01*
G01X583006Y263817D02*
X583131Y263567D01*
X583214Y263275D01*
Y262942D01*
X583089Y262567D01*
X582881Y262275D01*
X582631Y262067D01*
X582214Y261900D01*
X581839Y261858D01*
X581464Y261942D01*
X581214Y262067D01*
X580964Y262317D01*
X580797Y262608D01*
X580714Y262900D01*
Y263192D01*
X580797Y263483D01*
X580922Y263733D01*
X581089Y263942D01*
G01X580714Y266000D02*
X583214D01*
X582714Y265500D01*
G01X580714D02*
Y266500D01*
G01X583214Y269100D02*
X583131Y268767D01*
X582922Y268517D01*
X582672Y268350D01*
X582339Y268225D01*
X581964Y268183D01*
X581589Y268225D01*
X581256Y268350D01*
X581006Y268517D01*
X580797Y268767D01*
X580714Y269100D01*
X580797Y269433D01*
X581006Y269683D01*
X581256Y269850D01*
X581589Y269975D01*
X581964Y270017D01*
X582339Y269975D01*
X582672Y269850D01*
X582922Y269683D01*
X583131Y269433D01*
X583214Y269100D01*
G01X581214Y271283D02*
X580922Y271533D01*
X580756Y271867D01*
X580714Y272242D01*
X580756Y272575D01*
X580964Y272908D01*
X581214Y273117D01*
X581464Y273158D01*
X581756Y273075D01*
X581964Y272783D01*
X582047Y272492D01*
Y272117D01*
G01Y272492D02*
X582172Y272742D01*
X582381Y272950D01*
X582631Y273033D01*
X582881Y272950D01*
X583089Y272742D01*
X583214Y272367D01*
X583172Y271992D01*
X583006Y271617D01*
G01X580714Y275300D02*
X580756Y275592D01*
X580881Y275925D01*
X581089Y276133D01*
X581381Y276217D01*
X581672Y276133D01*
X581922Y275883D01*
X582047Y275508D01*
Y275092D01*
X582131Y274842D01*
X582339Y274633D01*
X582631Y274550D01*
X582922Y274675D01*
X583131Y274967D01*
X583214Y275300D01*
X583131Y275633D01*
X582922Y275925D01*
X582631Y276050D01*
X582339Y275967D01*
X582131Y275758D01*
X582047Y275508D01*
Y275092D01*
X581922Y274717D01*
X581672Y274467D01*
X581381Y274383D01*
X581089Y274467D01*
X580881Y274675D01*
X580756Y275008D01*
X580714Y275300D01*
G01X605862Y159375D02*
X605654Y159708D01*
X605529Y160083D01*
Y160417D01*
X605654Y160750D01*
X605862Y161000D01*
X606154Y161125D01*
X606446Y161042D01*
X606696Y160833D01*
X606862Y160458D01*
X606946Y159958D01*
X607112Y159667D01*
X607404Y159542D01*
X607696Y159625D01*
X607904Y159833D01*
X608029Y160125D01*
Y160417D01*
X607946Y160708D01*
X607737Y160958D01*
G01X607821Y164267D02*
X607946Y164017D01*
X608029Y163725D01*
Y163392D01*
X607904Y163017D01*
X607696Y162725D01*
X607446Y162517D01*
X607029Y162350D01*
X606654Y162308D01*
X606279Y162392D01*
X606029Y162517D01*
X605779Y162767D01*
X605612Y163058D01*
X605529Y163350D01*
Y163642D01*
X605612Y163933D01*
X605737Y164183D01*
X605904Y164392D01*
G01X605529Y166450D02*
X608029D01*
X607529Y165950D01*
G01X605529D02*
Y166950D01*
G01X608029Y169550D02*
X607946Y169217D01*
X607737Y168967D01*
X607487Y168800D01*
X607154Y168675D01*
X606779Y168633D01*
X606404Y168675D01*
X606071Y168800D01*
X605821Y168967D01*
X605612Y169217D01*
X605529Y169550D01*
X605612Y169883D01*
X605821Y170133D01*
X606071Y170300D01*
X606404Y170425D01*
X606779Y170467D01*
X607154Y170425D01*
X607487Y170300D01*
X607737Y170133D01*
X607946Y169883D01*
X608029Y169550D01*
G01X605904Y171733D02*
X605696Y171983D01*
X605571Y172275D01*
X605529Y172650D01*
X605612Y173025D01*
X605779Y173317D01*
X606071Y173525D01*
X606404Y173567D01*
X606737Y173483D01*
X606946Y173275D01*
X607112Y172983D01*
X607154Y172692D01*
X607112Y172400D01*
X606946Y172025D01*
X608029Y172150D01*
Y173275D01*
G01X607612Y174958D02*
X607862Y175208D01*
X607987Y175500D01*
X608029Y175833D01*
X607946Y176250D01*
X607737Y176542D01*
X607487Y176625D01*
X607237Y176583D01*
X607029Y176417D01*
X606612Y175583D01*
X606321Y175208D01*
X605904Y174958D01*
X605529Y174875D01*
Y176625D01*
G01X598362Y159375D02*
X598154Y159708D01*
X598029Y160083D01*
Y160417D01*
X598154Y160750D01*
X598362Y161000D01*
X598654Y161125D01*
X598946Y161042D01*
X599196Y160833D01*
X599362Y160458D01*
X599446Y159958D01*
X599612Y159667D01*
X599904Y159542D01*
X600196Y159625D01*
X600404Y159833D01*
X600529Y160125D01*
Y160417D01*
X600446Y160708D01*
X600237Y160958D01*
G01X600321Y164267D02*
X600446Y164017D01*
X600529Y163725D01*
Y163392D01*
X600404Y163017D01*
X600196Y162725D01*
X599946Y162517D01*
X599529Y162350D01*
X599154Y162308D01*
X598779Y162392D01*
X598529Y162517D01*
X598279Y162767D01*
X598112Y163058D01*
X598029Y163350D01*
Y163642D01*
X598112Y163933D01*
X598237Y164183D01*
X598404Y164392D01*
G01X598029Y166450D02*
X600529D01*
X600029Y165950D01*
G01X598029D02*
Y166950D01*
G01X600529Y169550D02*
X600446Y169217D01*
X600237Y168967D01*
X599987Y168800D01*
X599654Y168675D01*
X599279Y168633D01*
X598904Y168675D01*
X598571Y168800D01*
X598321Y168967D01*
X598112Y169217D01*
X598029Y169550D01*
X598112Y169883D01*
X598321Y170133D01*
X598571Y170300D01*
X598904Y170425D01*
X599279Y170467D01*
X599654Y170425D01*
X599987Y170300D01*
X600237Y170133D01*
X600446Y169883D01*
X600529Y169550D01*
G01X598529Y171733D02*
X598237Y171983D01*
X598071Y172317D01*
X598029Y172692D01*
X598071Y173025D01*
X598279Y173358D01*
X598529Y173567D01*
X598779Y173608D01*
X599071Y173525D01*
X599279Y173233D01*
X599362Y172942D01*
Y172567D01*
G01Y172942D02*
X599487Y173192D01*
X599696Y173400D01*
X599946Y173483D01*
X600196Y173400D01*
X600404Y173192D01*
X600529Y172817D01*
X600487Y172442D01*
X600321Y172067D01*
G01X600112Y174958D02*
X600362Y175208D01*
X600487Y175500D01*
X600529Y175833D01*
X600446Y176250D01*
X600237Y176542D01*
X599987Y176625D01*
X599737Y176583D01*
X599529Y176417D01*
X599112Y175583D01*
X598821Y175208D01*
X598404Y174958D01*
X598029Y174875D01*
Y176625D01*
G01X605762Y179375D02*
X605554Y179708D01*
X605429Y180083D01*
Y180417D01*
X605554Y180750D01*
X605762Y181000D01*
X606054Y181125D01*
X606346Y181042D01*
X606596Y180833D01*
X606762Y180458D01*
X606846Y179958D01*
X607012Y179667D01*
X607304Y179542D01*
X607596Y179625D01*
X607804Y179833D01*
X607929Y180125D01*
Y180417D01*
X607846Y180708D01*
X607637Y180958D01*
G01X607721Y184267D02*
X607846Y184017D01*
X607929Y183725D01*
Y183392D01*
X607804Y183017D01*
X607596Y182725D01*
X607346Y182517D01*
X606929Y182350D01*
X606554Y182308D01*
X606179Y182392D01*
X605929Y182517D01*
X605679Y182767D01*
X605512Y183058D01*
X605429Y183350D01*
Y183642D01*
X605512Y183933D01*
X605637Y184183D01*
X605804Y184392D01*
G01X605429Y186450D02*
X607929D01*
X607429Y185950D01*
G01X605429D02*
Y186950D01*
G01X607929Y189550D02*
X607846Y189217D01*
X607637Y188967D01*
X607387Y188800D01*
X607054Y188675D01*
X606679Y188633D01*
X606304Y188675D01*
X605971Y188800D01*
X605721Y188967D01*
X605512Y189217D01*
X605429Y189550D01*
X605512Y189883D01*
X605721Y190133D01*
X605971Y190300D01*
X606304Y190425D01*
X606679Y190467D01*
X607054Y190425D01*
X607387Y190300D01*
X607637Y190133D01*
X607846Y189883D01*
X607929Y189550D01*
G01X607512Y191858D02*
X607762Y192108D01*
X607887Y192400D01*
X607929Y192733D01*
X607846Y193150D01*
X607637Y193442D01*
X607387Y193525D01*
X607137Y193483D01*
X606929Y193317D01*
X606512Y192483D01*
X606221Y192108D01*
X605804Y191858D01*
X605429Y191775D01*
Y193525D01*
G01X606471Y194958D02*
X606762Y195250D01*
X606929Y195500D01*
X607012Y195833D01*
X606929Y196125D01*
X606762Y196333D01*
X606512Y196500D01*
X606221Y196542D01*
X605971Y196500D01*
X605721Y196333D01*
X605512Y196083D01*
X605429Y195792D01*
X605512Y195458D01*
X605762Y195167D01*
X606137Y195000D01*
X606554Y194958D01*
X607096Y195042D01*
X607387Y195167D01*
X607679Y195375D01*
X607887Y195667D01*
X607929Y195958D01*
X607846Y196250D01*
X607637Y196458D01*
G01X598262Y179375D02*
X598054Y179708D01*
X597929Y180083D01*
Y180417D01*
X598054Y180750D01*
X598262Y181000D01*
X598554Y181125D01*
X598846Y181042D01*
X599096Y180833D01*
X599262Y180458D01*
X599346Y179958D01*
X599512Y179667D01*
X599804Y179542D01*
X600096Y179625D01*
X600304Y179833D01*
X600429Y180125D01*
Y180417D01*
X600346Y180708D01*
X600137Y180958D01*
G01X600221Y184267D02*
X600346Y184017D01*
X600429Y183725D01*
Y183392D01*
X600304Y183017D01*
X600096Y182725D01*
X599846Y182517D01*
X599429Y182350D01*
X599054Y182308D01*
X598679Y182392D01*
X598429Y182517D01*
X598179Y182767D01*
X598012Y183058D01*
X597929Y183350D01*
Y183642D01*
X598012Y183933D01*
X598137Y184183D01*
X598304Y184392D01*
G01X597929Y186450D02*
X600429D01*
X599929Y185950D01*
G01X597929D02*
Y186950D01*
G01X600429Y189550D02*
X600346Y189217D01*
X600137Y188967D01*
X599887Y188800D01*
X599554Y188675D01*
X599179Y188633D01*
X598804Y188675D01*
X598471Y188800D01*
X598221Y188967D01*
X598012Y189217D01*
X597929Y189550D01*
X598012Y189883D01*
X598221Y190133D01*
X598471Y190300D01*
X598804Y190425D01*
X599179Y190467D01*
X599554Y190425D01*
X599887Y190300D01*
X600137Y190133D01*
X600346Y189883D01*
X600429Y189550D01*
G01X600012Y191858D02*
X600262Y192108D01*
X600387Y192400D01*
X600429Y192733D01*
X600346Y193150D01*
X600137Y193442D01*
X599887Y193525D01*
X599637Y193483D01*
X599429Y193317D01*
X599012Y192483D01*
X598721Y192108D01*
X598304Y191858D01*
X597929Y191775D01*
Y193525D01*
G01X598221Y195042D02*
X598012Y195333D01*
X597929Y195667D01*
X598012Y196000D01*
X598262Y196292D01*
X598637Y196500D01*
X599012Y196583D01*
X599471D01*
X599846Y196500D01*
X600179Y196292D01*
X600346Y196042D01*
X600429Y195750D01*
X600346Y195417D01*
X600179Y195167D01*
X599929Y195000D01*
X599596Y194917D01*
X599304Y195000D01*
X599012Y195208D01*
X598846Y195458D01*
X598804Y195750D01*
X598887Y196083D01*
X599096Y196333D01*
X599471Y196583D01*
G01X605762Y199375D02*
X605554Y199708D01*
X605429Y200083D01*
Y200417D01*
X605554Y200750D01*
X605762Y201000D01*
X606054Y201125D01*
X606346Y201042D01*
X606596Y200833D01*
X606762Y200458D01*
X606846Y199958D01*
X607012Y199667D01*
X607304Y199542D01*
X607596Y199625D01*
X607804Y199833D01*
X607929Y200125D01*
Y200417D01*
X607846Y200708D01*
X607637Y200958D01*
G01X607721Y204267D02*
X607846Y204017D01*
X607929Y203725D01*
Y203392D01*
X607804Y203017D01*
X607596Y202725D01*
X607346Y202517D01*
X606929Y202350D01*
X606554Y202308D01*
X606179Y202392D01*
X605929Y202517D01*
X605679Y202767D01*
X605512Y203058D01*
X605429Y203350D01*
Y203642D01*
X605512Y203933D01*
X605637Y204183D01*
X605804Y204392D01*
G01X605429Y206450D02*
X607929D01*
X607429Y205950D01*
G01X605429D02*
Y206950D01*
G01X607929Y209550D02*
X607846Y209217D01*
X607637Y208967D01*
X607387Y208800D01*
X607054Y208675D01*
X606679Y208633D01*
X606304Y208675D01*
X605971Y208800D01*
X605721Y208967D01*
X605512Y209217D01*
X605429Y209550D01*
X605512Y209883D01*
X605721Y210133D01*
X605971Y210300D01*
X606304Y210425D01*
X606679Y210467D01*
X607054Y210425D01*
X607387Y210300D01*
X607637Y210133D01*
X607846Y209883D01*
X607929Y209550D01*
G01X605804Y211733D02*
X605596Y211983D01*
X605471Y212275D01*
X605429Y212650D01*
X605512Y213025D01*
X605679Y213317D01*
X605971Y213525D01*
X606304Y213567D01*
X606637Y213483D01*
X606846Y213275D01*
X607012Y212983D01*
X607054Y212692D01*
X607012Y212400D01*
X606846Y212025D01*
X607929Y212150D01*
Y213275D01*
G01X605804Y214833D02*
X605596Y215083D01*
X605471Y215375D01*
X605429Y215750D01*
X605512Y216125D01*
X605679Y216417D01*
X605971Y216625D01*
X606304Y216667D01*
X606637Y216583D01*
X606846Y216375D01*
X607012Y216083D01*
X607054Y215792D01*
X607012Y215500D01*
X606846Y215125D01*
X607929Y215250D01*
Y216375D01*
G01X598262Y199375D02*
X598054Y199708D01*
X597929Y200083D01*
Y200417D01*
X598054Y200750D01*
X598262Y201000D01*
X598554Y201125D01*
X598846Y201042D01*
X599096Y200833D01*
X599262Y200458D01*
X599346Y199958D01*
X599512Y199667D01*
X599804Y199542D01*
X600096Y199625D01*
X600304Y199833D01*
X600429Y200125D01*
Y200417D01*
X600346Y200708D01*
X600137Y200958D01*
G01X600221Y204267D02*
X600346Y204017D01*
X600429Y203725D01*
Y203392D01*
X600304Y203017D01*
X600096Y202725D01*
X599846Y202517D01*
X599429Y202350D01*
X599054Y202308D01*
X598679Y202392D01*
X598429Y202517D01*
X598179Y202767D01*
X598012Y203058D01*
X597929Y203350D01*
Y203642D01*
X598012Y203933D01*
X598137Y204183D01*
X598304Y204392D01*
G01X597929Y206450D02*
X600429D01*
X599929Y205950D01*
G01X597929D02*
Y206950D01*
G01X600429Y209550D02*
X600346Y209217D01*
X600137Y208967D01*
X599887Y208800D01*
X599554Y208675D01*
X599179Y208633D01*
X598804Y208675D01*
X598471Y208800D01*
X598221Y208967D01*
X598012Y209217D01*
X597929Y209550D01*
X598012Y209883D01*
X598221Y210133D01*
X598471Y210300D01*
X598804Y210425D01*
X599179Y210467D01*
X599554Y210425D01*
X599887Y210300D01*
X600137Y210133D01*
X600346Y209883D01*
X600429Y209550D01*
G01X598429Y211733D02*
X598137Y211983D01*
X597971Y212317D01*
X597929Y212692D01*
X597971Y213025D01*
X598179Y213358D01*
X598429Y213567D01*
X598679Y213608D01*
X598971Y213525D01*
X599179Y213233D01*
X599262Y212942D01*
Y212567D01*
G01Y212942D02*
X599387Y213192D01*
X599596Y213400D01*
X599846Y213483D01*
X600096Y213400D01*
X600304Y213192D01*
X600429Y212817D01*
X600387Y212442D01*
X600221Y212067D01*
G01X598429Y214833D02*
X598137Y215083D01*
X597971Y215417D01*
X597929Y215792D01*
X597971Y216125D01*
X598179Y216458D01*
X598429Y216667D01*
X598679Y216708D01*
X598971Y216625D01*
X599179Y216333D01*
X599262Y216042D01*
Y215667D01*
G01Y216042D02*
X599387Y216292D01*
X599596Y216500D01*
X599846Y216583D01*
X600096Y216500D01*
X600304Y216292D01*
X600429Y215917D01*
X600387Y215542D01*
X600221Y215167D01*
G01X597262Y219375D02*
X597054Y219708D01*
X596929Y220083D01*
Y220417D01*
X597054Y220750D01*
X597262Y221000D01*
X597554Y221125D01*
X597846Y221042D01*
X598096Y220833D01*
X598262Y220458D01*
X598346Y219958D01*
X598512Y219667D01*
X598804Y219542D01*
X599096Y219625D01*
X599304Y219833D01*
X599429Y220125D01*
Y220417D01*
X599346Y220708D01*
X599137Y220958D01*
G01X599221Y224267D02*
X599346Y224017D01*
X599429Y223725D01*
Y223392D01*
X599304Y223017D01*
X599096Y222725D01*
X598846Y222517D01*
X598429Y222350D01*
X598054Y222308D01*
X597679Y222392D01*
X597429Y222517D01*
X597179Y222767D01*
X597012Y223058D01*
X596929Y223350D01*
Y223642D01*
X597012Y223933D01*
X597137Y224183D01*
X597304Y224392D01*
G01X596929Y226450D02*
X599429D01*
X598929Y225950D01*
G01X596929D02*
Y226950D01*
G01X599429Y229550D02*
X599346Y229217D01*
X599137Y228967D01*
X598887Y228800D01*
X598554Y228675D01*
X598179Y228633D01*
X597804Y228675D01*
X597471Y228800D01*
X597221Y228967D01*
X597012Y229217D01*
X596929Y229550D01*
X597012Y229883D01*
X597221Y230133D01*
X597471Y230300D01*
X597804Y230425D01*
X598179Y230467D01*
X598554Y230425D01*
X598887Y230300D01*
X599137Y230133D01*
X599346Y229883D01*
X599429Y229550D01*
G01X597429Y231733D02*
X597137Y231983D01*
X596971Y232317D01*
X596929Y232692D01*
X596971Y233025D01*
X597179Y233358D01*
X597429Y233567D01*
X597679Y233608D01*
X597971Y233525D01*
X598179Y233233D01*
X598262Y232942D01*
Y232567D01*
G01Y232942D02*
X598387Y233192D01*
X598596Y233400D01*
X598846Y233483D01*
X599096Y233400D01*
X599304Y233192D01*
X599429Y232817D01*
X599387Y232442D01*
X599221Y232067D01*
G01X597304Y234833D02*
X597096Y235083D01*
X596971Y235375D01*
X596929Y235750D01*
X597012Y236125D01*
X597179Y236417D01*
X597471Y236625D01*
X597804Y236667D01*
X598137Y236583D01*
X598346Y236375D01*
X598512Y236083D01*
X598554Y235792D01*
X598512Y235500D01*
X598346Y235125D01*
X599429Y235250D01*
Y236375D01*
G01X605762Y219375D02*
X605554Y219708D01*
X605429Y220083D01*
Y220417D01*
X605554Y220750D01*
X605762Y221000D01*
X606054Y221125D01*
X606346Y221042D01*
X606596Y220833D01*
X606762Y220458D01*
X606846Y219958D01*
X607012Y219667D01*
X607304Y219542D01*
X607596Y219625D01*
X607804Y219833D01*
X607929Y220125D01*
Y220417D01*
X607846Y220708D01*
X607637Y220958D01*
G01X607721Y224267D02*
X607846Y224017D01*
X607929Y223725D01*
Y223392D01*
X607804Y223017D01*
X607596Y222725D01*
X607346Y222517D01*
X606929Y222350D01*
X606554Y222308D01*
X606179Y222392D01*
X605929Y222517D01*
X605679Y222767D01*
X605512Y223058D01*
X605429Y223350D01*
Y223642D01*
X605512Y223933D01*
X605637Y224183D01*
X605804Y224392D01*
G01X605429Y226450D02*
X607929D01*
X607429Y225950D01*
G01X605429D02*
Y226950D01*
G01X607929Y229550D02*
X607846Y229217D01*
X607637Y228967D01*
X607387Y228800D01*
X607054Y228675D01*
X606679Y228633D01*
X606304Y228675D01*
X605971Y228800D01*
X605721Y228967D01*
X605512Y229217D01*
X605429Y229550D01*
X605512Y229883D01*
X605721Y230133D01*
X605971Y230300D01*
X606304Y230425D01*
X606679Y230467D01*
X607054Y230425D01*
X607387Y230300D01*
X607637Y230133D01*
X607846Y229883D01*
X607929Y229550D01*
G01X605929Y231733D02*
X605637Y231983D01*
X605471Y232317D01*
X605429Y232692D01*
X605471Y233025D01*
X605679Y233358D01*
X605929Y233567D01*
X606179Y233608D01*
X606471Y233525D01*
X606679Y233233D01*
X606762Y232942D01*
Y232567D01*
G01Y232942D02*
X606887Y233192D01*
X607096Y233400D01*
X607346Y233483D01*
X607596Y233400D01*
X607804Y233192D01*
X607929Y232817D01*
X607887Y232442D01*
X607721Y232067D01*
G01X606471Y234958D02*
X606762Y235250D01*
X606929Y235500D01*
X607012Y235833D01*
X606929Y236125D01*
X606762Y236333D01*
X606512Y236500D01*
X606221Y236542D01*
X605971Y236500D01*
X605721Y236333D01*
X605512Y236083D01*
X605429Y235792D01*
X605512Y235458D01*
X605762Y235167D01*
X606137Y235000D01*
X606554Y234958D01*
X607096Y235042D01*
X607387Y235167D01*
X607679Y235375D01*
X607887Y235667D01*
X607929Y235958D01*
X607846Y236250D01*
X607637Y236458D01*
G01X605262Y238875D02*
X605054Y239208D01*
X604929Y239583D01*
Y239917D01*
X605054Y240250D01*
X605262Y240500D01*
X605554Y240625D01*
X605846Y240542D01*
X606096Y240333D01*
X606262Y239958D01*
X606346Y239458D01*
X606512Y239167D01*
X606804Y239042D01*
X607096Y239125D01*
X607304Y239333D01*
X607429Y239625D01*
Y239917D01*
X607346Y240208D01*
X607137Y240458D01*
G01X607221Y243767D02*
X607346Y243517D01*
X607429Y243225D01*
Y242892D01*
X607304Y242517D01*
X607096Y242225D01*
X606846Y242017D01*
X606429Y241850D01*
X606054Y241808D01*
X605679Y241892D01*
X605429Y242017D01*
X605179Y242267D01*
X605012Y242558D01*
X604929Y242850D01*
Y243142D01*
X605012Y243433D01*
X605137Y243683D01*
X605304Y243892D01*
G01X604929Y245950D02*
X607429D01*
X606929Y245450D01*
G01X604929D02*
Y246450D01*
G01X607429Y249050D02*
X607346Y248717D01*
X607137Y248467D01*
X606887Y248300D01*
X606554Y248175D01*
X606179Y248133D01*
X605804Y248175D01*
X605471Y248300D01*
X605221Y248467D01*
X605012Y248717D01*
X604929Y249050D01*
X605012Y249383D01*
X605221Y249633D01*
X605471Y249800D01*
X605804Y249925D01*
X606179Y249967D01*
X606554Y249925D01*
X606887Y249800D01*
X607137Y249633D01*
X607346Y249383D01*
X607429Y249050D01*
G01X605304Y251233D02*
X605096Y251483D01*
X604971Y251775D01*
X604929Y252150D01*
X605012Y252525D01*
X605179Y252817D01*
X605471Y253025D01*
X605804Y253067D01*
X606137Y252983D01*
X606346Y252775D01*
X606512Y252483D01*
X606554Y252192D01*
X606512Y251900D01*
X606346Y251525D01*
X607429Y251650D01*
Y252775D01*
G01X605429Y254333D02*
X605137Y254583D01*
X604971Y254917D01*
X604929Y255292D01*
X604971Y255625D01*
X605179Y255958D01*
X605429Y256167D01*
X605679Y256208D01*
X605971Y256125D01*
X606179Y255833D01*
X606262Y255542D01*
Y255167D01*
G01Y255542D02*
X606387Y255792D01*
X606596Y256000D01*
X606846Y256083D01*
X607096Y256000D01*
X607304Y255792D01*
X607429Y255417D01*
X607387Y255042D01*
X607221Y254667D01*
G01X597762Y238875D02*
X597554Y239208D01*
X597429Y239583D01*
Y239917D01*
X597554Y240250D01*
X597762Y240500D01*
X598054Y240625D01*
X598346Y240542D01*
X598596Y240333D01*
X598762Y239958D01*
X598846Y239458D01*
X599012Y239167D01*
X599304Y239042D01*
X599596Y239125D01*
X599804Y239333D01*
X599929Y239625D01*
Y239917D01*
X599846Y240208D01*
X599637Y240458D01*
G01X599721Y243767D02*
X599846Y243517D01*
X599929Y243225D01*
Y242892D01*
X599804Y242517D01*
X599596Y242225D01*
X599346Y242017D01*
X598929Y241850D01*
X598554Y241808D01*
X598179Y241892D01*
X597929Y242017D01*
X597679Y242267D01*
X597512Y242558D01*
X597429Y242850D01*
Y243142D01*
X597512Y243433D01*
X597637Y243683D01*
X597804Y243892D01*
G01X597429Y245950D02*
X599929D01*
X599429Y245450D01*
G01X597429D02*
Y246450D01*
G01X599929Y249050D02*
X599846Y248717D01*
X599637Y248467D01*
X599387Y248300D01*
X599054Y248175D01*
X598679Y248133D01*
X598304Y248175D01*
X597971Y248300D01*
X597721Y248467D01*
X597512Y248717D01*
X597429Y249050D01*
X597512Y249383D01*
X597721Y249633D01*
X597971Y249800D01*
X598304Y249925D01*
X598679Y249967D01*
X599054Y249925D01*
X599387Y249800D01*
X599637Y249633D01*
X599846Y249383D01*
X599929Y249050D01*
G01X597804Y251233D02*
X597596Y251483D01*
X597471Y251775D01*
X597429Y252150D01*
X597512Y252525D01*
X597679Y252817D01*
X597971Y253025D01*
X598304Y253067D01*
X598637Y252983D01*
X598846Y252775D01*
X599012Y252483D01*
X599054Y252192D01*
X599012Y251900D01*
X598846Y251525D01*
X599929Y251650D01*
Y252775D01*
G01X597721Y254542D02*
X597512Y254833D01*
X597429Y255167D01*
X597512Y255500D01*
X597762Y255792D01*
X598137Y256000D01*
X598512Y256083D01*
X598971D01*
X599346Y256000D01*
X599679Y255792D01*
X599846Y255542D01*
X599929Y255250D01*
X599846Y254917D01*
X599679Y254667D01*
X599429Y254500D01*
X599096Y254417D01*
X598804Y254500D01*
X598512Y254708D01*
X598346Y254958D01*
X598304Y255250D01*
X598387Y255583D01*
X598596Y255833D01*
X598971Y256083D01*
G01X611629Y261000D02*
Y258500D01*
G01X612587Y261000D02*
X610671D01*
G01X609362Y258500D02*
Y261000D01*
X608362D01*
X608029Y260875D01*
X607779Y260583D01*
X607696Y260250D01*
X607779Y259917D01*
X607987Y259667D01*
X608362Y259542D01*
X609362D01*
G01X606221Y260583D02*
X605971Y260833D01*
X605679Y260958D01*
X605346Y261000D01*
X604929Y260917D01*
X604637Y260708D01*
X604554Y260458D01*
X604596Y260208D01*
X604762Y260000D01*
X605596Y259583D01*
X605971Y259292D01*
X606221Y258875D01*
X606304Y258500D01*
X604554D01*
G01X603121Y259542D02*
X602829Y259833D01*
X602579Y260000D01*
X602246Y260083D01*
X601954Y260000D01*
X601746Y259833D01*
X601579Y259583D01*
X601537Y259292D01*
X601579Y259042D01*
X601746Y258792D01*
X601996Y258583D01*
X602287Y258500D01*
X602621Y258583D01*
X602912Y258833D01*
X603079Y259208D01*
X603121Y259625D01*
X603037Y260167D01*
X602912Y260458D01*
X602704Y260750D01*
X602412Y260958D01*
X602121Y261000D01*
X601829Y260917D01*
X601621Y260708D01*
G01X599229Y261000D02*
X599562Y260917D01*
X599812Y260708D01*
X599979Y260458D01*
X600104Y260125D01*
X600146Y259750D01*
X600104Y259375D01*
X599979Y259042D01*
X599812Y258792D01*
X599562Y258583D01*
X599229Y258500D01*
X598896Y258583D01*
X598646Y258792D01*
X598479Y259042D01*
X598354Y259375D01*
X598312Y259750D01*
X598354Y260125D01*
X598479Y260458D01*
X598646Y260708D01*
X598896Y260917D01*
X599229Y261000D01*
G01X611854Y263533D02*
X611521Y263325D01*
X611146Y263200D01*
X610812D01*
X610479Y263325D01*
X610229Y263533D01*
X610104Y263825D01*
X610187Y264117D01*
X610396Y264367D01*
X610771Y264533D01*
X611271Y264617D01*
X611562Y264783D01*
X611687Y265075D01*
X611604Y265367D01*
X611396Y265575D01*
X611104Y265700D01*
X610812D01*
X610521Y265617D01*
X610271Y265408D01*
G01X606962Y265492D02*
X607212Y265617D01*
X607504Y265700D01*
X607837D01*
X608212Y265575D01*
X608504Y265367D01*
X608712Y265117D01*
X608879Y264700D01*
X608921Y264325D01*
X608837Y263950D01*
X608712Y263700D01*
X608462Y263450D01*
X608171Y263283D01*
X607879Y263200D01*
X607587D01*
X607296Y263283D01*
X607046Y263408D01*
X606837Y263575D01*
G01X604779Y263200D02*
Y265700D01*
X605279Y265200D01*
G01Y263200D02*
X604279D01*
G01X601679Y265700D02*
X602012Y265617D01*
X602262Y265408D01*
X602429Y265158D01*
X602554Y264825D01*
X602596Y264450D01*
X602554Y264075D01*
X602429Y263742D01*
X602262Y263492D01*
X602012Y263283D01*
X601679Y263200D01*
X601346Y263283D01*
X601096Y263492D01*
X600929Y263742D01*
X600804Y264075D01*
X600762Y264450D01*
X600804Y264825D01*
X600929Y265158D01*
X601096Y265408D01*
X601346Y265617D01*
X601679Y265700D01*
G01X598579D02*
X598912Y265617D01*
X599162Y265408D01*
X599329Y265158D01*
X599454Y264825D01*
X599496Y264450D01*
X599454Y264075D01*
X599329Y263742D01*
X599162Y263492D01*
X598912Y263283D01*
X598579Y263200D01*
X598246Y263283D01*
X597996Y263492D01*
X597829Y263742D01*
X597704Y264075D01*
X597662Y264450D01*
X597704Y264825D01*
X597829Y265158D01*
X597996Y265408D01*
X598246Y265617D01*
X598579Y265700D01*
G01X595479Y263200D02*
X595187Y263242D01*
X594854Y263367D01*
X594646Y263575D01*
X594562Y263867D01*
X594646Y264158D01*
X594896Y264408D01*
X595271Y264533D01*
X595687D01*
X595937Y264617D01*
X596146Y264825D01*
X596229Y265117D01*
X596104Y265408D01*
X595812Y265617D01*
X595479Y265700D01*
X595146Y265617D01*
X594854Y265408D01*
X594729Y265117D01*
X594812Y264825D01*
X595021Y264617D01*
X595271Y264533D01*
X595687D01*
X596062Y264408D01*
X596312Y264158D01*
X596396Y263867D01*
X596312Y263575D01*
X596104Y263367D01*
X595771Y263242D01*
X595479Y263200D01*
G01X611504Y267833D02*
X611171Y267625D01*
X610796Y267500D01*
X610462D01*
X610129Y267625D01*
X609879Y267833D01*
X609754Y268125D01*
X609837Y268417D01*
X610046Y268667D01*
X610421Y268833D01*
X610921Y268917D01*
X611212Y269083D01*
X611337Y269375D01*
X611254Y269667D01*
X611046Y269875D01*
X610754Y270000D01*
X610462D01*
X610171Y269917D01*
X609921Y269708D01*
G01X606612Y269792D02*
X606862Y269917D01*
X607154Y270000D01*
X607487D01*
X607862Y269875D01*
X608154Y269667D01*
X608362Y269417D01*
X608529Y269000D01*
X608571Y268625D01*
X608487Y268250D01*
X608362Y268000D01*
X608112Y267750D01*
X607821Y267583D01*
X607529Y267500D01*
X607237D01*
X606946Y267583D01*
X606696Y267708D01*
X606487Y267875D01*
G01X605137Y267792D02*
X604846Y267583D01*
X604512Y267500D01*
X604179Y267583D01*
X603887Y267833D01*
X603679Y268208D01*
X603596Y268583D01*
Y269042D01*
X603679Y269417D01*
X603887Y269750D01*
X604137Y269917D01*
X604429Y270000D01*
X604762Y269917D01*
X605012Y269750D01*
X605179Y269500D01*
X605262Y269167D01*
X605179Y268875D01*
X604971Y268583D01*
X604721Y268417D01*
X604429Y268375D01*
X604096Y268458D01*
X603846Y268667D01*
X603596Y269042D01*
G01X602037Y267792D02*
X601746Y267583D01*
X601412Y267500D01*
X601079Y267583D01*
X600787Y267833D01*
X600579Y268208D01*
X600496Y268583D01*
Y269042D01*
X600579Y269417D01*
X600787Y269750D01*
X601037Y269917D01*
X601329Y270000D01*
X601662Y269917D01*
X601912Y269750D01*
X602079Y269500D01*
X602162Y269167D01*
X602079Y268875D01*
X601871Y268583D01*
X601621Y268417D01*
X601329Y268375D01*
X600996Y268458D01*
X600746Y268667D01*
X600496Y269042D01*
G01X598937Y267792D02*
X598646Y267583D01*
X598312Y267500D01*
X597979Y267583D01*
X597687Y267833D01*
X597479Y268208D01*
X597396Y268583D01*
Y269042D01*
X597479Y269417D01*
X597687Y269750D01*
X597937Y269917D01*
X598229Y270000D01*
X598562Y269917D01*
X598812Y269750D01*
X598979Y269500D01*
X599062Y269167D01*
X598979Y268875D01*
X598771Y268583D01*
X598521Y268417D01*
X598229Y268375D01*
X597896Y268458D01*
X597646Y268667D01*
X597396Y269042D01*
G01X618865Y416634D02*
X618532Y416426D01*
X618157Y416301D01*
X617823D01*
X617490Y416426D01*
X617240Y416634D01*
X617115Y416926D01*
X617198Y417218D01*
X617407Y417468D01*
X617782Y417634D01*
X618282Y417718D01*
X618573Y417884D01*
X618698Y418176D01*
X618615Y418468D01*
X618407Y418676D01*
X618115Y418801D01*
X617823D01*
X617532Y418718D01*
X617282Y418509D01*
G01X613973Y418593D02*
X614223Y418718D01*
X614515Y418801D01*
X614848D01*
X615223Y418676D01*
X615515Y418468D01*
X615723Y418218D01*
X615890Y417801D01*
X615932Y417426D01*
X615848Y417051D01*
X615723Y416801D01*
X615473Y416551D01*
X615182Y416384D01*
X614890Y416301D01*
X614598D01*
X614307Y416384D01*
X614057Y416509D01*
X613848Y416676D01*
G01X611790Y416301D02*
Y418801D01*
X612290Y418301D01*
G01Y416301D02*
X611290D01*
G01X609482Y418384D02*
X609232Y418634D01*
X608940Y418759D01*
X608607Y418801D01*
X608190Y418718D01*
X607898Y418509D01*
X607815Y418259D01*
X607857Y418009D01*
X608023Y417801D01*
X608857Y417384D01*
X609232Y417093D01*
X609482Y416676D01*
X609565Y416301D01*
X607815D01*
G01X605090D02*
Y418801D01*
X606632Y417009D01*
X604548D01*
G01X603282Y418384D02*
X603032Y418634D01*
X602740Y418759D01*
X602407Y418801D01*
X601990Y418718D01*
X601698Y418509D01*
X601615Y418259D01*
X601657Y418009D01*
X601823Y417801D01*
X602657Y417384D01*
X603032Y417093D01*
X603282Y416676D01*
X603365Y416301D01*
X601615D01*
G01X618865Y434234D02*
X618532Y434026D01*
X618157Y433901D01*
X617823D01*
X617490Y434026D01*
X617240Y434234D01*
X617115Y434526D01*
X617198Y434818D01*
X617407Y435068D01*
X617782Y435234D01*
X618282Y435318D01*
X618573Y435484D01*
X618698Y435776D01*
X618615Y436068D01*
X618407Y436276D01*
X618115Y436401D01*
X617823D01*
X617532Y436318D01*
X617282Y436109D01*
G01X613973Y436193D02*
X614223Y436318D01*
X614515Y436401D01*
X614848D01*
X615223Y436276D01*
X615515Y436068D01*
X615723Y435818D01*
X615890Y435401D01*
X615932Y435026D01*
X615848Y434651D01*
X615723Y434401D01*
X615473Y434151D01*
X615182Y433984D01*
X614890Y433901D01*
X614598D01*
X614307Y433984D01*
X614057Y434109D01*
X613848Y434276D01*
G01X611790Y433901D02*
Y436401D01*
X612290Y435901D01*
G01Y433901D02*
X611290D01*
G01X609482Y435984D02*
X609232Y436234D01*
X608940Y436359D01*
X608607Y436401D01*
X608190Y436318D01*
X607898Y436109D01*
X607815Y435859D01*
X607857Y435609D01*
X608023Y435401D01*
X608857Y434984D01*
X609232Y434693D01*
X609482Y434276D01*
X609565Y433901D01*
X607815D01*
G01X605090D02*
Y436401D01*
X606632Y434609D01*
X604548D01*
G01X603282Y434943D02*
X602990Y435234D01*
X602740Y435401D01*
X602407Y435484D01*
X602115Y435401D01*
X601907Y435234D01*
X601740Y434984D01*
X601698Y434693D01*
X601740Y434443D01*
X601907Y434193D01*
X602157Y433984D01*
X602448Y433901D01*
X602782Y433984D01*
X603073Y434234D01*
X603240Y434609D01*
X603282Y435026D01*
X603198Y435568D01*
X603073Y435859D01*
X602865Y436151D01*
X602573Y436359D01*
X602282Y436401D01*
X601990Y436318D01*
X601782Y436109D01*
G01X618865Y429834D02*
X618532Y429626D01*
X618157Y429501D01*
X617823D01*
X617490Y429626D01*
X617240Y429834D01*
X617115Y430126D01*
X617198Y430418D01*
X617407Y430668D01*
X617782Y430834D01*
X618282Y430918D01*
X618573Y431084D01*
X618698Y431376D01*
X618615Y431668D01*
X618407Y431876D01*
X618115Y432001D01*
X617823D01*
X617532Y431918D01*
X617282Y431709D01*
G01X613973Y431793D02*
X614223Y431918D01*
X614515Y432001D01*
X614848D01*
X615223Y431876D01*
X615515Y431668D01*
X615723Y431418D01*
X615890Y431001D01*
X615932Y430626D01*
X615848Y430251D01*
X615723Y430001D01*
X615473Y429751D01*
X615182Y429584D01*
X614890Y429501D01*
X614598D01*
X614307Y429584D01*
X614057Y429709D01*
X613848Y429876D01*
G01X611790Y429501D02*
Y432001D01*
X612290Y431501D01*
G01Y429501D02*
X611290D01*
G01X609482Y431584D02*
X609232Y431834D01*
X608940Y431959D01*
X608607Y432001D01*
X608190Y431918D01*
X607898Y431709D01*
X607815Y431459D01*
X607857Y431209D01*
X608023Y431001D01*
X608857Y430584D01*
X609232Y430293D01*
X609482Y429876D01*
X609565Y429501D01*
X607815D01*
G01X605090D02*
Y432001D01*
X606632Y430209D01*
X604548D01*
G01X603407Y429876D02*
X603157Y429668D01*
X602865Y429543D01*
X602490Y429501D01*
X602115Y429584D01*
X601823Y429751D01*
X601615Y430043D01*
X601573Y430376D01*
X601657Y430709D01*
X601865Y430918D01*
X602157Y431084D01*
X602448Y431126D01*
X602740Y431084D01*
X603115Y430918D01*
X602990Y432001D01*
X601865D01*
G01X618865Y425434D02*
X618532Y425226D01*
X618157Y425101D01*
X617823D01*
X617490Y425226D01*
X617240Y425434D01*
X617115Y425726D01*
X617198Y426018D01*
X617407Y426268D01*
X617782Y426434D01*
X618282Y426518D01*
X618573Y426684D01*
X618698Y426976D01*
X618615Y427268D01*
X618407Y427476D01*
X618115Y427601D01*
X617823D01*
X617532Y427518D01*
X617282Y427309D01*
G01X613973Y427393D02*
X614223Y427518D01*
X614515Y427601D01*
X614848D01*
X615223Y427476D01*
X615515Y427268D01*
X615723Y427018D01*
X615890Y426601D01*
X615932Y426226D01*
X615848Y425851D01*
X615723Y425601D01*
X615473Y425351D01*
X615182Y425184D01*
X614890Y425101D01*
X614598D01*
X614307Y425184D01*
X614057Y425309D01*
X613848Y425476D01*
G01X611790Y425101D02*
Y427601D01*
X612290Y427101D01*
G01Y425101D02*
X611290D01*
G01X609482Y427184D02*
X609232Y427434D01*
X608940Y427559D01*
X608607Y427601D01*
X608190Y427518D01*
X607898Y427309D01*
X607815Y427059D01*
X607857Y426809D01*
X608023Y426601D01*
X608857Y426184D01*
X609232Y425893D01*
X609482Y425476D01*
X609565Y425101D01*
X607815D01*
G01X605090D02*
Y427601D01*
X606632Y425809D01*
X604548D01*
G01X601990Y425101D02*
Y427601D01*
X603532Y425809D01*
X601448D01*
G01X618865Y421034D02*
X618532Y420826D01*
X618157Y420701D01*
X617823D01*
X617490Y420826D01*
X617240Y421034D01*
X617115Y421326D01*
X617198Y421618D01*
X617407Y421868D01*
X617782Y422034D01*
X618282Y422118D01*
X618573Y422284D01*
X618698Y422576D01*
X618615Y422868D01*
X618407Y423076D01*
X618115Y423201D01*
X617823D01*
X617532Y423118D01*
X617282Y422909D01*
G01X613973Y422993D02*
X614223Y423118D01*
X614515Y423201D01*
X614848D01*
X615223Y423076D01*
X615515Y422868D01*
X615723Y422618D01*
X615890Y422201D01*
X615932Y421826D01*
X615848Y421451D01*
X615723Y421201D01*
X615473Y420951D01*
X615182Y420784D01*
X614890Y420701D01*
X614598D01*
X614307Y420784D01*
X614057Y420909D01*
X613848Y421076D01*
G01X611790Y420701D02*
Y423201D01*
X612290Y422701D01*
G01Y420701D02*
X611290D01*
G01X609482Y422784D02*
X609232Y423034D01*
X608940Y423159D01*
X608607Y423201D01*
X608190Y423118D01*
X607898Y422909D01*
X607815Y422659D01*
X607857Y422409D01*
X608023Y422201D01*
X608857Y421784D01*
X609232Y421493D01*
X609482Y421076D01*
X609565Y420701D01*
X607815D01*
G01X605090D02*
Y423201D01*
X606632Y421409D01*
X604548D01*
G01X603407Y421201D02*
X603157Y420909D01*
X602823Y420743D01*
X602448Y420701D01*
X602115Y420743D01*
X601782Y420951D01*
X601573Y421201D01*
X601532Y421451D01*
X601615Y421743D01*
X601907Y421951D01*
X602198Y422034D01*
X602573D01*
G01X602198D02*
X601948Y422159D01*
X601740Y422368D01*
X601657Y422618D01*
X601740Y422868D01*
X601948Y423076D01*
X602323Y423201D01*
X602698Y423159D01*
X603073Y422993D01*
G01X629504Y229193D02*
X629171Y228985D01*
X628796Y228860D01*
X628462D01*
X628129Y228985D01*
X627879Y229193D01*
X627754Y229485D01*
X627837Y229777D01*
X628046Y230027D01*
X628421Y230193D01*
X628921Y230277D01*
X629212Y230443D01*
X629337Y230735D01*
X629254Y231027D01*
X629046Y231235D01*
X628754Y231360D01*
X628462D01*
X628171Y231277D01*
X627921Y231068D01*
G01X624612Y231152D02*
X624862Y231277D01*
X625154Y231360D01*
X625487D01*
X625862Y231235D01*
X626154Y231027D01*
X626362Y230777D01*
X626529Y230360D01*
X626571Y229985D01*
X626487Y229610D01*
X626362Y229360D01*
X626112Y229110D01*
X625821Y228943D01*
X625529Y228860D01*
X625237D01*
X624946Y228943D01*
X624696Y229068D01*
X624487Y229235D01*
G01X623137Y229152D02*
X622846Y228943D01*
X622512Y228860D01*
X622179Y228943D01*
X621887Y229193D01*
X621679Y229568D01*
X621596Y229943D01*
Y230402D01*
X621679Y230777D01*
X621887Y231110D01*
X622137Y231277D01*
X622429Y231360D01*
X622762Y231277D01*
X623012Y231110D01*
X623179Y230860D01*
X623262Y230527D01*
X623179Y230235D01*
X622971Y229943D01*
X622721Y229777D01*
X622429Y229735D01*
X622096Y229818D01*
X621846Y230027D01*
X621596Y230402D01*
G01X619329Y228860D02*
X619037Y228902D01*
X618704Y229027D01*
X618496Y229235D01*
X618412Y229527D01*
X618496Y229818D01*
X618746Y230068D01*
X619121Y230193D01*
X619537D01*
X619787Y230277D01*
X619996Y230485D01*
X620079Y230777D01*
X619954Y231068D01*
X619662Y231277D01*
X619329Y231360D01*
X618996Y231277D01*
X618704Y231068D01*
X618579Y230777D01*
X618662Y230485D01*
X618871Y230277D01*
X619121Y230193D01*
X619537D01*
X619912Y230068D01*
X620162Y229818D01*
X620246Y229527D01*
X620162Y229235D01*
X619954Y229027D01*
X619621Y228902D01*
X619329Y228860D01*
G01X616229D02*
X615937Y228902D01*
X615604Y229027D01*
X615396Y229235D01*
X615312Y229527D01*
X615396Y229818D01*
X615646Y230068D01*
X616021Y230193D01*
X616437D01*
X616687Y230277D01*
X616896Y230485D01*
X616979Y230777D01*
X616854Y231068D01*
X616562Y231277D01*
X616229Y231360D01*
X615896Y231277D01*
X615604Y231068D01*
X615479Y230777D01*
X615562Y230485D01*
X615771Y230277D01*
X616021Y230193D01*
X616437D01*
X616812Y230068D01*
X617062Y229818D01*
X617146Y229527D01*
X617062Y229235D01*
X616854Y229027D01*
X616521Y228902D01*
X616229Y228860D01*
G01X629594Y223183D02*
X629261Y222975D01*
X628886Y222850D01*
X628552D01*
X628219Y222975D01*
X627969Y223183D01*
X627844Y223475D01*
X627927Y223767D01*
X628136Y224017D01*
X628511Y224183D01*
X629011Y224267D01*
X629302Y224433D01*
X629427Y224725D01*
X629344Y225017D01*
X629136Y225225D01*
X628844Y225350D01*
X628552D01*
X628261Y225267D01*
X628011Y225058D01*
G01X624702Y225142D02*
X624952Y225267D01*
X625244Y225350D01*
X625577D01*
X625952Y225225D01*
X626244Y225017D01*
X626452Y224767D01*
X626619Y224350D01*
X626661Y223975D01*
X626577Y223600D01*
X626452Y223350D01*
X626202Y223100D01*
X625911Y222933D01*
X625619Y222850D01*
X625327D01*
X625036Y222933D01*
X624786Y223058D01*
X624577Y223225D01*
G01X623227Y223142D02*
X622936Y222933D01*
X622602Y222850D01*
X622269Y222933D01*
X621977Y223183D01*
X621769Y223558D01*
X621686Y223933D01*
Y224392D01*
X621769Y224767D01*
X621977Y225100D01*
X622227Y225267D01*
X622519Y225350D01*
X622852Y225267D01*
X623102Y225100D01*
X623269Y224850D01*
X623352Y224517D01*
X623269Y224225D01*
X623061Y223933D01*
X622811Y223767D01*
X622519Y223725D01*
X622186Y223808D01*
X621936Y224017D01*
X621686Y224392D01*
G01X619419Y222850D02*
X619127Y222892D01*
X618794Y223017D01*
X618586Y223225D01*
X618502Y223517D01*
X618586Y223808D01*
X618836Y224058D01*
X619211Y224183D01*
X619627D01*
X619877Y224267D01*
X620086Y224475D01*
X620169Y224767D01*
X620044Y225058D01*
X619752Y225267D01*
X619419Y225350D01*
X619086Y225267D01*
X618794Y225058D01*
X618669Y224767D01*
X618752Y224475D01*
X618961Y224267D01*
X619211Y224183D01*
X619627D01*
X620002Y224058D01*
X620252Y223808D01*
X620336Y223517D01*
X620252Y223225D01*
X620044Y223017D01*
X619711Y222892D01*
X619419Y222850D01*
G01X617027Y223142D02*
X616736Y222933D01*
X616402Y222850D01*
X616069Y222933D01*
X615777Y223183D01*
X615569Y223558D01*
X615486Y223933D01*
Y224392D01*
X615569Y224767D01*
X615777Y225100D01*
X616027Y225267D01*
X616319Y225350D01*
X616652Y225267D01*
X616902Y225100D01*
X617069Y224850D01*
X617152Y224517D01*
X617069Y224225D01*
X616861Y223933D01*
X616611Y223767D01*
X616319Y223725D01*
X615986Y223808D01*
X615736Y224017D01*
X615486Y224392D01*
G01X629504Y235733D02*
X629171Y235525D01*
X628796Y235400D01*
X628462D01*
X628129Y235525D01*
X627879Y235733D01*
X627754Y236025D01*
X627837Y236317D01*
X628046Y236567D01*
X628421Y236733D01*
X628921Y236817D01*
X629212Y236983D01*
X629337Y237275D01*
X629254Y237567D01*
X629046Y237775D01*
X628754Y237900D01*
X628462D01*
X628171Y237817D01*
X627921Y237608D01*
G01X624612Y237692D02*
X624862Y237817D01*
X625154Y237900D01*
X625487D01*
X625862Y237775D01*
X626154Y237567D01*
X626362Y237317D01*
X626529Y236900D01*
X626571Y236525D01*
X626487Y236150D01*
X626362Y235900D01*
X626112Y235650D01*
X625821Y235483D01*
X625529Y235400D01*
X625237D01*
X624946Y235483D01*
X624696Y235608D01*
X624487Y235775D01*
G01X623137Y235692D02*
X622846Y235483D01*
X622512Y235400D01*
X622179Y235483D01*
X621887Y235733D01*
X621679Y236108D01*
X621596Y236483D01*
Y236942D01*
X621679Y237317D01*
X621887Y237650D01*
X622137Y237817D01*
X622429Y237900D01*
X622762Y237817D01*
X623012Y237650D01*
X623179Y237400D01*
X623262Y237067D01*
X623179Y236775D01*
X622971Y236483D01*
X622721Y236317D01*
X622429Y236275D01*
X622096Y236358D01*
X621846Y236567D01*
X621596Y236942D01*
G01X620037Y235692D02*
X619746Y235483D01*
X619412Y235400D01*
X619079Y235483D01*
X618787Y235733D01*
X618579Y236108D01*
X618496Y236483D01*
Y236942D01*
X618579Y237317D01*
X618787Y237650D01*
X619037Y237817D01*
X619329Y237900D01*
X619662Y237817D01*
X619912Y237650D01*
X620079Y237400D01*
X620162Y237067D01*
X620079Y236775D01*
X619871Y236483D01*
X619621Y236317D01*
X619329Y236275D01*
X618996Y236358D01*
X618746Y236567D01*
X618496Y236942D01*
G01X616229Y237900D02*
X616562Y237817D01*
X616812Y237608D01*
X616979Y237358D01*
X617104Y237025D01*
X617146Y236650D01*
X617104Y236275D01*
X616979Y235942D01*
X616812Y235692D01*
X616562Y235483D01*
X616229Y235400D01*
X615896Y235483D01*
X615646Y235692D01*
X615479Y235942D01*
X615354Y236275D01*
X615312Y236650D01*
X615354Y237025D01*
X615479Y237358D01*
X615646Y237608D01*
X615896Y237817D01*
X616229Y237900D01*
G01X629504Y248083D02*
X629171Y247875D01*
X628796Y247750D01*
X628462D01*
X628129Y247875D01*
X627879Y248083D01*
X627754Y248375D01*
X627837Y248667D01*
X628046Y248917D01*
X628421Y249083D01*
X628921Y249167D01*
X629212Y249333D01*
X629337Y249625D01*
X629254Y249917D01*
X629046Y250125D01*
X628754Y250250D01*
X628462D01*
X628171Y250167D01*
X627921Y249958D01*
G01X624612Y250042D02*
X624862Y250167D01*
X625154Y250250D01*
X625487D01*
X625862Y250125D01*
X626154Y249917D01*
X626362Y249667D01*
X626529Y249250D01*
X626571Y248875D01*
X626487Y248500D01*
X626362Y248250D01*
X626112Y248000D01*
X625821Y247833D01*
X625529Y247750D01*
X625237D01*
X624946Y247833D01*
X624696Y247958D01*
X624487Y248125D01*
G01X623137Y248042D02*
X622846Y247833D01*
X622512Y247750D01*
X622179Y247833D01*
X621887Y248083D01*
X621679Y248458D01*
X621596Y248833D01*
Y249292D01*
X621679Y249667D01*
X621887Y250000D01*
X622137Y250167D01*
X622429Y250250D01*
X622762Y250167D01*
X623012Y250000D01*
X623179Y249750D01*
X623262Y249417D01*
X623179Y249125D01*
X622971Y248833D01*
X622721Y248667D01*
X622429Y248625D01*
X622096Y248708D01*
X621846Y248917D01*
X621596Y249292D01*
G01X620037Y248042D02*
X619746Y247833D01*
X619412Y247750D01*
X619079Y247833D01*
X618787Y248083D01*
X618579Y248458D01*
X618496Y248833D01*
Y249292D01*
X618579Y249667D01*
X618787Y250000D01*
X619037Y250167D01*
X619329Y250250D01*
X619662Y250167D01*
X619912Y250000D01*
X620079Y249750D01*
X620162Y249417D01*
X620079Y249125D01*
X619871Y248833D01*
X619621Y248667D01*
X619329Y248625D01*
X618996Y248708D01*
X618746Y248917D01*
X618496Y249292D01*
G01X616229Y247750D02*
Y250250D01*
X616729Y249750D01*
G01Y247750D02*
X615729D01*
G01X630004Y254333D02*
X629671Y254125D01*
X629296Y254000D01*
X628962D01*
X628629Y254125D01*
X628379Y254333D01*
X628254Y254625D01*
X628337Y254917D01*
X628546Y255167D01*
X628921Y255333D01*
X629421Y255417D01*
X629712Y255583D01*
X629837Y255875D01*
X629754Y256167D01*
X629546Y256375D01*
X629254Y256500D01*
X628962D01*
X628671Y256417D01*
X628421Y256208D01*
G01X625112Y256292D02*
X625362Y256417D01*
X625654Y256500D01*
X625987D01*
X626362Y256375D01*
X626654Y256167D01*
X626862Y255917D01*
X627029Y255500D01*
X627071Y255125D01*
X626987Y254750D01*
X626862Y254500D01*
X626612Y254250D01*
X626321Y254083D01*
X626029Y254000D01*
X625737D01*
X625446Y254083D01*
X625196Y254208D01*
X624987Y254375D01*
G01X623637Y254292D02*
X623346Y254083D01*
X623012Y254000D01*
X622679Y254083D01*
X622387Y254333D01*
X622179Y254708D01*
X622096Y255083D01*
Y255542D01*
X622179Y255917D01*
X622387Y256250D01*
X622637Y256417D01*
X622929Y256500D01*
X623262Y256417D01*
X623512Y256250D01*
X623679Y256000D01*
X623762Y255667D01*
X623679Y255375D01*
X623471Y255083D01*
X623221Y254917D01*
X622929Y254875D01*
X622596Y254958D01*
X622346Y255167D01*
X622096Y255542D01*
G01X620537Y254292D02*
X620246Y254083D01*
X619912Y254000D01*
X619579Y254083D01*
X619287Y254333D01*
X619079Y254708D01*
X618996Y255083D01*
Y255542D01*
X619079Y255917D01*
X619287Y256250D01*
X619537Y256417D01*
X619829Y256500D01*
X620162Y256417D01*
X620412Y256250D01*
X620579Y256000D01*
X620662Y255667D01*
X620579Y255375D01*
X620371Y255083D01*
X620121Y254917D01*
X619829Y254875D01*
X619496Y254958D01*
X619246Y255167D01*
X618996Y255542D01*
G01X617521Y256083D02*
X617271Y256333D01*
X616979Y256458D01*
X616646Y256500D01*
X616229Y256417D01*
X615937Y256208D01*
X615854Y255958D01*
X615896Y255708D01*
X616062Y255500D01*
X616896Y255083D01*
X617271Y254792D01*
X617521Y254375D01*
X617604Y254000D01*
X615854D01*
G01X629704Y242133D02*
X629371Y241925D01*
X628996Y241800D01*
X628662D01*
X628329Y241925D01*
X628079Y242133D01*
X627954Y242425D01*
X628037Y242717D01*
X628246Y242967D01*
X628621Y243133D01*
X629121Y243217D01*
X629412Y243383D01*
X629537Y243675D01*
X629454Y243967D01*
X629246Y244175D01*
X628954Y244300D01*
X628662D01*
X628371Y244217D01*
X628121Y244008D01*
G01X624812Y244092D02*
X625062Y244217D01*
X625354Y244300D01*
X625687D01*
X626062Y244175D01*
X626354Y243967D01*
X626562Y243717D01*
X626729Y243300D01*
X626771Y242925D01*
X626687Y242550D01*
X626562Y242300D01*
X626312Y242050D01*
X626021Y241883D01*
X625729Y241800D01*
X625437D01*
X625146Y241883D01*
X624896Y242008D01*
X624687Y242175D01*
G01X623337Y242092D02*
X623046Y241883D01*
X622712Y241800D01*
X622379Y241883D01*
X622087Y242133D01*
X621879Y242508D01*
X621796Y242883D01*
Y243342D01*
X621879Y243717D01*
X622087Y244050D01*
X622337Y244217D01*
X622629Y244300D01*
X622962Y244217D01*
X623212Y244050D01*
X623379Y243800D01*
X623462Y243467D01*
X623379Y243175D01*
X623171Y242883D01*
X622921Y242717D01*
X622629Y242675D01*
X622296Y242758D01*
X622046Y242967D01*
X621796Y243342D01*
G01X620237Y242092D02*
X619946Y241883D01*
X619612Y241800D01*
X619279Y241883D01*
X618987Y242133D01*
X618779Y242508D01*
X618696Y242883D01*
Y243342D01*
X618779Y243717D01*
X618987Y244050D01*
X619237Y244217D01*
X619529Y244300D01*
X619862Y244217D01*
X620112Y244050D01*
X620279Y243800D01*
X620362Y243467D01*
X620279Y243175D01*
X620071Y242883D01*
X619821Y242717D01*
X619529Y242675D01*
X619196Y242758D01*
X618946Y242967D01*
X618696Y243342D01*
G01X617346Y242300D02*
X617096Y242008D01*
X616762Y241842D01*
X616387Y241800D01*
X616054Y241842D01*
X615721Y242050D01*
X615512Y242300D01*
X615471Y242550D01*
X615554Y242842D01*
X615846Y243050D01*
X616137Y243133D01*
X616512D01*
G01X616137D02*
X615887Y243258D01*
X615679Y243467D01*
X615596Y243717D01*
X615679Y243967D01*
X615887Y244175D01*
X616262Y244300D01*
X616637Y244258D01*
X617012Y244092D01*
G01X631374Y260813D02*
X631041Y260605D01*
X630666Y260480D01*
X630332D01*
X629999Y260605D01*
X629749Y260813D01*
X629624Y261105D01*
X629707Y261397D01*
X629916Y261647D01*
X630291Y261813D01*
X630791Y261897D01*
X631082Y262063D01*
X631207Y262355D01*
X631124Y262647D01*
X630916Y262855D01*
X630624Y262980D01*
X630332D01*
X630041Y262897D01*
X629791Y262688D01*
G01X626482Y262772D02*
X626732Y262897D01*
X627024Y262980D01*
X627357D01*
X627732Y262855D01*
X628024Y262647D01*
X628232Y262397D01*
X628399Y261980D01*
X628441Y261605D01*
X628357Y261230D01*
X628232Y260980D01*
X627982Y260730D01*
X627691Y260563D01*
X627399Y260480D01*
X627107D01*
X626816Y260563D01*
X626566Y260688D01*
X626357Y260855D01*
G01X624299Y260480D02*
Y262980D01*
X624799Y262480D01*
G01Y260480D02*
X623799D01*
G01X621199Y262980D02*
X621532Y262897D01*
X621782Y262688D01*
X621949Y262438D01*
X622074Y262105D01*
X622116Y261730D01*
X622074Y261355D01*
X621949Y261022D01*
X621782Y260772D01*
X621532Y260563D01*
X621199Y260480D01*
X620866Y260563D01*
X620616Y260772D01*
X620449Y261022D01*
X620324Y261355D01*
X620282Y261730D01*
X620324Y262105D01*
X620449Y262438D01*
X620616Y262688D01*
X620866Y262897D01*
X621199Y262980D01*
G01X618099D02*
X618432Y262897D01*
X618682Y262688D01*
X618849Y262438D01*
X618974Y262105D01*
X619016Y261730D01*
X618974Y261355D01*
X618849Y261022D01*
X618682Y260772D01*
X618432Y260563D01*
X618099Y260480D01*
X617766Y260563D01*
X617516Y260772D01*
X617349Y261022D01*
X617224Y261355D01*
X617182Y261730D01*
X617224Y262105D01*
X617349Y262438D01*
X617516Y262688D01*
X617766Y262897D01*
X618099Y262980D01*
G01X615791Y261522D02*
X615499Y261813D01*
X615249Y261980D01*
X614916Y262063D01*
X614624Y261980D01*
X614416Y261813D01*
X614249Y261563D01*
X614207Y261272D01*
X614249Y261022D01*
X614416Y260772D01*
X614666Y260563D01*
X614957Y260480D01*
X615291Y260563D01*
X615582Y260813D01*
X615749Y261188D01*
X615791Y261605D01*
X615707Y262147D01*
X615582Y262438D01*
X615374Y262730D01*
X615082Y262938D01*
X614791Y262980D01*
X614499Y262897D01*
X614291Y262688D01*
G01X631364Y267203D02*
X631031Y266995D01*
X630656Y266870D01*
X630322D01*
X629989Y266995D01*
X629739Y267203D01*
X629614Y267495D01*
X629697Y267787D01*
X629906Y268037D01*
X630281Y268203D01*
X630781Y268287D01*
X631072Y268453D01*
X631197Y268745D01*
X631114Y269037D01*
X630906Y269245D01*
X630614Y269370D01*
X630322D01*
X630031Y269287D01*
X629781Y269078D01*
G01X626472Y269162D02*
X626722Y269287D01*
X627014Y269370D01*
X627347D01*
X627722Y269245D01*
X628014Y269037D01*
X628222Y268787D01*
X628389Y268370D01*
X628431Y267995D01*
X628347Y267620D01*
X628222Y267370D01*
X627972Y267120D01*
X627681Y266953D01*
X627389Y266870D01*
X627097D01*
X626806Y266953D01*
X626556Y267078D01*
X626347Y267245D01*
G01X624289Y266870D02*
Y269370D01*
X624789Y268870D01*
G01Y266870D02*
X623789D01*
G01X621189Y269370D02*
X621522Y269287D01*
X621772Y269078D01*
X621939Y268828D01*
X622064Y268495D01*
X622106Y268120D01*
X622064Y267745D01*
X621939Y267412D01*
X621772Y267162D01*
X621522Y266953D01*
X621189Y266870D01*
X620856Y266953D01*
X620606Y267162D01*
X620439Y267412D01*
X620314Y267745D01*
X620272Y268120D01*
X620314Y268495D01*
X620439Y268828D01*
X620606Y269078D01*
X620856Y269287D01*
X621189Y269370D01*
G01X618089D02*
X618422Y269287D01*
X618672Y269078D01*
X618839Y268828D01*
X618964Y268495D01*
X619006Y268120D01*
X618964Y267745D01*
X618839Y267412D01*
X618672Y267162D01*
X618422Y266953D01*
X618089Y266870D01*
X617756Y266953D01*
X617506Y267162D01*
X617339Y267412D01*
X617214Y267745D01*
X617172Y268120D01*
X617214Y268495D01*
X617339Y268828D01*
X617506Y269078D01*
X617756Y269287D01*
X618089Y269370D01*
G01X615072Y266870D02*
X614989Y267412D01*
X614864Y267870D01*
X614697Y268287D01*
X614489Y268745D01*
X614156Y269370D01*
X615822D01*
G01X624500Y364467D02*
X627000D01*
Y365467D01*
X626875Y365800D01*
X626583Y366050D01*
X626250Y366133D01*
X625917Y366050D01*
X625667Y365842D01*
X625542Y365467D01*
Y364467D01*
G01X626792Y369317D02*
X626917Y369067D01*
X627000Y368775D01*
Y368442D01*
X626875Y368067D01*
X626667Y367775D01*
X626417Y367567D01*
X626000Y367400D01*
X625625Y367358D01*
X625250Y367442D01*
X625000Y367567D01*
X624750Y367817D01*
X624583Y368108D01*
X624500Y368400D01*
Y368692D01*
X624583Y368983D01*
X624708Y369233D01*
X624875Y369442D01*
G01X624500Y371500D02*
X627000D01*
X626500Y371000D01*
G01X624500D02*
Y372000D01*
G01Y374517D02*
X625042Y374600D01*
X625500Y374725D01*
X625917Y374892D01*
X626375Y375100D01*
X627000Y375433D01*
Y373767D01*
G01X624792Y376992D02*
X624583Y377283D01*
X624500Y377617D01*
X624583Y377950D01*
X624833Y378242D01*
X625208Y378450D01*
X625583Y378533D01*
X626042D01*
X626417Y378450D01*
X626750Y378242D01*
X626917Y377992D01*
X627000Y377700D01*
X626917Y377367D01*
X626750Y377117D01*
X626500Y376950D01*
X626167Y376867D01*
X625875Y376950D01*
X625583Y377158D01*
X625417Y377408D01*
X625375Y377700D01*
X625458Y378033D01*
X625667Y378283D01*
X626042Y378533D01*
G01X632125Y406833D02*
X631792Y406625D01*
X631417Y406500D01*
X631083D01*
X630750Y406625D01*
X630500Y406833D01*
X630375Y407125D01*
X630458Y407417D01*
X630667Y407667D01*
X631042Y407833D01*
X631542Y407917D01*
X631833Y408083D01*
X631958Y408375D01*
X631875Y408667D01*
X631667Y408875D01*
X631375Y409000D01*
X631083D01*
X630792Y408917D01*
X630542Y408708D01*
G01X627233Y408792D02*
X627483Y408917D01*
X627775Y409000D01*
X628108D01*
X628483Y408875D01*
X628775Y408667D01*
X628983Y408417D01*
X629150Y408000D01*
X629192Y407625D01*
X629108Y407250D01*
X628983Y407000D01*
X628733Y406750D01*
X628442Y406583D01*
X628150Y406500D01*
X627858D01*
X627567Y406583D01*
X627317Y406708D01*
X627108Y406875D01*
G01X625050Y406500D02*
Y409000D01*
X625550Y408500D01*
G01Y406500D02*
X624550D01*
G01X622742Y408583D02*
X622492Y408833D01*
X622200Y408958D01*
X621867Y409000D01*
X621450Y408917D01*
X621158Y408708D01*
X621075Y408458D01*
X621117Y408208D01*
X621283Y408000D01*
X622117Y407583D01*
X622492Y407292D01*
X622742Y406875D01*
X622825Y406500D01*
X621075D01*
G01X618350D02*
Y409000D01*
X619892Y407208D01*
X617808D01*
G01X615750Y406500D02*
Y409000D01*
X616250Y408500D01*
G01Y406500D02*
X615250D01*
G01X632762Y238425D02*
X632554Y238758D01*
X632429Y239133D01*
Y239467D01*
X632554Y239800D01*
X632762Y240050D01*
X633054Y240175D01*
X633346Y240092D01*
X633596Y239883D01*
X633762Y239508D01*
X633846Y239008D01*
X634012Y238717D01*
X634304Y238592D01*
X634596Y238675D01*
X634804Y238883D01*
X634929Y239175D01*
Y239467D01*
X634846Y239758D01*
X634637Y240008D01*
G01X634929Y242400D02*
X632429D01*
G01X634929Y241442D02*
Y243358D01*
G01X632429Y244667D02*
X634929D01*
Y245667D01*
X634804Y246000D01*
X634512Y246250D01*
X634179Y246333D01*
X633846Y246250D01*
X633596Y246042D01*
X633471Y245667D01*
Y244667D01*
G01X632429Y248600D02*
X634929D01*
X634429Y248100D01*
G01X632429D02*
Y249100D01*
G01X632804Y250783D02*
X632596Y251033D01*
X632471Y251325D01*
X632429Y251700D01*
X632512Y252075D01*
X632679Y252367D01*
X632971Y252575D01*
X633304Y252617D01*
X633637Y252533D01*
X633846Y252325D01*
X634012Y252033D01*
X634054Y251742D01*
X634012Y251450D01*
X633846Y251075D01*
X634929Y251200D01*
Y252325D01*
G01X639500Y364467D02*
X642000D01*
Y365467D01*
X641875Y365800D01*
X641583Y366050D01*
X641250Y366133D01*
X640917Y366050D01*
X640667Y365842D01*
X640542Y365467D01*
Y364467D01*
G01X641792Y369317D02*
X641917Y369067D01*
X642000Y368775D01*
Y368442D01*
X641875Y368067D01*
X641667Y367775D01*
X641417Y367567D01*
X641000Y367400D01*
X640625Y367358D01*
X640250Y367442D01*
X640000Y367567D01*
X639750Y367817D01*
X639583Y368108D01*
X639500Y368400D01*
Y368692D01*
X639583Y368983D01*
X639708Y369233D01*
X639875Y369442D01*
G01X639500Y371500D02*
X642000D01*
X641500Y371000D01*
G01X639500D02*
Y372000D01*
G01Y374517D02*
X640042Y374600D01*
X640500Y374725D01*
X640917Y374892D01*
X641375Y375100D01*
X642000Y375433D01*
Y373767D01*
G01X640542Y376908D02*
X640833Y377200D01*
X641000Y377450D01*
X641083Y377783D01*
X641000Y378075D01*
X640833Y378283D01*
X640583Y378450D01*
X640292Y378492D01*
X640042Y378450D01*
X639792Y378283D01*
X639583Y378033D01*
X639500Y377742D01*
X639583Y377408D01*
X639833Y377117D01*
X640208Y376950D01*
X640625Y376908D01*
X641167Y376992D01*
X641458Y377117D01*
X641750Y377325D01*
X641958Y377617D01*
X642000Y377908D01*
X641917Y378200D01*
X641708Y378408D01*
G01X634500Y364467D02*
X637000D01*
Y365467D01*
X636875Y365800D01*
X636583Y366050D01*
X636250Y366133D01*
X635917Y366050D01*
X635667Y365842D01*
X635542Y365467D01*
Y364467D01*
G01X636792Y369317D02*
X636917Y369067D01*
X637000Y368775D01*
Y368442D01*
X636875Y368067D01*
X636667Y367775D01*
X636417Y367567D01*
X636000Y367400D01*
X635625Y367358D01*
X635250Y367442D01*
X635000Y367567D01*
X634750Y367817D01*
X634583Y368108D01*
X634500Y368400D01*
Y368692D01*
X634583Y368983D01*
X634708Y369233D01*
X634875Y369442D01*
G01X634500Y371500D02*
X637000D01*
X636500Y371000D01*
G01X634500D02*
Y372000D01*
G01Y374517D02*
X635042Y374600D01*
X635500Y374725D01*
X635917Y374892D01*
X636375Y375100D01*
X637000Y375433D01*
Y373767D01*
G01X634500Y377617D02*
X635042Y377700D01*
X635500Y377825D01*
X635917Y377992D01*
X636375Y378200D01*
X637000Y378533D01*
Y376867D01*
G01X629500Y364467D02*
X632000D01*
Y365467D01*
X631875Y365800D01*
X631583Y366050D01*
X631250Y366133D01*
X630917Y366050D01*
X630667Y365842D01*
X630542Y365467D01*
Y364467D01*
G01X631792Y369317D02*
X631917Y369067D01*
X632000Y368775D01*
Y368442D01*
X631875Y368067D01*
X631667Y367775D01*
X631417Y367567D01*
X631000Y367400D01*
X630625Y367358D01*
X630250Y367442D01*
X630000Y367567D01*
X629750Y367817D01*
X629583Y368108D01*
X629500Y368400D01*
Y368692D01*
X629583Y368983D01*
X629708Y369233D01*
X629875Y369442D01*
G01X629500Y371500D02*
X632000D01*
X631500Y371000D01*
G01X629500D02*
Y372000D01*
G01Y374517D02*
X630042Y374600D01*
X630500Y374725D01*
X630917Y374892D01*
X631375Y375100D01*
X632000Y375433D01*
Y373767D01*
G01X629500Y377700D02*
X629542Y377992D01*
X629667Y378325D01*
X629875Y378533D01*
X630167Y378617D01*
X630458Y378533D01*
X630708Y378283D01*
X630833Y377908D01*
Y377492D01*
X630917Y377242D01*
X631125Y377033D01*
X631417Y376950D01*
X631708Y377075D01*
X631917Y377367D01*
X632000Y377700D01*
X631917Y378033D01*
X631708Y378325D01*
X631417Y378450D01*
X631125Y378367D01*
X630917Y378158D01*
X630833Y377908D01*
Y377492D01*
X630708Y377117D01*
X630458Y376867D01*
X630167Y376783D01*
X629875Y376867D01*
X629667Y377075D01*
X629542Y377408D01*
X629500Y377700D01*
G01X640333Y438425D02*
X640125Y438758D01*
X640000Y439133D01*
Y439467D01*
X640125Y439800D01*
X640333Y440050D01*
X640625Y440175D01*
X640917Y440092D01*
X641167Y439883D01*
X641333Y439508D01*
X641417Y439008D01*
X641583Y438717D01*
X641875Y438592D01*
X642167Y438675D01*
X642375Y438883D01*
X642500Y439175D01*
Y439467D01*
X642417Y439758D01*
X642208Y440008D01*
G01X640000Y441567D02*
X642500D01*
Y442608D01*
X642375Y442942D01*
X642208Y443150D01*
X641875Y443233D01*
X641542Y443150D01*
X641333Y442900D01*
X641208Y442608D01*
Y441567D01*
G01Y442608D02*
X640000Y443233D01*
G01Y445500D02*
X640042Y445792D01*
X640167Y446125D01*
X640375Y446333D01*
X640667Y446417D01*
X640958Y446333D01*
X641208Y446083D01*
X641333Y445708D01*
Y445292D01*
X641417Y445042D01*
X641625Y444833D01*
X641917Y444750D01*
X642208Y444875D01*
X642417Y445167D01*
X642500Y445500D01*
X642417Y445833D01*
X642208Y446125D01*
X641917Y446250D01*
X641625Y446167D01*
X641417Y445958D01*
X641333Y445708D01*
Y445292D01*
X641208Y444917D01*
X640958Y444667D01*
X640667Y444583D01*
X640375Y444667D01*
X640167Y444875D01*
X640042Y445208D01*
X640000Y445500D01*
G01X640375Y447683D02*
X640167Y447933D01*
X640042Y448225D01*
X640000Y448600D01*
X640083Y448975D01*
X640250Y449267D01*
X640542Y449475D01*
X640875Y449517D01*
X641208Y449433D01*
X641417Y449225D01*
X641583Y448933D01*
X641625Y448642D01*
X641583Y448350D01*
X641417Y447975D01*
X642500Y448100D01*
Y449225D01*
G01X640375Y450783D02*
X640167Y451033D01*
X640042Y451325D01*
X640000Y451700D01*
X640083Y452075D01*
X640250Y452367D01*
X640542Y452575D01*
X640875Y452617D01*
X641208Y452533D01*
X641417Y452325D01*
X641583Y452033D01*
X641625Y451742D01*
X641583Y451450D01*
X641417Y451075D01*
X642500Y451200D01*
Y452325D01*
G01X635833Y438425D02*
X635625Y438758D01*
X635500Y439133D01*
Y439467D01*
X635625Y439800D01*
X635833Y440050D01*
X636125Y440175D01*
X636417Y440092D01*
X636667Y439883D01*
X636833Y439508D01*
X636917Y439008D01*
X637083Y438717D01*
X637375Y438592D01*
X637667Y438675D01*
X637875Y438883D01*
X638000Y439175D01*
Y439467D01*
X637917Y439758D01*
X637708Y440008D01*
G01X635500Y441567D02*
X638000D01*
Y442608D01*
X637875Y442942D01*
X637708Y443150D01*
X637375Y443233D01*
X637042Y443150D01*
X636833Y442900D01*
X636708Y442608D01*
Y441567D01*
G01Y442608D02*
X635500Y443233D01*
G01Y445500D02*
X635542Y445792D01*
X635667Y446125D01*
X635875Y446333D01*
X636167Y446417D01*
X636458Y446333D01*
X636708Y446083D01*
X636833Y445708D01*
Y445292D01*
X636917Y445042D01*
X637125Y444833D01*
X637417Y444750D01*
X637708Y444875D01*
X637917Y445167D01*
X638000Y445500D01*
X637917Y445833D01*
X637708Y446125D01*
X637417Y446250D01*
X637125Y446167D01*
X636917Y445958D01*
X636833Y445708D01*
Y445292D01*
X636708Y444917D01*
X636458Y444667D01*
X636167Y444583D01*
X635875Y444667D01*
X635667Y444875D01*
X635542Y445208D01*
X635500Y445500D01*
G01X635875Y447683D02*
X635667Y447933D01*
X635542Y448225D01*
X635500Y448600D01*
X635583Y448975D01*
X635750Y449267D01*
X636042Y449475D01*
X636375Y449517D01*
X636708Y449433D01*
X636917Y449225D01*
X637083Y448933D01*
X637125Y448642D01*
X637083Y448350D01*
X636917Y447975D01*
X638000Y448100D01*
Y449225D01*
G01X635500Y452200D02*
X638000D01*
X636208Y450658D01*
Y452742D01*
G01X634833Y456975D02*
X634625Y457308D01*
X634500Y457683D01*
Y458017D01*
X634625Y458350D01*
X634833Y458600D01*
X635125Y458725D01*
X635417Y458642D01*
X635667Y458433D01*
X635833Y458058D01*
X635917Y457558D01*
X636083Y457267D01*
X636375Y457142D01*
X636667Y457225D01*
X636875Y457433D01*
X637000Y457725D01*
Y458017D01*
X636917Y458308D01*
X636708Y458558D01*
G01X634500Y460950D02*
X634542Y460617D01*
X634708Y460325D01*
X634958Y460075D01*
X635250Y459908D01*
X635583Y459825D01*
X635917D01*
X636250Y459908D01*
X636542Y460075D01*
X636792Y460325D01*
X636958Y460617D01*
X637000Y460950D01*
X636958Y461283D01*
X636792Y461575D01*
X636542Y461825D01*
X636250Y461992D01*
X635917Y462075D01*
X635583D01*
X635250Y461992D01*
X634958Y461825D01*
X634708Y461575D01*
X634542Y461283D01*
X634500Y460950D01*
G01X635167Y461283D02*
X634500Y461783D01*
G01Y464050D02*
X637000D01*
X636500Y463550D01*
G01X634500D02*
Y464550D01*
G01X636583Y466358D02*
X636833Y466608D01*
X636958Y466900D01*
X637000Y467233D01*
X636917Y467650D01*
X636708Y467942D01*
X636458Y468025D01*
X636208Y467983D01*
X636000Y467817D01*
X635583Y466983D01*
X635292Y466608D01*
X634875Y466358D01*
X634500Y466275D01*
Y468025D01*
G01X639000Y455500D02*
Y469500D01*
G01X652000Y455500D02*
X639000D01*
G01Y469500D02*
X652000D01*
G01X640333Y479425D02*
X640125Y479758D01*
X640000Y480133D01*
Y480467D01*
X640125Y480800D01*
X640333Y481050D01*
X640625Y481175D01*
X640917Y481092D01*
X641167Y480883D01*
X641333Y480508D01*
X641417Y480008D01*
X641583Y479717D01*
X641875Y479592D01*
X642167Y479675D01*
X642375Y479883D01*
X642500Y480175D01*
Y480467D01*
X642417Y480758D01*
X642208Y481008D01*
G01X640000Y482567D02*
X642500D01*
Y483608D01*
X642375Y483942D01*
X642208Y484150D01*
X641875Y484233D01*
X641542Y484150D01*
X641333Y483900D01*
X641208Y483608D01*
Y482567D01*
G01Y483608D02*
X640000Y484233D01*
G01Y486500D02*
X640042Y486792D01*
X640167Y487125D01*
X640375Y487333D01*
X640667Y487417D01*
X640958Y487333D01*
X641208Y487083D01*
X641333Y486708D01*
Y486292D01*
X641417Y486042D01*
X641625Y485833D01*
X641917Y485750D01*
X642208Y485875D01*
X642417Y486167D01*
X642500Y486500D01*
X642417Y486833D01*
X642208Y487125D01*
X641917Y487250D01*
X641625Y487167D01*
X641417Y486958D01*
X641333Y486708D01*
Y486292D01*
X641208Y485917D01*
X640958Y485667D01*
X640667Y485583D01*
X640375Y485667D01*
X640167Y485875D01*
X640042Y486208D01*
X640000Y486500D01*
G01X640375Y488683D02*
X640167Y488933D01*
X640042Y489225D01*
X640000Y489600D01*
X640083Y489975D01*
X640250Y490267D01*
X640542Y490475D01*
X640875Y490517D01*
X641208Y490433D01*
X641417Y490225D01*
X641583Y489933D01*
X641625Y489642D01*
X641583Y489350D01*
X641417Y488975D01*
X642500Y489100D01*
Y490225D01*
G01X640000Y492700D02*
X640042Y492992D01*
X640167Y493325D01*
X640375Y493533D01*
X640667Y493617D01*
X640958Y493533D01*
X641208Y493283D01*
X641333Y492908D01*
Y492492D01*
X641417Y492242D01*
X641625Y492033D01*
X641917Y491950D01*
X642208Y492075D01*
X642417Y492367D01*
X642500Y492700D01*
X642417Y493033D01*
X642208Y493325D01*
X641917Y493450D01*
X641625Y493367D01*
X641417Y493158D01*
X641333Y492908D01*
Y492492D01*
X641208Y492117D01*
X640958Y491867D01*
X640667Y491783D01*
X640375Y491867D01*
X640167Y492075D01*
X640042Y492408D01*
X640000Y492700D01*
G01X639000Y477700D02*
X643000D01*
Y470300D01*
G01X646000Y364967D02*
X648500D01*
Y365967D01*
X648375Y366300D01*
X648083Y366550D01*
X647750Y366633D01*
X647417Y366550D01*
X647167Y366342D01*
X647042Y365967D01*
Y364967D01*
G01X648292Y369817D02*
X648417Y369567D01*
X648500Y369275D01*
Y368942D01*
X648375Y368567D01*
X648167Y368275D01*
X647917Y368067D01*
X647500Y367900D01*
X647125Y367858D01*
X646750Y367942D01*
X646500Y368067D01*
X646250Y368317D01*
X646083Y368608D01*
X646000Y368900D01*
Y369192D01*
X646083Y369483D01*
X646208Y369733D01*
X646375Y369942D01*
G01X646000Y372000D02*
X648500D01*
X648000Y371500D01*
G01X646000D02*
Y372500D01*
G01Y375100D02*
X646042Y375392D01*
X646167Y375725D01*
X646375Y375933D01*
X646667Y376017D01*
X646958Y375933D01*
X647208Y375683D01*
X647333Y375308D01*
Y374892D01*
X647417Y374642D01*
X647625Y374433D01*
X647917Y374350D01*
X648208Y374475D01*
X648417Y374767D01*
X648500Y375100D01*
X648417Y375433D01*
X648208Y375725D01*
X647917Y375850D01*
X647625Y375767D01*
X647417Y375558D01*
X647333Y375308D01*
Y374892D01*
X647208Y374517D01*
X646958Y374267D01*
X646667Y374183D01*
X646375Y374267D01*
X646167Y374475D01*
X646042Y374808D01*
X646000Y375100D01*
G01X648083Y377408D02*
X648333Y377658D01*
X648458Y377950D01*
X648500Y378283D01*
X648417Y378700D01*
X648208Y378992D01*
X647958Y379075D01*
X647708Y379033D01*
X647500Y378867D01*
X647083Y378033D01*
X646792Y377658D01*
X646375Y377408D01*
X646000Y377325D01*
Y379075D01*
G01X653600Y427000D02*
X653933Y427042D01*
X654225Y427208D01*
X654475Y427458D01*
X654642Y427750D01*
X654725Y428083D01*
Y428417D01*
X654642Y428750D01*
X654475Y429042D01*
X654225Y429292D01*
X653933Y429458D01*
X653600Y429500D01*
X653267Y429458D01*
X652975Y429292D01*
X652725Y429042D01*
X652558Y428750D01*
X652475Y428417D01*
Y428083D01*
X652558Y427750D01*
X652725Y427458D01*
X652975Y427208D01*
X653267Y427042D01*
X653600Y427000D01*
G01X653267Y427667D02*
X652767Y427000D01*
G01X650500D02*
Y429500D01*
X651000Y429000D01*
G01Y427000D02*
X650000D01*
G01X646900D02*
Y429500D01*
X648442Y427708D01*
X646358D01*
G01X657500Y445500D02*
Y431500D01*
G01X644500D02*
Y445500D01*
G01X657500Y431500D02*
X644500D01*
G01Y445500D02*
X657500D01*
G01X653000Y446800D02*
X649000D01*
Y454200D01*
G01X644500D02*
X648500D01*
Y446800D01*
G01X652000Y469500D02*
Y455500D01*
G01X656000Y470967D02*
X658500D01*
Y471967D01*
X658375Y472300D01*
X658083Y472550D01*
X657750Y472633D01*
X657417Y472550D01*
X657167Y472342D01*
X657042Y471967D01*
Y470967D01*
G01X658292Y475817D02*
X658417Y475567D01*
X658500Y475275D01*
Y474942D01*
X658375Y474567D01*
X658167Y474275D01*
X657917Y474067D01*
X657500Y473900D01*
X657125Y473858D01*
X656750Y473942D01*
X656500Y474067D01*
X656250Y474317D01*
X656083Y474608D01*
X656000Y474900D01*
Y475192D01*
X656083Y475483D01*
X656208Y475733D01*
X656375Y475942D01*
G01X656000Y478000D02*
X658500D01*
X658000Y477500D01*
G01X656000D02*
Y478500D01*
G01Y481100D02*
X656042Y481392D01*
X656167Y481725D01*
X656375Y481933D01*
X656667Y482017D01*
X656958Y481933D01*
X657208Y481683D01*
X657333Y481308D01*
Y480892D01*
X657417Y480642D01*
X657625Y480433D01*
X657917Y480350D01*
X658208Y480475D01*
X658417Y480767D01*
X658500Y481100D01*
X658417Y481433D01*
X658208Y481725D01*
X657917Y481850D01*
X657625Y481767D01*
X657417Y481558D01*
X657333Y481308D01*
Y480892D01*
X657208Y480517D01*
X656958Y480267D01*
X656667Y480183D01*
X656375Y480267D01*
X656167Y480475D01*
X656042Y480808D01*
X656000Y481100D01*
G01Y484700D02*
X658500D01*
X656708Y483158D01*
Y485242D01*
G01X644833Y479425D02*
X644625Y479758D01*
X644500Y480133D01*
Y480467D01*
X644625Y480800D01*
X644833Y481050D01*
X645125Y481175D01*
X645417Y481092D01*
X645667Y480883D01*
X645833Y480508D01*
X645917Y480008D01*
X646083Y479717D01*
X646375Y479592D01*
X646667Y479675D01*
X646875Y479883D01*
X647000Y480175D01*
Y480467D01*
X646917Y480758D01*
X646708Y481008D01*
G01X644500Y482567D02*
X647000D01*
Y483608D01*
X646875Y483942D01*
X646708Y484150D01*
X646375Y484233D01*
X646042Y484150D01*
X645833Y483900D01*
X645708Y483608D01*
Y482567D01*
G01Y483608D02*
X644500Y484233D01*
G01Y486500D02*
X644542Y486792D01*
X644667Y487125D01*
X644875Y487333D01*
X645167Y487417D01*
X645458Y487333D01*
X645708Y487083D01*
X645833Y486708D01*
Y486292D01*
X645917Y486042D01*
X646125Y485833D01*
X646417Y485750D01*
X646708Y485875D01*
X646917Y486167D01*
X647000Y486500D01*
X646917Y486833D01*
X646708Y487125D01*
X646417Y487250D01*
X646125Y487167D01*
X645917Y486958D01*
X645833Y486708D01*
Y486292D01*
X645708Y485917D01*
X645458Y485667D01*
X645167Y485583D01*
X644875Y485667D01*
X644667Y485875D01*
X644542Y486208D01*
X644500Y486500D01*
G01X644875Y488683D02*
X644667Y488933D01*
X644542Y489225D01*
X644500Y489600D01*
X644583Y489975D01*
X644750Y490267D01*
X645042Y490475D01*
X645375Y490517D01*
X645708Y490433D01*
X645917Y490225D01*
X646083Y489933D01*
X646125Y489642D01*
X646083Y489350D01*
X645917Y488975D01*
X647000Y489100D01*
Y490225D01*
G01X645542Y491908D02*
X645833Y492200D01*
X646000Y492450D01*
X646083Y492783D01*
X646000Y493075D01*
X645833Y493283D01*
X645583Y493450D01*
X645292Y493492D01*
X645042Y493450D01*
X644792Y493283D01*
X644583Y493033D01*
X644500Y492742D01*
X644583Y492408D01*
X644833Y492117D01*
X645208Y491950D01*
X645625Y491908D01*
X646167Y491992D01*
X646458Y492117D01*
X646750Y492325D01*
X646958Y492617D01*
X647000Y492908D01*
X646917Y493200D01*
X646708Y493408D01*
G01X647500Y470300D02*
X643500D01*
Y477700D01*
G01X674533Y435500D02*
Y438000D01*
X673533D01*
X673200Y437875D01*
X672950Y437583D01*
X672867Y437250D01*
X672950Y436917D01*
X673158Y436667D01*
X673533Y436542D01*
X674533D01*
G01X669683Y437792D02*
X669933Y437917D01*
X670225Y438000D01*
X670558D01*
X670933Y437875D01*
X671225Y437667D01*
X671433Y437417D01*
X671600Y437000D01*
X671642Y436625D01*
X671558Y436250D01*
X671433Y436000D01*
X671183Y435750D01*
X670892Y435583D01*
X670600Y435500D01*
X670308D01*
X670017Y435583D01*
X669767Y435708D01*
X669558Y435875D01*
G01X667500Y435500D02*
Y438000D01*
X668000Y437500D01*
G01Y435500D02*
X667000D01*
G01X664400D02*
X664108Y435542D01*
X663775Y435667D01*
X663567Y435875D01*
X663483Y436167D01*
X663567Y436458D01*
X663817Y436708D01*
X664192Y436833D01*
X664608D01*
X664858Y436917D01*
X665067Y437125D01*
X665150Y437417D01*
X665025Y437708D01*
X664733Y437917D01*
X664400Y438000D01*
X664067Y437917D01*
X663775Y437708D01*
X663650Y437417D01*
X663733Y437125D01*
X663942Y436917D01*
X664192Y436833D01*
X664608D01*
X664983Y436708D01*
X665233Y436458D01*
X665317Y436167D01*
X665233Y435875D01*
X665025Y435667D01*
X664692Y435542D01*
X664400Y435500D01*
G01X662217Y435875D02*
X661967Y435667D01*
X661675Y435542D01*
X661300Y435500D01*
X660925Y435583D01*
X660633Y435750D01*
X660425Y436042D01*
X660383Y436375D01*
X660467Y436708D01*
X660675Y436917D01*
X660967Y437083D01*
X661258Y437125D01*
X661550Y437083D01*
X661925Y436917D01*
X661800Y438000D01*
X660675D01*
G01X675500Y472467D02*
X678000D01*
Y473467D01*
X677875Y473800D01*
X677583Y474050D01*
X677250Y474133D01*
X676917Y474050D01*
X676667Y473842D01*
X676542Y473467D01*
Y472467D01*
G01X675500Y475567D02*
X678000D01*
Y476608D01*
X677875Y476942D01*
X677708Y477150D01*
X677375Y477233D01*
X677042Y477150D01*
X676833Y476900D01*
X676708Y476608D01*
Y475567D01*
G01Y476608D02*
X675500Y477233D01*
G01Y479500D02*
X678000D01*
X677500Y479000D01*
G01X675500D02*
Y480000D01*
G01X675875Y481683D02*
X675667Y481933D01*
X675542Y482225D01*
X675500Y482600D01*
X675583Y482975D01*
X675750Y483267D01*
X676042Y483475D01*
X676375Y483517D01*
X676708Y483433D01*
X676917Y483225D01*
X677083Y482933D01*
X677125Y482642D01*
X677083Y482350D01*
X676917Y481975D01*
X678000Y482100D01*
Y483225D01*
G01Y485700D02*
X677917Y485367D01*
X677708Y485117D01*
X677458Y484950D01*
X677125Y484825D01*
X676750Y484783D01*
X676375Y484825D01*
X676042Y484950D01*
X675792Y485117D01*
X675583Y485367D01*
X675500Y485700D01*
X675583Y486033D01*
X675792Y486283D01*
X676042Y486450D01*
X676375Y486575D01*
X676750Y486617D01*
X677125Y486575D01*
X677458Y486450D01*
X677708Y486283D01*
X677917Y486033D01*
X678000Y485700D01*
G01X683000Y387967D02*
X685500D01*
Y388967D01*
X685375Y389300D01*
X685083Y389550D01*
X684750Y389633D01*
X684417Y389550D01*
X684167Y389342D01*
X684042Y388967D01*
Y387967D01*
G01X685292Y392817D02*
X685417Y392567D01*
X685500Y392275D01*
Y391942D01*
X685375Y391567D01*
X685167Y391275D01*
X684917Y391067D01*
X684500Y390900D01*
X684125Y390858D01*
X683750Y390942D01*
X683500Y391067D01*
X683250Y391317D01*
X683083Y391608D01*
X683000Y391900D01*
Y392192D01*
X683083Y392483D01*
X683208Y392733D01*
X683375Y392942D01*
G01X683000Y395000D02*
X685500D01*
X685000Y394500D01*
G01X683000D02*
Y395500D01*
G01Y398100D02*
X683042Y398392D01*
X683167Y398725D01*
X683375Y398933D01*
X683667Y399017D01*
X683958Y398933D01*
X684208Y398683D01*
X684333Y398308D01*
Y397892D01*
X684417Y397642D01*
X684625Y397433D01*
X684917Y397350D01*
X685208Y397475D01*
X685417Y397767D01*
X685500Y398100D01*
X685417Y398433D01*
X685208Y398725D01*
X684917Y398850D01*
X684625Y398767D01*
X684417Y398558D01*
X684333Y398308D01*
Y397892D01*
X684208Y397517D01*
X683958Y397267D01*
X683667Y397183D01*
X683375Y397267D01*
X683167Y397475D01*
X683042Y397808D01*
X683000Y398100D01*
G01X684042Y400408D02*
X684333Y400700D01*
X684500Y400950D01*
X684583Y401283D01*
X684500Y401575D01*
X684333Y401783D01*
X684083Y401950D01*
X683792Y401992D01*
X683542Y401950D01*
X683292Y401783D01*
X683083Y401533D01*
X683000Y401242D01*
X683083Y400908D01*
X683333Y400617D01*
X683708Y400450D01*
X684125Y400408D01*
X684667Y400492D01*
X684958Y400617D01*
X685250Y400825D01*
X685458Y401117D01*
X685500Y401408D01*
X685417Y401700D01*
X685208Y401908D01*
G01X683000Y404467D02*
X685500D01*
Y405467D01*
X685375Y405800D01*
X685083Y406050D01*
X684750Y406133D01*
X684417Y406050D01*
X684167Y405842D01*
X684042Y405467D01*
Y404467D01*
G01X683000Y407567D02*
X685500D01*
Y408608D01*
X685375Y408942D01*
X685208Y409150D01*
X684875Y409233D01*
X684542Y409150D01*
X684333Y408900D01*
X684208Y408608D01*
Y407567D01*
G01Y408608D02*
X683000Y409233D01*
G01Y411500D02*
X685500D01*
X685000Y411000D01*
G01X683000D02*
Y412000D01*
G01X683375Y413683D02*
X683167Y413933D01*
X683042Y414225D01*
X683000Y414600D01*
X683083Y414975D01*
X683250Y415267D01*
X683542Y415475D01*
X683875Y415517D01*
X684208Y415433D01*
X684417Y415225D01*
X684583Y414933D01*
X684625Y414642D01*
X684583Y414350D01*
X684417Y413975D01*
X685500Y414100D01*
Y415225D01*
G01X683375Y416783D02*
X683167Y417033D01*
X683042Y417325D01*
X683000Y417700D01*
X683083Y418075D01*
X683250Y418367D01*
X683542Y418575D01*
X683875Y418617D01*
X684208Y418533D01*
X684417Y418325D01*
X684583Y418033D01*
X684625Y417742D01*
X684583Y417450D01*
X684417Y417075D01*
X685500Y417200D01*
Y418325D01*
G01X676500Y412200D02*
X680500D01*
Y404800D01*
G01X694533Y437500D02*
Y440000D01*
X693533D01*
X693200Y439875D01*
X692950Y439583D01*
X692867Y439250D01*
X692950Y438917D01*
X693158Y438667D01*
X693533Y438542D01*
X694533D01*
G01X691433Y437500D02*
Y440000D01*
X690392D01*
X690058Y439875D01*
X689850Y439708D01*
X689767Y439375D01*
X689850Y439042D01*
X690100Y438833D01*
X690392Y438708D01*
X691433D01*
G01X690392D02*
X689767Y437500D01*
G01X687500D02*
Y440000D01*
X688000Y439500D01*
G01Y437500D02*
X687000D01*
G01X685317Y437875D02*
X685067Y437667D01*
X684775Y437542D01*
X684400Y437500D01*
X684025Y437583D01*
X683733Y437750D01*
X683525Y438042D01*
X683483Y438375D01*
X683567Y438708D01*
X683775Y438917D01*
X684067Y439083D01*
X684358Y439125D01*
X684650Y439083D01*
X685025Y438917D01*
X684900Y440000D01*
X683775D01*
G01X682217Y438000D02*
X681967Y437708D01*
X681633Y437542D01*
X681258Y437500D01*
X680925Y437542D01*
X680592Y437750D01*
X680383Y438000D01*
X680342Y438250D01*
X680425Y438542D01*
X680717Y438750D01*
X681008Y438833D01*
X681383D01*
G01X681008D02*
X680758Y438958D01*
X680550Y439167D01*
X680467Y439417D01*
X680550Y439667D01*
X680758Y439875D01*
X681133Y440000D01*
X681508Y439958D01*
X681883Y439792D01*
G01X677800Y442500D02*
X683000D01*
G01X677800Y449500D02*
X685600D01*
G01X677800Y442500D02*
Y449500D01*
G01X691200Y442500D02*
X682500D01*
G01X684800Y449500D02*
X691200D01*
G01X712981Y108292D02*
X713231Y108417D01*
X713523Y108500D01*
X713856D01*
X714231Y108375D01*
X714523Y108167D01*
X714731Y107917D01*
X714898Y107500D01*
X714940Y107125D01*
X714856Y106750D01*
X714731Y106500D01*
X714481Y106250D01*
X714190Y106083D01*
X713898Y106000D01*
X713606D01*
X713315Y106083D01*
X713065Y106208D01*
X712856Y106375D01*
G01X711590Y108083D02*
X711340Y108333D01*
X711048Y108458D01*
X710715Y108500D01*
X710298Y108417D01*
X710006Y108208D01*
X709923Y107958D01*
X709965Y107708D01*
X710131Y107500D01*
X710965Y107083D01*
X711340Y106792D01*
X711590Y106375D01*
X711673Y106000D01*
X709923D01*
G01X708490Y108083D02*
X708240Y108333D01*
X707948Y108458D01*
X707615Y108500D01*
X707198Y108417D01*
X706906Y108208D01*
X706823Y107958D01*
X706865Y107708D01*
X707031Y107500D01*
X707865Y107083D01*
X708240Y106792D01*
X708490Y106375D01*
X708573Y106000D01*
X706823D01*
G01X704681D02*
X704598Y106542D01*
X704473Y107000D01*
X704306Y107417D01*
X704098Y107875D01*
X703765Y108500D01*
X705431D01*
G01X700515Y117333D02*
X700348Y117458D01*
X700223Y117667D01*
X700140Y117958D01*
X700223Y118208D01*
X700390Y118375D01*
X700681Y118500D01*
X701806D01*
Y116000D01*
X700431D01*
X700140Y116167D01*
X699973Y116417D01*
X699890Y116708D01*
X699973Y117000D01*
X700223Y117250D01*
X700515Y117333D01*
X701806D01*
G01X696831Y118292D02*
X697081Y118417D01*
X697373Y118500D01*
X697706D01*
X698081Y118375D01*
X698373Y118167D01*
X698581Y117917D01*
X698748Y117500D01*
X698790Y117125D01*
X698706Y116750D01*
X698581Y116500D01*
X698331Y116250D01*
X698040Y116083D01*
X697748Y116000D01*
X697456D01*
X697165Y116083D01*
X696915Y116208D01*
X696706Y116375D01*
G01X694648Y116000D02*
Y118500D01*
X695148Y118000D01*
G01Y116000D02*
X694148D01*
G01X711949Y139576D02*
X712199Y139701D01*
X712491Y139784D01*
X712824D01*
X713199Y139659D01*
X713491Y139451D01*
X713699Y139201D01*
X713866Y138784D01*
X713908Y138409D01*
X713824Y138034D01*
X713699Y137784D01*
X713449Y137534D01*
X713158Y137367D01*
X712866Y137284D01*
X712574D01*
X712283Y137367D01*
X712033Y137492D01*
X711824Y137659D01*
G01X710558Y139367D02*
X710308Y139617D01*
X710016Y139742D01*
X709683Y139784D01*
X709266Y139701D01*
X708974Y139492D01*
X708891Y139242D01*
X708933Y138992D01*
X709099Y138784D01*
X709933Y138367D01*
X710308Y138076D01*
X710558Y137659D01*
X710641Y137284D01*
X708891D01*
G01X707458Y139367D02*
X707208Y139617D01*
X706916Y139742D01*
X706583Y139784D01*
X706166Y139701D01*
X705874Y139492D01*
X705791Y139242D01*
X705833Y138992D01*
X705999Y138784D01*
X706833Y138367D01*
X707208Y138076D01*
X707458Y137659D01*
X707541Y137284D01*
X705791D01*
G01X704483Y137784D02*
X704233Y137492D01*
X703899Y137326D01*
X703524Y137284D01*
X703191Y137326D01*
X702858Y137534D01*
X702649Y137784D01*
X702608Y138034D01*
X702691Y138326D01*
X702983Y138534D01*
X703274Y138617D01*
X703649D01*
G01X703274D02*
X703024Y138742D01*
X702816Y138951D01*
X702733Y139201D01*
X702816Y139451D01*
X703024Y139659D01*
X703399Y139784D01*
X703774Y139742D01*
X704149Y139576D01*
G01X711481Y151792D02*
X711731Y151917D01*
X712023Y152000D01*
X712356D01*
X712731Y151875D01*
X713023Y151667D01*
X713231Y151417D01*
X713398Y151000D01*
X713440Y150625D01*
X713356Y150250D01*
X713231Y150000D01*
X712981Y149750D01*
X712690Y149583D01*
X712398Y149500D01*
X712106D01*
X711815Y149583D01*
X711565Y149708D01*
X711356Y149875D01*
G01X710090Y151583D02*
X709840Y151833D01*
X709548Y151958D01*
X709215Y152000D01*
X708798Y151917D01*
X708506Y151708D01*
X708423Y151458D01*
X708465Y151208D01*
X708631Y151000D01*
X709465Y150583D01*
X709840Y150292D01*
X710090Y149875D01*
X710173Y149500D01*
X708423D01*
G01X707115Y150000D02*
X706865Y149708D01*
X706531Y149542D01*
X706156Y149500D01*
X705823Y149542D01*
X705490Y149750D01*
X705281Y150000D01*
X705240Y150250D01*
X705323Y150542D01*
X705615Y150750D01*
X705906Y150833D01*
X706281D01*
G01X705906D02*
X705656Y150958D01*
X705448Y151167D01*
X705365Y151417D01*
X705448Y151667D01*
X705656Y151875D01*
X706031Y152000D01*
X706406Y151958D01*
X706781Y151792D01*
G01X703098Y152000D02*
X703431Y151917D01*
X703681Y151708D01*
X703848Y151458D01*
X703973Y151125D01*
X704015Y150750D01*
X703973Y150375D01*
X703848Y150042D01*
X703681Y149792D01*
X703431Y149583D01*
X703098Y149500D01*
X702765Y149583D01*
X702515Y149792D01*
X702348Y150042D01*
X702223Y150375D01*
X702181Y150750D01*
X702223Y151125D01*
X702348Y151458D01*
X702515Y151708D01*
X702765Y151917D01*
X703098Y152000D01*
G01X711949Y143576D02*
X712199Y143701D01*
X712491Y143784D01*
X712824D01*
X713199Y143659D01*
X713491Y143451D01*
X713699Y143201D01*
X713866Y142784D01*
X713908Y142409D01*
X713824Y142034D01*
X713699Y141784D01*
X713449Y141534D01*
X713158Y141367D01*
X712866Y141284D01*
X712574D01*
X712283Y141367D01*
X712033Y141492D01*
X711824Y141659D01*
G01X710558Y143367D02*
X710308Y143617D01*
X710016Y143742D01*
X709683Y143784D01*
X709266Y143701D01*
X708974Y143492D01*
X708891Y143242D01*
X708933Y142992D01*
X709099Y142784D01*
X709933Y142367D01*
X710308Y142076D01*
X710558Y141659D01*
X710641Y141284D01*
X708891D01*
G01X707458Y143367D02*
X707208Y143617D01*
X706916Y143742D01*
X706583Y143784D01*
X706166Y143701D01*
X705874Y143492D01*
X705791Y143242D01*
X705833Y142992D01*
X705999Y142784D01*
X706833Y142367D01*
X707208Y142076D01*
X707458Y141659D01*
X707541Y141284D01*
X705791D01*
G01X704358Y143367D02*
X704108Y143617D01*
X703816Y143742D01*
X703483Y143784D01*
X703066Y143701D01*
X702774Y143492D01*
X702691Y143242D01*
X702733Y142992D01*
X702899Y142784D01*
X703733Y142367D01*
X704108Y142076D01*
X704358Y141659D01*
X704441Y141284D01*
X702691D01*
G01X711949Y147576D02*
X712199Y147701D01*
X712491Y147784D01*
X712824D01*
X713199Y147659D01*
X713491Y147451D01*
X713699Y147201D01*
X713866Y146784D01*
X713908Y146409D01*
X713824Y146034D01*
X713699Y145784D01*
X713449Y145534D01*
X713158Y145367D01*
X712866Y145284D01*
X712574D01*
X712283Y145367D01*
X712033Y145492D01*
X711824Y145659D01*
G01X710558Y147367D02*
X710308Y147617D01*
X710016Y147742D01*
X709683Y147784D01*
X709266Y147701D01*
X708974Y147492D01*
X708891Y147242D01*
X708933Y146992D01*
X709099Y146784D01*
X709933Y146367D01*
X710308Y146076D01*
X710558Y145659D01*
X710641Y145284D01*
X708891D01*
G01X707458Y147367D02*
X707208Y147617D01*
X706916Y147742D01*
X706583Y147784D01*
X706166Y147701D01*
X705874Y147492D01*
X705791Y147242D01*
X705833Y146992D01*
X705999Y146784D01*
X706833Y146367D01*
X707208Y146076D01*
X707458Y145659D01*
X707541Y145284D01*
X705791D01*
G01X703566Y147784D02*
X703899Y147701D01*
X704149Y147492D01*
X704316Y147242D01*
X704441Y146909D01*
X704483Y146534D01*
X704441Y146159D01*
X704316Y145826D01*
X704149Y145576D01*
X703899Y145367D01*
X703566Y145284D01*
X703233Y145367D01*
X702983Y145576D01*
X702816Y145826D01*
X702691Y146159D01*
X702649Y146534D01*
X702691Y146909D01*
X702816Y147242D01*
X702983Y147492D01*
X703233Y147701D01*
X703566Y147784D01*
G01X691200Y449500D02*
Y442500D01*
G01X740540Y106767D02*
X740665Y106517D01*
X740748Y106225D01*
Y105892D01*
X740623Y105517D01*
X740415Y105225D01*
X740165Y105017D01*
X739748Y104850D01*
X739373Y104808D01*
X738998Y104892D01*
X738748Y105017D01*
X738498Y105267D01*
X738331Y105558D01*
X738248Y105850D01*
Y106142D01*
X738331Y106433D01*
X738456Y106683D01*
X738623Y106892D01*
G01X740331Y108158D02*
X740581Y108408D01*
X740706Y108700D01*
X740748Y109033D01*
X740665Y109450D01*
X740456Y109742D01*
X740206Y109825D01*
X739956Y109783D01*
X739748Y109617D01*
X739331Y108783D01*
X739040Y108408D01*
X738623Y108158D01*
X738248Y108075D01*
Y109825D01*
G01X738748Y111133D02*
X738456Y111383D01*
X738290Y111717D01*
X738248Y112092D01*
X738290Y112425D01*
X738498Y112758D01*
X738748Y112967D01*
X738998Y113008D01*
X739290Y112925D01*
X739498Y112633D01*
X739581Y112342D01*
Y111967D01*
G01Y112342D02*
X739706Y112592D01*
X739915Y112800D01*
X740165Y112883D01*
X740415Y112800D01*
X740623Y112592D01*
X740748Y112217D01*
X740706Y111842D01*
X740540Y111467D01*
G01X738248Y115150D02*
X740748D01*
X740248Y114650D01*
G01X738248D02*
Y115650D01*
G01X740540Y143767D02*
X740665Y143517D01*
X740748Y143225D01*
Y142892D01*
X740623Y142517D01*
X740415Y142225D01*
X740165Y142017D01*
X739748Y141850D01*
X739373Y141808D01*
X738998Y141892D01*
X738748Y142017D01*
X738498Y142267D01*
X738331Y142558D01*
X738248Y142850D01*
Y143142D01*
X738331Y143433D01*
X738456Y143683D01*
X738623Y143892D01*
G01X740331Y145158D02*
X740581Y145408D01*
X740706Y145700D01*
X740748Y146033D01*
X740665Y146450D01*
X740456Y146742D01*
X740206Y146825D01*
X739956Y146783D01*
X739748Y146617D01*
X739331Y145783D01*
X739040Y145408D01*
X738623Y145158D01*
X738248Y145075D01*
Y146825D01*
G01X740331Y148258D02*
X740581Y148508D01*
X740706Y148800D01*
X740748Y149133D01*
X740665Y149550D01*
X740456Y149842D01*
X740206Y149925D01*
X739956Y149883D01*
X739748Y149717D01*
X739331Y148883D01*
X739040Y148508D01*
X738623Y148258D01*
X738248Y148175D01*
Y149925D01*
G01X739290Y151358D02*
X739581Y151650D01*
X739748Y151900D01*
X739831Y152233D01*
X739748Y152525D01*
X739581Y152733D01*
X739331Y152900D01*
X739040Y152942D01*
X738790Y152900D01*
X738540Y152733D01*
X738331Y152483D01*
X738248Y152192D01*
X738331Y151858D01*
X738581Y151567D01*
X738956Y151400D01*
X739373Y151358D01*
X739915Y151442D01*
X740206Y151567D01*
X740498Y151775D01*
X740706Y152067D01*
X740748Y152358D01*
X740665Y152650D01*
X740456Y152858D01*
G01X734008Y141051D02*
X734133Y140801D01*
X734216Y140509D01*
Y140176D01*
X734091Y139801D01*
X733883Y139509D01*
X733633Y139301D01*
X733216Y139134D01*
X732841Y139092D01*
X732466Y139176D01*
X732216Y139301D01*
X731966Y139551D01*
X731799Y139842D01*
X731716Y140134D01*
Y140426D01*
X731799Y140717D01*
X731924Y140967D01*
X732091Y141176D01*
G01X733799Y142442D02*
X734049Y142692D01*
X734174Y142984D01*
X734216Y143317D01*
X734133Y143734D01*
X733924Y144026D01*
X733674Y144109D01*
X733424Y144067D01*
X733216Y143901D01*
X732799Y143067D01*
X732508Y142692D01*
X732091Y142442D01*
X731716Y142359D01*
Y144109D01*
G01X733799Y145542D02*
X734049Y145792D01*
X734174Y146084D01*
X734216Y146417D01*
X734133Y146834D01*
X733924Y147126D01*
X733674Y147209D01*
X733424Y147167D01*
X733216Y147001D01*
X732799Y146167D01*
X732508Y145792D01*
X732091Y145542D01*
X731716Y145459D01*
Y147209D01*
G01X732008Y148726D02*
X731799Y149017D01*
X731716Y149351D01*
X731799Y149684D01*
X732049Y149976D01*
X732424Y150184D01*
X732799Y150267D01*
X733258D01*
X733633Y150184D01*
X733966Y149976D01*
X734133Y149726D01*
X734216Y149434D01*
X734133Y149101D01*
X733966Y148851D01*
X733716Y148684D01*
X733383Y148601D01*
X733091Y148684D01*
X732799Y148892D01*
X732633Y149142D01*
X732591Y149434D01*
X732674Y149767D01*
X732883Y150017D01*
X733258Y150267D01*
G01X729540Y141267D02*
X729665Y141017D01*
X729748Y140725D01*
Y140392D01*
X729623Y140017D01*
X729415Y139725D01*
X729165Y139517D01*
X728748Y139350D01*
X728373Y139308D01*
X727998Y139392D01*
X727748Y139517D01*
X727498Y139767D01*
X727331Y140058D01*
X727248Y140350D01*
Y140642D01*
X727331Y140933D01*
X727456Y141183D01*
X727623Y141392D01*
G01X729331Y142658D02*
X729581Y142908D01*
X729706Y143200D01*
X729748Y143533D01*
X729665Y143950D01*
X729456Y144242D01*
X729206Y144325D01*
X728956Y144283D01*
X728748Y144117D01*
X728331Y143283D01*
X728040Y142908D01*
X727623Y142658D01*
X727248Y142575D01*
Y144325D01*
G01X729331Y145758D02*
X729581Y146008D01*
X729706Y146300D01*
X729748Y146633D01*
X729665Y147050D01*
X729456Y147342D01*
X729206Y147425D01*
X728956Y147383D01*
X728748Y147217D01*
X728331Y146383D01*
X728040Y146008D01*
X727623Y145758D01*
X727248Y145675D01*
Y147425D01*
G01Y149650D02*
X729748D01*
X729248Y149150D01*
G01X727248D02*
Y150150D01*
G01X745040Y106767D02*
X745165Y106517D01*
X745248Y106225D01*
Y105892D01*
X745123Y105517D01*
X744915Y105225D01*
X744665Y105017D01*
X744248Y104850D01*
X743873Y104808D01*
X743498Y104892D01*
X743248Y105017D01*
X742998Y105267D01*
X742831Y105558D01*
X742748Y105850D01*
Y106142D01*
X742831Y106433D01*
X742956Y106683D01*
X743123Y106892D01*
G01X744831Y108158D02*
X745081Y108408D01*
X745206Y108700D01*
X745248Y109033D01*
X745165Y109450D01*
X744956Y109742D01*
X744706Y109825D01*
X744456Y109783D01*
X744248Y109617D01*
X743831Y108783D01*
X743540Y108408D01*
X743123Y108158D01*
X742748Y108075D01*
Y109825D01*
G01X744831Y111258D02*
X745081Y111508D01*
X745206Y111800D01*
X745248Y112133D01*
X745165Y112550D01*
X744956Y112842D01*
X744706Y112925D01*
X744456Y112883D01*
X744248Y112717D01*
X743831Y111883D01*
X743540Y111508D01*
X743123Y111258D01*
X742748Y111175D01*
Y112925D01*
G01Y115150D02*
X742790Y115442D01*
X742915Y115775D01*
X743123Y115983D01*
X743415Y116067D01*
X743706Y115983D01*
X743956Y115733D01*
X744081Y115358D01*
Y114942D01*
X744165Y114692D01*
X744373Y114483D01*
X744665Y114400D01*
X744956Y114525D01*
X745165Y114817D01*
X745248Y115150D01*
X745165Y115483D01*
X744956Y115775D01*
X744665Y115900D01*
X744373Y115817D01*
X744165Y115608D01*
X744081Y115358D01*
Y114942D01*
X743956Y114567D01*
X743706Y114317D01*
X743415Y114233D01*
X743123Y114317D01*
X742915Y114525D01*
X742790Y114858D01*
X742748Y115150D01*
G01X782983Y961500D02*
Y964000D01*
X781942D01*
X781608Y963875D01*
X781400Y963708D01*
X781317Y963375D01*
X781400Y963042D01*
X781650Y962833D01*
X781942Y962708D01*
X782983D01*
G01X781942D02*
X781317Y961500D01*
G01X779842Y962542D02*
X779550Y962833D01*
X779300Y963000D01*
X778967Y963083D01*
X778675Y963000D01*
X778467Y962833D01*
X778300Y962583D01*
X778258Y962292D01*
X778300Y962042D01*
X778467Y961792D01*
X778717Y961583D01*
X779008Y961500D01*
X779342Y961583D01*
X779633Y961833D01*
X779800Y962208D01*
X779842Y962625D01*
X779758Y963167D01*
X779633Y963458D01*
X779425Y963750D01*
X779133Y963958D01*
X778842Y964000D01*
X778550Y963917D01*
X778342Y963708D01*
G01X776742Y963583D02*
X776492Y963833D01*
X776200Y963958D01*
X775867Y964000D01*
X775450Y963917D01*
X775158Y963708D01*
X775075Y963458D01*
X775117Y963208D01*
X775283Y963000D01*
X776117Y962583D01*
X776492Y962292D01*
X776742Y961875D01*
X776825Y961500D01*
X775075D01*
G01X772933D02*
X772850Y962042D01*
X772725Y962500D01*
X772558Y962917D01*
X772350Y963375D01*
X772017Y964000D01*
X773683D01*
G01X783983Y978000D02*
Y980500D01*
X782942D01*
X782608Y980375D01*
X782400Y980208D01*
X782317Y979875D01*
X782400Y979542D01*
X782650Y979333D01*
X782942Y979208D01*
X783983D01*
G01X782942D02*
X782317Y978000D01*
G01X780842Y979042D02*
X780550Y979333D01*
X780300Y979500D01*
X779967Y979583D01*
X779675Y979500D01*
X779467Y979333D01*
X779300Y979083D01*
X779258Y978792D01*
X779300Y978542D01*
X779467Y978292D01*
X779717Y978083D01*
X780008Y978000D01*
X780342Y978083D01*
X780633Y978333D01*
X780800Y978708D01*
X780842Y979125D01*
X780758Y979667D01*
X780633Y979958D01*
X780425Y980250D01*
X780133Y980458D01*
X779842Y980500D01*
X779550Y980417D01*
X779342Y980208D01*
G01X777742Y980083D02*
X777492Y980333D01*
X777200Y980458D01*
X776867Y980500D01*
X776450Y980417D01*
X776158Y980208D01*
X776075Y979958D01*
X776117Y979708D01*
X776283Y979500D01*
X777117Y979083D01*
X777492Y978792D01*
X777742Y978375D01*
X777825Y978000D01*
X776075D01*
G01X774642Y979042D02*
X774350Y979333D01*
X774100Y979500D01*
X773767Y979583D01*
X773475Y979500D01*
X773267Y979333D01*
X773100Y979083D01*
X773058Y978792D01*
X773100Y978542D01*
X773267Y978292D01*
X773517Y978083D01*
X773808Y978000D01*
X774142Y978083D01*
X774433Y978333D01*
X774600Y978708D01*
X774642Y979125D01*
X774558Y979667D01*
X774433Y979958D01*
X774225Y980250D01*
X773933Y980458D01*
X773642Y980500D01*
X773350Y980417D01*
X773142Y980208D01*
G01X790333Y335375D02*
X790125Y335708D01*
X790000Y336083D01*
Y336417D01*
X790125Y336750D01*
X790333Y337000D01*
X790625Y337125D01*
X790917Y337042D01*
X791167Y336833D01*
X791333Y336458D01*
X791417Y335958D01*
X791583Y335667D01*
X791875Y335542D01*
X792167Y335625D01*
X792375Y335833D01*
X792500Y336125D01*
Y336417D01*
X792417Y336708D01*
X792208Y336958D01*
G01X792292Y340267D02*
X792417Y340017D01*
X792500Y339725D01*
Y339392D01*
X792375Y339017D01*
X792167Y338725D01*
X791917Y338517D01*
X791500Y338350D01*
X791125Y338308D01*
X790750Y338392D01*
X790500Y338517D01*
X790250Y338767D01*
X790083Y339058D01*
X790000Y339350D01*
Y339642D01*
X790083Y339933D01*
X790208Y340183D01*
X790375Y340392D01*
G01X790000Y342450D02*
X792500D01*
X792000Y341950D01*
G01X790000D02*
Y342950D01*
G01Y345550D02*
X792500D01*
X792000Y345050D01*
G01X790000D02*
Y346050D01*
G01X790500Y347733D02*
X790208Y347983D01*
X790042Y348317D01*
X790000Y348692D01*
X790042Y349025D01*
X790250Y349358D01*
X790500Y349567D01*
X790750Y349608D01*
X791042Y349525D01*
X791250Y349233D01*
X791333Y348942D01*
Y348567D01*
G01Y348942D02*
X791458Y349192D01*
X791667Y349400D01*
X791917Y349483D01*
X792167Y349400D01*
X792375Y349192D01*
X792500Y348817D01*
X792458Y348442D01*
X792292Y348067D01*
G01X790500Y350833D02*
X790208Y351083D01*
X790042Y351417D01*
X790000Y351792D01*
X790042Y352125D01*
X790250Y352458D01*
X790500Y352667D01*
X790750Y352708D01*
X791042Y352625D01*
X791250Y352333D01*
X791333Y352042D01*
Y351667D01*
G01Y352042D02*
X791458Y352292D01*
X791667Y352500D01*
X791917Y352583D01*
X792167Y352500D01*
X792375Y352292D01*
X792500Y351917D01*
X792458Y351542D01*
X792292Y351167D01*
G01X786157Y335423D02*
X785949Y335756D01*
X785824Y336131D01*
Y336465D01*
X785949Y336798D01*
X786157Y337048D01*
X786449Y337173D01*
X786741Y337090D01*
X786991Y336881D01*
X787157Y336506D01*
X787241Y336006D01*
X787407Y335715D01*
X787699Y335590D01*
X787991Y335673D01*
X788199Y335881D01*
X788324Y336173D01*
Y336465D01*
X788241Y336756D01*
X788032Y337006D01*
G01X788116Y340315D02*
X788241Y340065D01*
X788324Y339773D01*
Y339440D01*
X788199Y339065D01*
X787991Y338773D01*
X787741Y338565D01*
X787324Y338398D01*
X786949Y338356D01*
X786574Y338440D01*
X786324Y338565D01*
X786074Y338815D01*
X785907Y339106D01*
X785824Y339398D01*
Y339690D01*
X785907Y339981D01*
X786032Y340231D01*
X786199Y340440D01*
G01X785824Y342498D02*
X788324D01*
X787824Y341998D01*
G01X785824D02*
Y342998D01*
G01Y345598D02*
X788324D01*
X787824Y345098D01*
G01X785824D02*
Y346098D01*
G01X786324Y347781D02*
X786032Y348031D01*
X785866Y348365D01*
X785824Y348740D01*
X785866Y349073D01*
X786074Y349406D01*
X786324Y349615D01*
X786574Y349656D01*
X786866Y349573D01*
X787074Y349281D01*
X787157Y348990D01*
Y348615D01*
G01Y348990D02*
X787282Y349240D01*
X787491Y349448D01*
X787741Y349531D01*
X787991Y349448D01*
X788199Y349240D01*
X788324Y348865D01*
X788282Y348490D01*
X788116Y348115D01*
G01X785824Y352298D02*
X788324D01*
X786532Y350756D01*
Y352840D01*
G01X794033Y393500D02*
Y396000D01*
X793033D01*
X792700Y395875D01*
X792450Y395583D01*
X792367Y395250D01*
X792450Y394917D01*
X792658Y394667D01*
X793033Y394542D01*
X794033D01*
G01X789183Y395792D02*
X789433Y395917D01*
X789725Y396000D01*
X790058D01*
X790433Y395875D01*
X790725Y395667D01*
X790933Y395417D01*
X791100Y395000D01*
X791142Y394625D01*
X791058Y394250D01*
X790933Y394000D01*
X790683Y393750D01*
X790392Y393583D01*
X790100Y393500D01*
X789808D01*
X789517Y393583D01*
X789267Y393708D01*
X789058Y393875D01*
G01X787792Y395583D02*
X787542Y395833D01*
X787250Y395958D01*
X786917Y396000D01*
X786500Y395917D01*
X786208Y395708D01*
X786125Y395458D01*
X786167Y395208D01*
X786333Y395000D01*
X787167Y394583D01*
X787542Y394292D01*
X787792Y393875D01*
X787875Y393500D01*
X786125D01*
G01X784817Y394000D02*
X784567Y393708D01*
X784233Y393542D01*
X783858Y393500D01*
X783525Y393542D01*
X783192Y393750D01*
X782983Y394000D01*
X782942Y394250D01*
X783025Y394542D01*
X783317Y394750D01*
X783608Y394833D01*
X783983D01*
G01X783608D02*
X783358Y394958D01*
X783150Y395167D01*
X783067Y395417D01*
X783150Y395667D01*
X783358Y395875D01*
X783733Y396000D01*
X784108Y395958D01*
X784483Y395792D01*
G01X781717Y394000D02*
X781467Y393708D01*
X781133Y393542D01*
X780758Y393500D01*
X780425Y393542D01*
X780092Y393750D01*
X779883Y394000D01*
X779842Y394250D01*
X779925Y394542D01*
X780217Y394750D01*
X780508Y394833D01*
X780883D01*
G01X780508D02*
X780258Y394958D01*
X780050Y395167D01*
X779967Y395417D01*
X780050Y395667D01*
X780258Y395875D01*
X780633Y396000D01*
X781008Y395958D01*
X781383Y395792D01*
G01X785000Y416700D02*
X789000D01*
Y409300D01*
G01X782200Y970500D02*
Y966500D01*
X774800D01*
G01Y971000D02*
Y975000D01*
X782200D01*
G01X791000Y407917D02*
X793500D01*
Y408917D01*
X793375Y409250D01*
X793083Y409500D01*
X792750Y409583D01*
X792417Y409500D01*
X792167Y409292D01*
X792042Y408917D01*
Y407917D01*
G01X791000Y411017D02*
X793500D01*
Y412058D01*
X793375Y412392D01*
X793208Y412600D01*
X792875Y412683D01*
X792542Y412600D01*
X792333Y412350D01*
X792208Y412058D01*
Y411017D01*
G01Y412058D02*
X791000Y412683D01*
G01X791292Y414242D02*
X791083Y414533D01*
X791000Y414867D01*
X791083Y415200D01*
X791333Y415492D01*
X791708Y415700D01*
X792083Y415783D01*
X792542D01*
X792917Y415700D01*
X793250Y415492D01*
X793417Y415242D01*
X793500Y414950D01*
X793417Y414617D01*
X793250Y414367D01*
X793000Y414200D01*
X792667Y414117D01*
X792375Y414200D01*
X792083Y414408D01*
X791917Y414658D01*
X791875Y414950D01*
X791958Y415283D01*
X792167Y415533D01*
X792542Y415783D01*
G01X793500Y418050D02*
X793417Y417717D01*
X793208Y417467D01*
X792958Y417300D01*
X792625Y417175D01*
X792250Y417133D01*
X791875Y417175D01*
X791542Y417300D01*
X791292Y417467D01*
X791083Y417717D01*
X791000Y418050D01*
X791083Y418383D01*
X791292Y418633D01*
X791542Y418800D01*
X791875Y418925D01*
X792250Y418967D01*
X792625Y418925D01*
X792958Y418800D01*
X793208Y418633D01*
X793417Y418383D01*
X793500Y418050D01*
G01X791000Y421150D02*
X793500D01*
X793000Y420650D01*
G01X791000D02*
Y421650D01*
G01Y424250D02*
X791042Y424542D01*
X791167Y424875D01*
X791375Y425083D01*
X791667Y425167D01*
X791958Y425083D01*
X792208Y424833D01*
X792333Y424458D01*
Y424042D01*
X792417Y423792D01*
X792625Y423583D01*
X792917Y423500D01*
X793208Y423625D01*
X793417Y423917D01*
X793500Y424250D01*
X793417Y424583D01*
X793208Y424875D01*
X792917Y425000D01*
X792625Y424917D01*
X792417Y424708D01*
X792333Y424458D01*
Y424042D01*
X792208Y423667D01*
X791958Y423417D01*
X791667Y423333D01*
X791375Y423417D01*
X791167Y423625D01*
X791042Y423958D01*
X791000Y424250D01*
G01X1001567Y58500D02*
Y56708D01*
X1001400Y56333D01*
X1001067Y56083D01*
X1000650Y56000D01*
X1000233Y56083D01*
X999900Y56333D01*
X999733Y56708D01*
Y58500D01*
G01X997550Y56000D02*
Y58500D01*
X998050Y58000D01*
G01Y56000D02*
X997050D01*
G01X995158Y56292D02*
X994867Y56083D01*
X994533Y56000D01*
X994200Y56083D01*
X993908Y56333D01*
X993700Y56708D01*
X993617Y57083D01*
Y57542D01*
X993700Y57917D01*
X993908Y58250D01*
X994158Y58417D01*
X994450Y58500D01*
X994783Y58417D01*
X995033Y58250D01*
X995200Y58000D01*
X995283Y57667D01*
X995200Y57375D01*
X994992Y57083D01*
X994742Y56917D01*
X994450Y56875D01*
X994117Y56958D01*
X993867Y57167D01*
X993617Y57542D01*
G01X990850Y56000D02*
Y58500D01*
X992392Y56708D01*
X990308D01*
G01X1001483Y65500D02*
Y68000D01*
X1000442D01*
X1000108Y67875D01*
X999900Y67708D01*
X999817Y67375D01*
X999900Y67042D01*
X1000150Y66833D01*
X1000442Y66708D01*
X1001483D01*
G01X1000442D02*
X999817Y65500D01*
G01X997050D02*
Y68000D01*
X998592Y66208D01*
X996508D01*
G01X994450Y68000D02*
X994783Y67917D01*
X995033Y67708D01*
X995200Y67458D01*
X995325Y67125D01*
X995367Y66750D01*
X995325Y66375D01*
X995200Y66042D01*
X995033Y65792D01*
X994783Y65583D01*
X994450Y65500D01*
X994117Y65583D01*
X993867Y65792D01*
X993700Y66042D01*
X993575Y66375D01*
X993533Y66750D01*
X993575Y67125D01*
X993700Y67458D01*
X993867Y67708D01*
X994117Y67917D01*
X994450Y68000D01*
G01X991350Y65500D02*
X991058Y65542D01*
X990725Y65667D01*
X990517Y65875D01*
X990433Y66167D01*
X990517Y66458D01*
X990767Y66708D01*
X991142Y66833D01*
X991558D01*
X991808Y66917D01*
X992017Y67125D01*
X992100Y67417D01*
X991975Y67708D01*
X991683Y67917D01*
X991350Y68000D01*
X991017Y67917D01*
X990725Y67708D01*
X990600Y67417D01*
X990683Y67125D01*
X990892Y66917D01*
X991142Y66833D01*
X991558D01*
X991933Y66708D01*
X992183Y66458D01*
X992267Y66167D01*
X992183Y65875D01*
X991975Y65667D01*
X991642Y65542D01*
X991350Y65500D01*
G01X999733Y71792D02*
X999983Y71917D01*
X1000275Y72000D01*
X1000608D01*
X1000983Y71875D01*
X1001275Y71667D01*
X1001483Y71417D01*
X1001650Y71000D01*
X1001692Y70625D01*
X1001608Y70250D01*
X1001483Y70000D01*
X1001233Y69750D01*
X1000942Y69583D01*
X1000650Y69500D01*
X1000358D01*
X1000067Y69583D01*
X999817Y69708D01*
X999608Y69875D01*
G01X998342Y71583D02*
X998092Y71833D01*
X997800Y71958D01*
X997467Y72000D01*
X997050Y71917D01*
X996758Y71708D01*
X996675Y71458D01*
X996717Y71208D01*
X996883Y71000D01*
X997717Y70583D01*
X998092Y70292D01*
X998342Y69875D01*
X998425Y69500D01*
X996675D01*
G01X995367Y70000D02*
X995117Y69708D01*
X994783Y69542D01*
X994408Y69500D01*
X994075Y69542D01*
X993742Y69750D01*
X993533Y70000D01*
X993492Y70250D01*
X993575Y70542D01*
X993867Y70750D01*
X994158Y70833D01*
X994533D01*
G01X994158D02*
X993908Y70958D01*
X993700Y71167D01*
X993617Y71417D01*
X993700Y71667D01*
X993908Y71875D01*
X994283Y72000D01*
X994658Y71958D01*
X995033Y71792D01*
G01X992058Y69792D02*
X991767Y69583D01*
X991433Y69500D01*
X991100Y69583D01*
X990808Y69833D01*
X990600Y70208D01*
X990517Y70583D01*
Y71042D01*
X990600Y71417D01*
X990808Y71750D01*
X991058Y71917D01*
X991350Y72000D01*
X991683Y71917D01*
X991933Y71750D01*
X992100Y71500D01*
X992183Y71167D01*
X992100Y70875D01*
X991892Y70583D01*
X991642Y70417D01*
X991350Y70375D01*
X991017Y70458D01*
X990767Y70667D01*
X990517Y71042D01*
G01X997500Y74017D02*
X1000000D01*
Y75058D01*
X999875Y75392D01*
X999708Y75600D01*
X999375Y75683D01*
X999042Y75600D01*
X998833Y75350D01*
X998708Y75058D01*
Y74017D01*
G01Y75058D02*
X997500Y75683D01*
G01Y78450D02*
X1000000D01*
X998208Y76908D01*
Y78992D01*
G01X1000000Y81050D02*
X999917Y80717D01*
X999708Y80467D01*
X999458Y80300D01*
X999125Y80175D01*
X998750Y80133D01*
X998375Y80175D01*
X998042Y80300D01*
X997792Y80467D01*
X997583Y80717D01*
X997500Y81050D01*
X997583Y81383D01*
X997792Y81633D01*
X998042Y81800D01*
X998375Y81925D01*
X998750Y81967D01*
X999125Y81925D01*
X999458Y81800D01*
X999708Y81633D01*
X999917Y81383D01*
X1000000Y81050D01*
G01X997500Y84067D02*
X998042Y84150D01*
X998500Y84275D01*
X998917Y84442D01*
X999375Y84650D01*
X1000000Y84983D01*
Y83317D01*
G01X995792Y75767D02*
X995917Y75517D01*
X996000Y75225D01*
Y74892D01*
X995875Y74517D01*
X995667Y74225D01*
X995417Y74017D01*
X995000Y73850D01*
X994625Y73808D01*
X994250Y73892D01*
X994000Y74017D01*
X993750Y74267D01*
X993583Y74558D01*
X993500Y74850D01*
Y75142D01*
X993583Y75433D01*
X993708Y75683D01*
X993875Y75892D01*
G01X994000Y77033D02*
X993708Y77283D01*
X993542Y77617D01*
X993500Y77992D01*
X993542Y78325D01*
X993750Y78658D01*
X994000Y78867D01*
X994250Y78908D01*
X994542Y78825D01*
X994750Y78533D01*
X994833Y78242D01*
Y77867D01*
G01Y78242D02*
X994958Y78492D01*
X995167Y78700D01*
X995417Y78783D01*
X995667Y78700D01*
X995875Y78492D01*
X996000Y78117D01*
X995958Y77742D01*
X995792Y77367D01*
G01X994000Y80133D02*
X993708Y80383D01*
X993542Y80717D01*
X993500Y81092D01*
X993542Y81425D01*
X993750Y81758D01*
X994000Y81967D01*
X994250Y82008D01*
X994542Y81925D01*
X994750Y81633D01*
X994833Y81342D01*
Y80967D01*
G01Y81342D02*
X994958Y81592D01*
X995167Y81800D01*
X995417Y81883D01*
X995667Y81800D01*
X995875Y81592D01*
X996000Y81217D01*
X995958Y80842D01*
X995792Y80467D01*
G01X995583Y83358D02*
X995833Y83608D01*
X995958Y83900D01*
X996000Y84233D01*
X995917Y84650D01*
X995708Y84942D01*
X995458Y85025D01*
X995208Y84983D01*
X995000Y84817D01*
X994583Y83983D01*
X994292Y83608D01*
X993875Y83358D01*
X993500Y83275D01*
Y85025D01*
G01X1013000Y46000D02*
X1005000D01*
G01X1019000D02*
X1013000D01*
G01X1019000D02*
X1005000D01*
G01X1019000Y64000D02*
Y46000D01*
G01X1005000D02*
Y64000D01*
G01D02*
X1019000D01*
G01X1008500Y80200D02*
X1012500D01*
Y72800D01*
G01X1012200Y68500D02*
Y64500D01*
X1004800D01*
G01X1032792Y75767D02*
X1032917Y75517D01*
X1033000Y75225D01*
Y74892D01*
X1032875Y74517D01*
X1032667Y74225D01*
X1032417Y74017D01*
X1032000Y73850D01*
X1031625Y73808D01*
X1031250Y73892D01*
X1031000Y74017D01*
X1030750Y74267D01*
X1030583Y74558D01*
X1030500Y74850D01*
Y75142D01*
X1030583Y75433D01*
X1030708Y75683D01*
X1030875Y75892D01*
G01X1031000Y77033D02*
X1030708Y77283D01*
X1030542Y77617D01*
X1030500Y77992D01*
X1030542Y78325D01*
X1030750Y78658D01*
X1031000Y78867D01*
X1031250Y78908D01*
X1031542Y78825D01*
X1031750Y78533D01*
X1031833Y78242D01*
Y77867D01*
G01Y78242D02*
X1031958Y78492D01*
X1032167Y78700D01*
X1032417Y78783D01*
X1032667Y78700D01*
X1032875Y78492D01*
X1033000Y78117D01*
X1032958Y77742D01*
X1032792Y77367D01*
G01X1031000Y80133D02*
X1030708Y80383D01*
X1030542Y80717D01*
X1030500Y81092D01*
X1030542Y81425D01*
X1030750Y81758D01*
X1031000Y81967D01*
X1031250Y82008D01*
X1031542Y81925D01*
X1031750Y81633D01*
X1031833Y81342D01*
Y80967D01*
G01Y81342D02*
X1031958Y81592D01*
X1032167Y81800D01*
X1032417Y81883D01*
X1032667Y81800D01*
X1032875Y81592D01*
X1033000Y81217D01*
X1032958Y80842D01*
X1032792Y80467D01*
G01X1030500Y84650D02*
X1033000D01*
X1031208Y83108D01*
Y85192D01*
G01X1037792Y75767D02*
X1037917Y75517D01*
X1038000Y75225D01*
Y74892D01*
X1037875Y74517D01*
X1037667Y74225D01*
X1037417Y74017D01*
X1037000Y73850D01*
X1036625Y73808D01*
X1036250Y73892D01*
X1036000Y74017D01*
X1035750Y74267D01*
X1035583Y74558D01*
X1035500Y74850D01*
Y75142D01*
X1035583Y75433D01*
X1035708Y75683D01*
X1035875Y75892D01*
G01X1036000Y77033D02*
X1035708Y77283D01*
X1035542Y77617D01*
X1035500Y77992D01*
X1035542Y78325D01*
X1035750Y78658D01*
X1036000Y78867D01*
X1036250Y78908D01*
X1036542Y78825D01*
X1036750Y78533D01*
X1036833Y78242D01*
Y77867D01*
G01Y78242D02*
X1036958Y78492D01*
X1037167Y78700D01*
X1037417Y78783D01*
X1037667Y78700D01*
X1037875Y78492D01*
X1038000Y78117D01*
X1037958Y77742D01*
X1037792Y77367D01*
G01X1036000Y80133D02*
X1035708Y80383D01*
X1035542Y80717D01*
X1035500Y81092D01*
X1035542Y81425D01*
X1035750Y81758D01*
X1036000Y81967D01*
X1036250Y82008D01*
X1036542Y81925D01*
X1036750Y81633D01*
X1036833Y81342D01*
Y80967D01*
G01Y81342D02*
X1036958Y81592D01*
X1037167Y81800D01*
X1037417Y81883D01*
X1037667Y81800D01*
X1037875Y81592D01*
X1038000Y81217D01*
X1037958Y80842D01*
X1037792Y80467D01*
G01X1035875Y83233D02*
X1035667Y83483D01*
X1035542Y83775D01*
X1035500Y84150D01*
X1035583Y84525D01*
X1035750Y84817D01*
X1036042Y85025D01*
X1036375Y85067D01*
X1036708Y84983D01*
X1036917Y84775D01*
X1037083Y84483D01*
X1037125Y84192D01*
X1037083Y83900D01*
X1036917Y83525D01*
X1038000Y83650D01*
Y84775D01*
G01X1042483Y135000D02*
Y137500D01*
X1041483D01*
X1041150Y137375D01*
X1040900Y137083D01*
X1040817Y136750D01*
X1040900Y136417D01*
X1041108Y136167D01*
X1041483Y136042D01*
X1042483D01*
G01X1039383Y135000D02*
Y137500D01*
X1038342D01*
X1038008Y137375D01*
X1037800Y137208D01*
X1037717Y136875D01*
X1037800Y136542D01*
X1038050Y136333D01*
X1038342Y136208D01*
X1039383D01*
G01X1038342D02*
X1037717Y135000D01*
G01X1034950D02*
Y137500D01*
X1036492Y135708D01*
X1034408D01*
G01X1033267Y135375D02*
X1033017Y135167D01*
X1032725Y135042D01*
X1032350Y135000D01*
X1031975Y135083D01*
X1031683Y135250D01*
X1031475Y135542D01*
X1031433Y135875D01*
X1031517Y136208D01*
X1031725Y136417D01*
X1032017Y136583D01*
X1032308Y136625D01*
X1032600Y136583D01*
X1032975Y136417D01*
X1032850Y137500D01*
X1031725D01*
G01X1042483Y130500D02*
Y133000D01*
X1041483D01*
X1041150Y132875D01*
X1040900Y132583D01*
X1040817Y132250D01*
X1040900Y131917D01*
X1041108Y131667D01*
X1041483Y131542D01*
X1042483D01*
G01X1039383Y130500D02*
Y133000D01*
X1038342D01*
X1038008Y132875D01*
X1037800Y132708D01*
X1037717Y132375D01*
X1037800Y132042D01*
X1038050Y131833D01*
X1038342Y131708D01*
X1039383D01*
G01X1038342D02*
X1037717Y130500D01*
G01X1034950D02*
Y133000D01*
X1036492Y131208D01*
X1034408D01*
G01X1032350Y130500D02*
X1032058Y130542D01*
X1031725Y130667D01*
X1031517Y130875D01*
X1031433Y131167D01*
X1031517Y131458D01*
X1031767Y131708D01*
X1032142Y131833D01*
X1032558D01*
X1032808Y131917D01*
X1033017Y132125D01*
X1033100Y132417D01*
X1032975Y132708D01*
X1032683Y132917D01*
X1032350Y133000D01*
X1032017Y132917D01*
X1031725Y132708D01*
X1031600Y132417D01*
X1031683Y132125D01*
X1031892Y131917D01*
X1032142Y131833D01*
X1032558D01*
X1032933Y131708D01*
X1033183Y131458D01*
X1033267Y131167D01*
X1033183Y130875D01*
X1032975Y130667D01*
X1032642Y130542D01*
X1032350Y130500D01*
G01X1041200Y147500D02*
Y143500D01*
X1033800D01*
G01Y139000D02*
Y143000D01*
X1041200D01*
G01X1042792Y75767D02*
X1042917Y75517D01*
X1043000Y75225D01*
Y74892D01*
X1042875Y74517D01*
X1042667Y74225D01*
X1042417Y74017D01*
X1042000Y73850D01*
X1041625Y73808D01*
X1041250Y73892D01*
X1041000Y74017D01*
X1040750Y74267D01*
X1040583Y74558D01*
X1040500Y74850D01*
Y75142D01*
X1040583Y75433D01*
X1040708Y75683D01*
X1040875Y75892D01*
G01X1041000Y77033D02*
X1040708Y77283D01*
X1040542Y77617D01*
X1040500Y77992D01*
X1040542Y78325D01*
X1040750Y78658D01*
X1041000Y78867D01*
X1041250Y78908D01*
X1041542Y78825D01*
X1041750Y78533D01*
X1041833Y78242D01*
Y77867D01*
G01Y78242D02*
X1041958Y78492D01*
X1042167Y78700D01*
X1042417Y78783D01*
X1042667Y78700D01*
X1042875Y78492D01*
X1043000Y78117D01*
X1042958Y77742D01*
X1042792Y77367D01*
G01X1041000Y80133D02*
X1040708Y80383D01*
X1040542Y80717D01*
X1040500Y81092D01*
X1040542Y81425D01*
X1040750Y81758D01*
X1041000Y81967D01*
X1041250Y82008D01*
X1041542Y81925D01*
X1041750Y81633D01*
X1041833Y81342D01*
Y80967D01*
G01Y81342D02*
X1041958Y81592D01*
X1042167Y81800D01*
X1042417Y81883D01*
X1042667Y81800D01*
X1042875Y81592D01*
X1043000Y81217D01*
X1042958Y80842D01*
X1042792Y80467D01*
G01X1041542Y83358D02*
X1041833Y83650D01*
X1042000Y83900D01*
X1042083Y84233D01*
X1042000Y84525D01*
X1041833Y84733D01*
X1041583Y84900D01*
X1041292Y84942D01*
X1041042Y84900D01*
X1040792Y84733D01*
X1040583Y84483D01*
X1040500Y84192D01*
X1040583Y83858D01*
X1040833Y83567D01*
X1041208Y83400D01*
X1041625Y83358D01*
X1042167Y83442D01*
X1042458Y83567D01*
X1042750Y83775D01*
X1042958Y84067D01*
X1043000Y84358D01*
X1042917Y84650D01*
X1042708Y84858D01*
G01X1047792Y75767D02*
X1047917Y75517D01*
X1048000Y75225D01*
Y74892D01*
X1047875Y74517D01*
X1047667Y74225D01*
X1047417Y74017D01*
X1047000Y73850D01*
X1046625Y73808D01*
X1046250Y73892D01*
X1046000Y74017D01*
X1045750Y74267D01*
X1045583Y74558D01*
X1045500Y74850D01*
Y75142D01*
X1045583Y75433D01*
X1045708Y75683D01*
X1045875Y75892D01*
G01X1046000Y77033D02*
X1045708Y77283D01*
X1045542Y77617D01*
X1045500Y77992D01*
X1045542Y78325D01*
X1045750Y78658D01*
X1046000Y78867D01*
X1046250Y78908D01*
X1046542Y78825D01*
X1046750Y78533D01*
X1046833Y78242D01*
Y77867D01*
G01Y78242D02*
X1046958Y78492D01*
X1047167Y78700D01*
X1047417Y78783D01*
X1047667Y78700D01*
X1047875Y78492D01*
X1048000Y78117D01*
X1047958Y77742D01*
X1047792Y77367D01*
G01X1046000Y80133D02*
X1045708Y80383D01*
X1045542Y80717D01*
X1045500Y81092D01*
X1045542Y81425D01*
X1045750Y81758D01*
X1046000Y81967D01*
X1046250Y82008D01*
X1046542Y81925D01*
X1046750Y81633D01*
X1046833Y81342D01*
Y80967D01*
G01Y81342D02*
X1046958Y81592D01*
X1047167Y81800D01*
X1047417Y81883D01*
X1047667Y81800D01*
X1047875Y81592D01*
X1048000Y81217D01*
X1047958Y80842D01*
X1047792Y80467D01*
G01X1045500Y84067D02*
X1046042Y84150D01*
X1046500Y84275D01*
X1046917Y84442D01*
X1047375Y84650D01*
X1048000Y84983D01*
Y83317D01*
G01X1052792Y75767D02*
X1052917Y75517D01*
X1053000Y75225D01*
Y74892D01*
X1052875Y74517D01*
X1052667Y74225D01*
X1052417Y74017D01*
X1052000Y73850D01*
X1051625Y73808D01*
X1051250Y73892D01*
X1051000Y74017D01*
X1050750Y74267D01*
X1050583Y74558D01*
X1050500Y74850D01*
Y75142D01*
X1050583Y75433D01*
X1050708Y75683D01*
X1050875Y75892D01*
G01X1051000Y77033D02*
X1050708Y77283D01*
X1050542Y77617D01*
X1050500Y77992D01*
X1050542Y78325D01*
X1050750Y78658D01*
X1051000Y78867D01*
X1051250Y78908D01*
X1051542Y78825D01*
X1051750Y78533D01*
X1051833Y78242D01*
Y77867D01*
G01Y78242D02*
X1051958Y78492D01*
X1052167Y78700D01*
X1052417Y78783D01*
X1052667Y78700D01*
X1052875Y78492D01*
X1053000Y78117D01*
X1052958Y77742D01*
X1052792Y77367D01*
G01X1051000Y80133D02*
X1050708Y80383D01*
X1050542Y80717D01*
X1050500Y81092D01*
X1050542Y81425D01*
X1050750Y81758D01*
X1051000Y81967D01*
X1051250Y82008D01*
X1051542Y81925D01*
X1051750Y81633D01*
X1051833Y81342D01*
Y80967D01*
G01Y81342D02*
X1051958Y81592D01*
X1052167Y81800D01*
X1052417Y81883D01*
X1052667Y81800D01*
X1052875Y81592D01*
X1053000Y81217D01*
X1052958Y80842D01*
X1052792Y80467D01*
G01X1050500Y84150D02*
X1050542Y84442D01*
X1050667Y84775D01*
X1050875Y84983D01*
X1051167Y85067D01*
X1051458Y84983D01*
X1051708Y84733D01*
X1051833Y84358D01*
Y83942D01*
X1051917Y83692D01*
X1052125Y83483D01*
X1052417Y83400D01*
X1052708Y83525D01*
X1052917Y83817D01*
X1053000Y84150D01*
X1052917Y84483D01*
X1052708Y84775D01*
X1052417Y84900D01*
X1052125Y84817D01*
X1051917Y84608D01*
X1051833Y84358D01*
Y83942D01*
X1051708Y83567D01*
X1051458Y83317D01*
X1051167Y83233D01*
X1050875Y83317D01*
X1050667Y83525D01*
X1050542Y83858D01*
X1050500Y84150D01*
G01X1048500Y123517D02*
X1051000D01*
Y124517D01*
X1050875Y124850D01*
X1050583Y125100D01*
X1050250Y125183D01*
X1049917Y125100D01*
X1049667Y124892D01*
X1049542Y124517D01*
Y123517D01*
G01X1048500Y126617D02*
X1051000D01*
Y127658D01*
X1050875Y127992D01*
X1050708Y128200D01*
X1050375Y128283D01*
X1050042Y128200D01*
X1049833Y127950D01*
X1049708Y127658D01*
Y126617D01*
G01Y127658D02*
X1048500Y128283D01*
G01Y131050D02*
X1051000D01*
X1049208Y129508D01*
Y131592D01*
G01X1048500Y133650D02*
X1051000D01*
X1050500Y133150D01*
G01X1048500D02*
Y134150D01*
G01X1047300Y137000D02*
X1052500D01*
G01X1047300D02*
Y144000D01*
G01X1060700Y137000D02*
X1052000D01*
G01X1047300Y144000D02*
X1055100D01*
G01X1059483Y684000D02*
Y686500D01*
X1058442D01*
X1058108Y686375D01*
X1057900Y686208D01*
X1057817Y685875D01*
X1057900Y685542D01*
X1058150Y685333D01*
X1058442Y685208D01*
X1059483D01*
G01X1058442D02*
X1057817Y684000D01*
G01X1056342Y686083D02*
X1056092Y686333D01*
X1055800Y686458D01*
X1055467Y686500D01*
X1055050Y686417D01*
X1054758Y686208D01*
X1054675Y685958D01*
X1054717Y685708D01*
X1054883Y685500D01*
X1055717Y685083D01*
X1056092Y684792D01*
X1056342Y684375D01*
X1056425Y684000D01*
X1054675D01*
G01X1053367Y684375D02*
X1053117Y684167D01*
X1052825Y684042D01*
X1052450Y684000D01*
X1052075Y684083D01*
X1051783Y684250D01*
X1051575Y684542D01*
X1051533Y684875D01*
X1051617Y685208D01*
X1051825Y685417D01*
X1052117Y685583D01*
X1052408Y685625D01*
X1052700Y685583D01*
X1053075Y685417D01*
X1052950Y686500D01*
X1051825D01*
G01X1049433Y684000D02*
X1049350Y684542D01*
X1049225Y685000D01*
X1049058Y685417D01*
X1048850Y685875D01*
X1048517Y686500D01*
X1050183D01*
G01X1079483Y123000D02*
Y125500D01*
X1078483D01*
X1078150Y125375D01*
X1077900Y125083D01*
X1077817Y124750D01*
X1077900Y124417D01*
X1078108Y124167D01*
X1078483Y124042D01*
X1079483D01*
G01X1076383Y123000D02*
Y125500D01*
X1075342D01*
X1075008Y125375D01*
X1074800Y125208D01*
X1074717Y124875D01*
X1074800Y124542D01*
X1075050Y124333D01*
X1075342Y124208D01*
X1076383D01*
G01X1075342D02*
X1074717Y123000D01*
G01X1071950D02*
Y125500D01*
X1073492Y123708D01*
X1071408D01*
G01X1070142Y124042D02*
X1069850Y124333D01*
X1069600Y124500D01*
X1069267Y124583D01*
X1068975Y124500D01*
X1068767Y124333D01*
X1068600Y124083D01*
X1068558Y123792D01*
X1068600Y123542D01*
X1068767Y123292D01*
X1069017Y123083D01*
X1069308Y123000D01*
X1069642Y123083D01*
X1069933Y123333D01*
X1070100Y123708D01*
X1070142Y124125D01*
X1070058Y124667D01*
X1069933Y124958D01*
X1069725Y125250D01*
X1069433Y125458D01*
X1069142Y125500D01*
X1068850Y125417D01*
X1068642Y125208D01*
G01X1079483Y119000D02*
Y121500D01*
X1078483D01*
X1078150Y121375D01*
X1077900Y121083D01*
X1077817Y120750D01*
X1077900Y120417D01*
X1078108Y120167D01*
X1078483Y120042D01*
X1079483D01*
G01X1074633Y121292D02*
X1074883Y121417D01*
X1075175Y121500D01*
X1075508D01*
X1075883Y121375D01*
X1076175Y121167D01*
X1076383Y120917D01*
X1076550Y120500D01*
X1076592Y120125D01*
X1076508Y119750D01*
X1076383Y119500D01*
X1076133Y119250D01*
X1075842Y119083D01*
X1075550Y119000D01*
X1075258D01*
X1074967Y119083D01*
X1074717Y119208D01*
X1074508Y119375D01*
G01X1073367D02*
X1073117Y119167D01*
X1072825Y119042D01*
X1072450Y119000D01*
X1072075Y119083D01*
X1071783Y119250D01*
X1071575Y119542D01*
X1071533Y119875D01*
X1071617Y120208D01*
X1071825Y120417D01*
X1072117Y120583D01*
X1072408Y120625D01*
X1072700Y120583D01*
X1073075Y120417D01*
X1072950Y121500D01*
X1071825D01*
G01X1069350D02*
X1069683Y121417D01*
X1069933Y121208D01*
X1070100Y120958D01*
X1070225Y120625D01*
X1070267Y120250D01*
X1070225Y119875D01*
X1070100Y119542D01*
X1069933Y119292D01*
X1069683Y119083D01*
X1069350Y119000D01*
X1069017Y119083D01*
X1068767Y119292D01*
X1068600Y119542D01*
X1068475Y119875D01*
X1068433Y120250D01*
X1068475Y120625D01*
X1068600Y120958D01*
X1068767Y121208D01*
X1069017Y121417D01*
X1069350Y121500D01*
G01X1060700Y144000D02*
Y137000D01*
G01X1065700Y126500D02*
Y122500D01*
X1058300D01*
G01X1054300Y144000D02*
X1060700D01*
G01X1073483Y638500D02*
Y641000D01*
X1072442D01*
X1072108Y640875D01*
X1071900Y640708D01*
X1071817Y640375D01*
X1071900Y640042D01*
X1072150Y639833D01*
X1072442Y639708D01*
X1073483D01*
G01X1072442D02*
X1071817Y638500D01*
G01X1070467Y639000D02*
X1070217Y638708D01*
X1069883Y638542D01*
X1069508Y638500D01*
X1069175Y638542D01*
X1068842Y638750D01*
X1068633Y639000D01*
X1068592Y639250D01*
X1068675Y639542D01*
X1068967Y639750D01*
X1069258Y639833D01*
X1069633D01*
G01X1069258D02*
X1069008Y639958D01*
X1068800Y640167D01*
X1068717Y640417D01*
X1068800Y640667D01*
X1069008Y640875D01*
X1069383Y641000D01*
X1069758Y640958D01*
X1070133Y640792D01*
G01X1067242Y640583D02*
X1066992Y640833D01*
X1066700Y640958D01*
X1066367Y641000D01*
X1065950Y640917D01*
X1065658Y640708D01*
X1065575Y640458D01*
X1065617Y640208D01*
X1065783Y640000D01*
X1066617Y639583D01*
X1066992Y639292D01*
X1067242Y638875D01*
X1067325Y638500D01*
X1065575D01*
G01X1063433D02*
X1063350Y639042D01*
X1063225Y639500D01*
X1063058Y639917D01*
X1062850Y640375D01*
X1062517Y641000D01*
X1064183D01*
G01X1073483Y663500D02*
Y666000D01*
X1072442D01*
X1072108Y665875D01*
X1071900Y665708D01*
X1071817Y665375D01*
X1071900Y665042D01*
X1072150Y664833D01*
X1072442Y664708D01*
X1073483D01*
G01X1072442D02*
X1071817Y663500D01*
G01X1070342Y665583D02*
X1070092Y665833D01*
X1069800Y665958D01*
X1069467Y666000D01*
X1069050Y665917D01*
X1068758Y665708D01*
X1068675Y665458D01*
X1068717Y665208D01*
X1068883Y665000D01*
X1069717Y664583D01*
X1070092Y664292D01*
X1070342Y663875D01*
X1070425Y663500D01*
X1068675D01*
G01X1065950D02*
Y666000D01*
X1067492Y664208D01*
X1065408D01*
G01X1063350Y666000D02*
X1063683Y665917D01*
X1063933Y665708D01*
X1064100Y665458D01*
X1064225Y665125D01*
X1064267Y664750D01*
X1064225Y664375D01*
X1064100Y664042D01*
X1063933Y663792D01*
X1063683Y663583D01*
X1063350Y663500D01*
X1063017Y663583D01*
X1062767Y663792D01*
X1062600Y664042D01*
X1062475Y664375D01*
X1062433Y664750D01*
X1062475Y665125D01*
X1062600Y665458D01*
X1062767Y665708D01*
X1063017Y665917D01*
X1063350Y666000D01*
G01X1064168Y679554D02*
Y683554D01*
X1071568D01*
G01X1073483Y671500D02*
Y674000D01*
X1072442D01*
X1072108Y673875D01*
X1071900Y673708D01*
X1071817Y673375D01*
X1071900Y673042D01*
X1072150Y672833D01*
X1072442Y672708D01*
X1073483D01*
G01X1072442D02*
X1071817Y671500D01*
G01X1070467Y672000D02*
X1070217Y671708D01*
X1069883Y671542D01*
X1069508Y671500D01*
X1069175Y671542D01*
X1068842Y671750D01*
X1068633Y672000D01*
X1068592Y672250D01*
X1068675Y672542D01*
X1068967Y672750D01*
X1069258Y672833D01*
X1069633D01*
G01X1069258D02*
X1069008Y672958D01*
X1068800Y673167D01*
X1068717Y673417D01*
X1068800Y673667D01*
X1069008Y673875D01*
X1069383Y674000D01*
X1069758Y673958D01*
X1070133Y673792D01*
G01X1066450Y674000D02*
X1066783Y673917D01*
X1067033Y673708D01*
X1067200Y673458D01*
X1067325Y673125D01*
X1067367Y672750D01*
X1067325Y672375D01*
X1067200Y672042D01*
X1067033Y671792D01*
X1066783Y671583D01*
X1066450Y671500D01*
X1066117Y671583D01*
X1065867Y671792D01*
X1065700Y672042D01*
X1065575Y672375D01*
X1065533Y672750D01*
X1065575Y673125D01*
X1065700Y673458D01*
X1065867Y673708D01*
X1066117Y673917D01*
X1066450Y674000D01*
G01X1064142Y672542D02*
X1063850Y672833D01*
X1063600Y673000D01*
X1063267Y673083D01*
X1062975Y673000D01*
X1062767Y672833D01*
X1062600Y672583D01*
X1062558Y672292D01*
X1062600Y672042D01*
X1062767Y671792D01*
X1063017Y671583D01*
X1063308Y671500D01*
X1063642Y671583D01*
X1063933Y671833D01*
X1064100Y672208D01*
X1064142Y672625D01*
X1064058Y673167D01*
X1063933Y673458D01*
X1063725Y673750D01*
X1063433Y673958D01*
X1063142Y674000D01*
X1062850Y673917D01*
X1062642Y673708D01*
G01X1073483Y667500D02*
Y670000D01*
X1072442D01*
X1072108Y669875D01*
X1071900Y669708D01*
X1071817Y669375D01*
X1071900Y669042D01*
X1072150Y668833D01*
X1072442Y668708D01*
X1073483D01*
G01X1072442D02*
X1071817Y667500D01*
G01X1070467Y668000D02*
X1070217Y667708D01*
X1069883Y667542D01*
X1069508Y667500D01*
X1069175Y667542D01*
X1068842Y667750D01*
X1068633Y668000D01*
X1068592Y668250D01*
X1068675Y668542D01*
X1068967Y668750D01*
X1069258Y668833D01*
X1069633D01*
G01X1069258D02*
X1069008Y668958D01*
X1068800Y669167D01*
X1068717Y669417D01*
X1068800Y669667D01*
X1069008Y669875D01*
X1069383Y670000D01*
X1069758Y669958D01*
X1070133Y669792D01*
G01X1066450Y670000D02*
X1066783Y669917D01*
X1067033Y669708D01*
X1067200Y669458D01*
X1067325Y669125D01*
X1067367Y668750D01*
X1067325Y668375D01*
X1067200Y668042D01*
X1067033Y667792D01*
X1066783Y667583D01*
X1066450Y667500D01*
X1066117Y667583D01*
X1065867Y667792D01*
X1065700Y668042D01*
X1065575Y668375D01*
X1065533Y668750D01*
X1065575Y669125D01*
X1065700Y669458D01*
X1065867Y669708D01*
X1066117Y669917D01*
X1066450Y670000D01*
G01X1064058Y667792D02*
X1063767Y667583D01*
X1063433Y667500D01*
X1063100Y667583D01*
X1062808Y667833D01*
X1062600Y668208D01*
X1062517Y668583D01*
Y669042D01*
X1062600Y669417D01*
X1062808Y669750D01*
X1063058Y669917D01*
X1063350Y670000D01*
X1063683Y669917D01*
X1063933Y669750D01*
X1064100Y669500D01*
X1064183Y669167D01*
X1064100Y668875D01*
X1063892Y668583D01*
X1063642Y668417D01*
X1063350Y668375D01*
X1063017Y668458D01*
X1062767Y668667D01*
X1062517Y669042D01*
G01X1072983Y686000D02*
Y688500D01*
X1071942D01*
X1071608Y688375D01*
X1071400Y688208D01*
X1071317Y687875D01*
X1071400Y687542D01*
X1071650Y687333D01*
X1071942Y687208D01*
X1072983D01*
G01X1071942D02*
X1071317Y686000D01*
G01X1069842Y688083D02*
X1069592Y688333D01*
X1069300Y688458D01*
X1068967Y688500D01*
X1068550Y688417D01*
X1068258Y688208D01*
X1068175Y687958D01*
X1068217Y687708D01*
X1068383Y687500D01*
X1069217Y687083D01*
X1069592Y686792D01*
X1069842Y686375D01*
X1069925Y686000D01*
X1068175D01*
G01X1065450D02*
Y688500D01*
X1066992Y686708D01*
X1064908D01*
G01X1062850Y686000D02*
Y688500D01*
X1063350Y688000D01*
G01Y686000D02*
X1062350D01*
G01X1072983Y690500D02*
Y693000D01*
X1071942D01*
X1071608Y692875D01*
X1071400Y692708D01*
X1071317Y692375D01*
X1071400Y692042D01*
X1071650Y691833D01*
X1071942Y691708D01*
X1072983D01*
G01X1071942D02*
X1071317Y690500D01*
G01X1069967Y691000D02*
X1069717Y690708D01*
X1069383Y690542D01*
X1069008Y690500D01*
X1068675Y690542D01*
X1068342Y690750D01*
X1068133Y691000D01*
X1068092Y691250D01*
X1068175Y691542D01*
X1068467Y691750D01*
X1068758Y691833D01*
X1069133D01*
G01X1068758D02*
X1068508Y691958D01*
X1068300Y692167D01*
X1068217Y692417D01*
X1068300Y692667D01*
X1068508Y692875D01*
X1068883Y693000D01*
X1069258Y692958D01*
X1069633Y692792D01*
G01X1066867Y691000D02*
X1066617Y690708D01*
X1066283Y690542D01*
X1065908Y690500D01*
X1065575Y690542D01*
X1065242Y690750D01*
X1065033Y691000D01*
X1064992Y691250D01*
X1065075Y691542D01*
X1065367Y691750D01*
X1065658Y691833D01*
X1066033D01*
G01X1065658D02*
X1065408Y691958D01*
X1065200Y692167D01*
X1065117Y692417D01*
X1065200Y692667D01*
X1065408Y692875D01*
X1065783Y693000D01*
X1066158Y692958D01*
X1066533Y692792D01*
G01X1063642Y692583D02*
X1063392Y692833D01*
X1063100Y692958D01*
X1062767Y693000D01*
X1062350Y692917D01*
X1062058Y692708D01*
X1061975Y692458D01*
X1062017Y692208D01*
X1062183Y692000D01*
X1063017Y691583D01*
X1063392Y691292D01*
X1063642Y690875D01*
X1063725Y690500D01*
X1061975D01*
G01X1072983Y694500D02*
Y697000D01*
X1071942D01*
X1071608Y696875D01*
X1071400Y696708D01*
X1071317Y696375D01*
X1071400Y696042D01*
X1071650Y695833D01*
X1071942Y695708D01*
X1072983D01*
G01X1071942D02*
X1071317Y694500D01*
G01X1069967Y695000D02*
X1069717Y694708D01*
X1069383Y694542D01*
X1069008Y694500D01*
X1068675Y694542D01*
X1068342Y694750D01*
X1068133Y695000D01*
X1068092Y695250D01*
X1068175Y695542D01*
X1068467Y695750D01*
X1068758Y695833D01*
X1069133D01*
G01X1068758D02*
X1068508Y695958D01*
X1068300Y696167D01*
X1068217Y696417D01*
X1068300Y696667D01*
X1068508Y696875D01*
X1068883Y697000D01*
X1069258Y696958D01*
X1069633Y696792D01*
G01X1066742Y695542D02*
X1066450Y695833D01*
X1066200Y696000D01*
X1065867Y696083D01*
X1065575Y696000D01*
X1065367Y695833D01*
X1065200Y695583D01*
X1065158Y695292D01*
X1065200Y695042D01*
X1065367Y694792D01*
X1065617Y694583D01*
X1065908Y694500D01*
X1066242Y694583D01*
X1066533Y694833D01*
X1066700Y695208D01*
X1066742Y695625D01*
X1066658Y696167D01*
X1066533Y696458D01*
X1066325Y696750D01*
X1066033Y696958D01*
X1065742Y697000D01*
X1065450Y696917D01*
X1065242Y696708D01*
G01X1062850Y697000D02*
X1063183Y696917D01*
X1063433Y696708D01*
X1063600Y696458D01*
X1063725Y696125D01*
X1063767Y695750D01*
X1063725Y695375D01*
X1063600Y695042D01*
X1063433Y694792D01*
X1063183Y694583D01*
X1062850Y694500D01*
X1062517Y694583D01*
X1062267Y694792D01*
X1062100Y695042D01*
X1061975Y695375D01*
X1061933Y695750D01*
X1061975Y696125D01*
X1062100Y696458D01*
X1062267Y696708D01*
X1062517Y696917D01*
X1062850Y697000D01*
G01X1072983Y706500D02*
Y709000D01*
X1071942D01*
X1071608Y708875D01*
X1071400Y708708D01*
X1071317Y708375D01*
X1071400Y708042D01*
X1071650Y707833D01*
X1071942Y707708D01*
X1072983D01*
G01X1071942D02*
X1071317Y706500D01*
G01X1069967Y707000D02*
X1069717Y706708D01*
X1069383Y706542D01*
X1069008Y706500D01*
X1068675Y706542D01*
X1068342Y706750D01*
X1068133Y707000D01*
X1068092Y707250D01*
X1068175Y707542D01*
X1068467Y707750D01*
X1068758Y707833D01*
X1069133D01*
G01X1068758D02*
X1068508Y707958D01*
X1068300Y708167D01*
X1068217Y708417D01*
X1068300Y708667D01*
X1068508Y708875D01*
X1068883Y709000D01*
X1069258Y708958D01*
X1069633Y708792D01*
G01X1065450Y706500D02*
Y709000D01*
X1066992Y707208D01*
X1064908D01*
G01X1062850Y709000D02*
X1063183Y708917D01*
X1063433Y708708D01*
X1063600Y708458D01*
X1063725Y708125D01*
X1063767Y707750D01*
X1063725Y707375D01*
X1063600Y707042D01*
X1063433Y706792D01*
X1063183Y706583D01*
X1062850Y706500D01*
X1062517Y706583D01*
X1062267Y706792D01*
X1062100Y707042D01*
X1061975Y707375D01*
X1061933Y707750D01*
X1061975Y708125D01*
X1062100Y708458D01*
X1062267Y708708D01*
X1062517Y708917D01*
X1062850Y709000D01*
G01X1072983Y702500D02*
Y705000D01*
X1071942D01*
X1071608Y704875D01*
X1071400Y704708D01*
X1071317Y704375D01*
X1071400Y704042D01*
X1071650Y703833D01*
X1071942Y703708D01*
X1072983D01*
G01X1071942D02*
X1071317Y702500D01*
G01X1069967Y703000D02*
X1069717Y702708D01*
X1069383Y702542D01*
X1069008Y702500D01*
X1068675Y702542D01*
X1068342Y702750D01*
X1068133Y703000D01*
X1068092Y703250D01*
X1068175Y703542D01*
X1068467Y703750D01*
X1068758Y703833D01*
X1069133D01*
G01X1068758D02*
X1068508Y703958D01*
X1068300Y704167D01*
X1068217Y704417D01*
X1068300Y704667D01*
X1068508Y704875D01*
X1068883Y705000D01*
X1069258Y704958D01*
X1069633Y704792D01*
G01X1065450Y702500D02*
Y705000D01*
X1066992Y703208D01*
X1064908D01*
G01X1062350Y702500D02*
Y705000D01*
X1063892Y703208D01*
X1061808D01*
G01X1072983Y710500D02*
Y713000D01*
X1071942D01*
X1071608Y712875D01*
X1071400Y712708D01*
X1071317Y712375D01*
X1071400Y712042D01*
X1071650Y711833D01*
X1071942Y711708D01*
X1072983D01*
G01X1071942D02*
X1071317Y710500D01*
G01X1069967Y711000D02*
X1069717Y710708D01*
X1069383Y710542D01*
X1069008Y710500D01*
X1068675Y710542D01*
X1068342Y710750D01*
X1068133Y711000D01*
X1068092Y711250D01*
X1068175Y711542D01*
X1068467Y711750D01*
X1068758Y711833D01*
X1069133D01*
G01X1068758D02*
X1068508Y711958D01*
X1068300Y712167D01*
X1068217Y712417D01*
X1068300Y712667D01*
X1068508Y712875D01*
X1068883Y713000D01*
X1069258Y712958D01*
X1069633Y712792D01*
G01X1066867Y710875D02*
X1066617Y710667D01*
X1066325Y710542D01*
X1065950Y710500D01*
X1065575Y710583D01*
X1065283Y710750D01*
X1065075Y711042D01*
X1065033Y711375D01*
X1065117Y711708D01*
X1065325Y711917D01*
X1065617Y712083D01*
X1065908Y712125D01*
X1066200Y712083D01*
X1066575Y711917D01*
X1066450Y713000D01*
X1065325D01*
G01X1063642Y711542D02*
X1063350Y711833D01*
X1063100Y712000D01*
X1062767Y712083D01*
X1062475Y712000D01*
X1062267Y711833D01*
X1062100Y711583D01*
X1062058Y711292D01*
X1062100Y711042D01*
X1062267Y710792D01*
X1062517Y710583D01*
X1062808Y710500D01*
X1063142Y710583D01*
X1063433Y710833D01*
X1063600Y711208D01*
X1063642Y711625D01*
X1063558Y712167D01*
X1063433Y712458D01*
X1063225Y712750D01*
X1062933Y712958D01*
X1062642Y713000D01*
X1062350Y712917D01*
X1062142Y712708D01*
G01X1072983Y698500D02*
Y701000D01*
X1071942D01*
X1071608Y700875D01*
X1071400Y700708D01*
X1071317Y700375D01*
X1071400Y700042D01*
X1071650Y699833D01*
X1071942Y699708D01*
X1072983D01*
G01X1071942D02*
X1071317Y698500D01*
G01X1069967Y699000D02*
X1069717Y698708D01*
X1069383Y698542D01*
X1069008Y698500D01*
X1068675Y698542D01*
X1068342Y698750D01*
X1068133Y699000D01*
X1068092Y699250D01*
X1068175Y699542D01*
X1068467Y699750D01*
X1068758Y699833D01*
X1069133D01*
G01X1068758D02*
X1068508Y699958D01*
X1068300Y700167D01*
X1068217Y700417D01*
X1068300Y700667D01*
X1068508Y700875D01*
X1068883Y701000D01*
X1069258Y700958D01*
X1069633Y700792D01*
G01X1066742Y699542D02*
X1066450Y699833D01*
X1066200Y700000D01*
X1065867Y700083D01*
X1065575Y700000D01*
X1065367Y699833D01*
X1065200Y699583D01*
X1065158Y699292D01*
X1065200Y699042D01*
X1065367Y698792D01*
X1065617Y698583D01*
X1065908Y698500D01*
X1066242Y698583D01*
X1066533Y698833D01*
X1066700Y699208D01*
X1066742Y699625D01*
X1066658Y700167D01*
X1066533Y700458D01*
X1066325Y700750D01*
X1066033Y700958D01*
X1065742Y701000D01*
X1065450Y700917D01*
X1065242Y700708D01*
G01X1062350Y698500D02*
Y701000D01*
X1063892Y699208D01*
X1061808D01*
G01X1072983Y718500D02*
Y721000D01*
X1071942D01*
X1071608Y720875D01*
X1071400Y720708D01*
X1071317Y720375D01*
X1071400Y720042D01*
X1071650Y719833D01*
X1071942Y719708D01*
X1072983D01*
G01X1071942D02*
X1071317Y718500D01*
G01X1069967Y719000D02*
X1069717Y718708D01*
X1069383Y718542D01*
X1069008Y718500D01*
X1068675Y718542D01*
X1068342Y718750D01*
X1068133Y719000D01*
X1068092Y719250D01*
X1068175Y719542D01*
X1068467Y719750D01*
X1068758Y719833D01*
X1069133D01*
G01X1068758D02*
X1068508Y719958D01*
X1068300Y720167D01*
X1068217Y720417D01*
X1068300Y720667D01*
X1068508Y720875D01*
X1068883Y721000D01*
X1069258Y720958D01*
X1069633Y720792D01*
G01X1065450Y718500D02*
Y721000D01*
X1066992Y719208D01*
X1064908D01*
G01X1063558Y718792D02*
X1063267Y718583D01*
X1062933Y718500D01*
X1062600Y718583D01*
X1062308Y718833D01*
X1062100Y719208D01*
X1062017Y719583D01*
Y720042D01*
X1062100Y720417D01*
X1062308Y720750D01*
X1062558Y720917D01*
X1062850Y721000D01*
X1063183Y720917D01*
X1063433Y720750D01*
X1063600Y720500D01*
X1063683Y720167D01*
X1063600Y719875D01*
X1063392Y719583D01*
X1063142Y719417D01*
X1062850Y719375D01*
X1062517Y719458D01*
X1062267Y719667D01*
X1062017Y720042D01*
G01X1072983Y730500D02*
Y733000D01*
X1071942D01*
X1071608Y732875D01*
X1071400Y732708D01*
X1071317Y732375D01*
X1071400Y732042D01*
X1071650Y731833D01*
X1071942Y731708D01*
X1072983D01*
G01X1071942D02*
X1071317Y730500D01*
G01X1069967Y731000D02*
X1069717Y730708D01*
X1069383Y730542D01*
X1069008Y730500D01*
X1068675Y730542D01*
X1068342Y730750D01*
X1068133Y731000D01*
X1068092Y731250D01*
X1068175Y731542D01*
X1068467Y731750D01*
X1068758Y731833D01*
X1069133D01*
G01X1068758D02*
X1068508Y731958D01*
X1068300Y732167D01*
X1068217Y732417D01*
X1068300Y732667D01*
X1068508Y732875D01*
X1068883Y733000D01*
X1069258Y732958D01*
X1069633Y732792D01*
G01X1066867Y730875D02*
X1066617Y730667D01*
X1066325Y730542D01*
X1065950Y730500D01*
X1065575Y730583D01*
X1065283Y730750D01*
X1065075Y731042D01*
X1065033Y731375D01*
X1065117Y731708D01*
X1065325Y731917D01*
X1065617Y732083D01*
X1065908Y732125D01*
X1066200Y732083D01*
X1066575Y731917D01*
X1066450Y733000D01*
X1065325D01*
G01X1062850D02*
X1063183Y732917D01*
X1063433Y732708D01*
X1063600Y732458D01*
X1063725Y732125D01*
X1063767Y731750D01*
X1063725Y731375D01*
X1063600Y731042D01*
X1063433Y730792D01*
X1063183Y730583D01*
X1062850Y730500D01*
X1062517Y730583D01*
X1062267Y730792D01*
X1062100Y731042D01*
X1061975Y731375D01*
X1061933Y731750D01*
X1061975Y732125D01*
X1062100Y732458D01*
X1062267Y732708D01*
X1062517Y732917D01*
X1062850Y733000D01*
G01X1072983Y714500D02*
Y717000D01*
X1071942D01*
X1071608Y716875D01*
X1071400Y716708D01*
X1071317Y716375D01*
X1071400Y716042D01*
X1071650Y715833D01*
X1071942Y715708D01*
X1072983D01*
G01X1071942D02*
X1071317Y714500D01*
G01X1069967Y715000D02*
X1069717Y714708D01*
X1069383Y714542D01*
X1069008Y714500D01*
X1068675Y714542D01*
X1068342Y714750D01*
X1068133Y715000D01*
X1068092Y715250D01*
X1068175Y715542D01*
X1068467Y715750D01*
X1068758Y715833D01*
X1069133D01*
G01X1068758D02*
X1068508Y715958D01*
X1068300Y716167D01*
X1068217Y716417D01*
X1068300Y716667D01*
X1068508Y716875D01*
X1068883Y717000D01*
X1069258Y716958D01*
X1069633Y716792D01*
G01X1066867Y714875D02*
X1066617Y714667D01*
X1066325Y714542D01*
X1065950Y714500D01*
X1065575Y714583D01*
X1065283Y714750D01*
X1065075Y715042D01*
X1065033Y715375D01*
X1065117Y715708D01*
X1065325Y715917D01*
X1065617Y716083D01*
X1065908Y716125D01*
X1066200Y716083D01*
X1066575Y715917D01*
X1066450Y717000D01*
X1065325D01*
G01X1063767Y715000D02*
X1063517Y714708D01*
X1063183Y714542D01*
X1062808Y714500D01*
X1062475Y714542D01*
X1062142Y714750D01*
X1061933Y715000D01*
X1061892Y715250D01*
X1061975Y715542D01*
X1062267Y715750D01*
X1062558Y715833D01*
X1062933D01*
G01X1062558D02*
X1062308Y715958D01*
X1062100Y716167D01*
X1062017Y716417D01*
X1062100Y716667D01*
X1062308Y716875D01*
X1062683Y717000D01*
X1063058Y716958D01*
X1063433Y716792D01*
G01X1072983Y726500D02*
Y729000D01*
X1071942D01*
X1071608Y728875D01*
X1071400Y728708D01*
X1071317Y728375D01*
X1071400Y728042D01*
X1071650Y727833D01*
X1071942Y727708D01*
X1072983D01*
G01X1071942D02*
X1071317Y726500D01*
G01X1069967Y727000D02*
X1069717Y726708D01*
X1069383Y726542D01*
X1069008Y726500D01*
X1068675Y726542D01*
X1068342Y726750D01*
X1068133Y727000D01*
X1068092Y727250D01*
X1068175Y727542D01*
X1068467Y727750D01*
X1068758Y727833D01*
X1069133D01*
G01X1068758D02*
X1068508Y727958D01*
X1068300Y728167D01*
X1068217Y728417D01*
X1068300Y728667D01*
X1068508Y728875D01*
X1068883Y729000D01*
X1069258Y728958D01*
X1069633Y728792D01*
G01X1066867Y726875D02*
X1066617Y726667D01*
X1066325Y726542D01*
X1065950Y726500D01*
X1065575Y726583D01*
X1065283Y726750D01*
X1065075Y727042D01*
X1065033Y727375D01*
X1065117Y727708D01*
X1065325Y727917D01*
X1065617Y728083D01*
X1065908Y728125D01*
X1066200Y728083D01*
X1066575Y727917D01*
X1066450Y729000D01*
X1065325D01*
G01X1063767Y726875D02*
X1063517Y726667D01*
X1063225Y726542D01*
X1062850Y726500D01*
X1062475Y726583D01*
X1062183Y726750D01*
X1061975Y727042D01*
X1061933Y727375D01*
X1062017Y727708D01*
X1062225Y727917D01*
X1062517Y728083D01*
X1062808Y728125D01*
X1063100Y728083D01*
X1063475Y727917D01*
X1063350Y729000D01*
X1062225D01*
G01X1072983Y722500D02*
Y725000D01*
X1071942D01*
X1071608Y724875D01*
X1071400Y724708D01*
X1071317Y724375D01*
X1071400Y724042D01*
X1071650Y723833D01*
X1071942Y723708D01*
X1072983D01*
G01X1071942D02*
X1071317Y722500D01*
G01X1069967Y723000D02*
X1069717Y722708D01*
X1069383Y722542D01*
X1069008Y722500D01*
X1068675Y722542D01*
X1068342Y722750D01*
X1068133Y723000D01*
X1068092Y723250D01*
X1068175Y723542D01*
X1068467Y723750D01*
X1068758Y723833D01*
X1069133D01*
G01X1068758D02*
X1068508Y723958D01*
X1068300Y724167D01*
X1068217Y724417D01*
X1068300Y724667D01*
X1068508Y724875D01*
X1068883Y725000D01*
X1069258Y724958D01*
X1069633Y724792D01*
G01X1066867Y722875D02*
X1066617Y722667D01*
X1066325Y722542D01*
X1065950Y722500D01*
X1065575Y722583D01*
X1065283Y722750D01*
X1065075Y723042D01*
X1065033Y723375D01*
X1065117Y723708D01*
X1065325Y723917D01*
X1065617Y724083D01*
X1065908Y724125D01*
X1066200Y724083D01*
X1066575Y723917D01*
X1066450Y725000D01*
X1065325D01*
G01X1063558Y722792D02*
X1063267Y722583D01*
X1062933Y722500D01*
X1062600Y722583D01*
X1062308Y722833D01*
X1062100Y723208D01*
X1062017Y723583D01*
Y724042D01*
X1062100Y724417D01*
X1062308Y724750D01*
X1062558Y724917D01*
X1062850Y725000D01*
X1063183Y724917D01*
X1063433Y724750D01*
X1063600Y724500D01*
X1063683Y724167D01*
X1063600Y723875D01*
X1063392Y723583D01*
X1063142Y723417D01*
X1062850Y723375D01*
X1062517Y723458D01*
X1062267Y723667D01*
X1062017Y724042D01*
G01X1072983Y734500D02*
Y737000D01*
X1071942D01*
X1071608Y736875D01*
X1071400Y736708D01*
X1071317Y736375D01*
X1071400Y736042D01*
X1071650Y735833D01*
X1071942Y735708D01*
X1072983D01*
G01X1071942D02*
X1071317Y734500D01*
G01X1069967Y735000D02*
X1069717Y734708D01*
X1069383Y734542D01*
X1069008Y734500D01*
X1068675Y734542D01*
X1068342Y734750D01*
X1068133Y735000D01*
X1068092Y735250D01*
X1068175Y735542D01*
X1068467Y735750D01*
X1068758Y735833D01*
X1069133D01*
G01X1068758D02*
X1068508Y735958D01*
X1068300Y736167D01*
X1068217Y736417D01*
X1068300Y736667D01*
X1068508Y736875D01*
X1068883Y737000D01*
X1069258Y736958D01*
X1069633Y736792D01*
G01X1066742Y735542D02*
X1066450Y735833D01*
X1066200Y736000D01*
X1065867Y736083D01*
X1065575Y736000D01*
X1065367Y735833D01*
X1065200Y735583D01*
X1065158Y735292D01*
X1065200Y735042D01*
X1065367Y734792D01*
X1065617Y734583D01*
X1065908Y734500D01*
X1066242Y734583D01*
X1066533Y734833D01*
X1066700Y735208D01*
X1066742Y735625D01*
X1066658Y736167D01*
X1066533Y736458D01*
X1066325Y736750D01*
X1066033Y736958D01*
X1065742Y737000D01*
X1065450Y736917D01*
X1065242Y736708D01*
G01X1063642Y736583D02*
X1063392Y736833D01*
X1063100Y736958D01*
X1062767Y737000D01*
X1062350Y736917D01*
X1062058Y736708D01*
X1061975Y736458D01*
X1062017Y736208D01*
X1062183Y736000D01*
X1063017Y735583D01*
X1063392Y735292D01*
X1063642Y734875D01*
X1063725Y734500D01*
X1061975D01*
G01X1072983Y740500D02*
Y743000D01*
X1071942D01*
X1071608Y742875D01*
X1071400Y742708D01*
X1071317Y742375D01*
X1071400Y742042D01*
X1071650Y741833D01*
X1071942Y741708D01*
X1072983D01*
G01X1071942D02*
X1071317Y740500D01*
G01X1069967Y741000D02*
X1069717Y740708D01*
X1069383Y740542D01*
X1069008Y740500D01*
X1068675Y740542D01*
X1068342Y740750D01*
X1068133Y741000D01*
X1068092Y741250D01*
X1068175Y741542D01*
X1068467Y741750D01*
X1068758Y741833D01*
X1069133D01*
G01X1068758D02*
X1068508Y741958D01*
X1068300Y742167D01*
X1068217Y742417D01*
X1068300Y742667D01*
X1068508Y742875D01*
X1068883Y743000D01*
X1069258Y742958D01*
X1069633Y742792D01*
G01X1066033Y740500D02*
X1065950Y741042D01*
X1065825Y741500D01*
X1065658Y741917D01*
X1065450Y742375D01*
X1065117Y743000D01*
X1066783D01*
G01X1062850D02*
X1063183Y742917D01*
X1063433Y742708D01*
X1063600Y742458D01*
X1063725Y742125D01*
X1063767Y741750D01*
X1063725Y741375D01*
X1063600Y741042D01*
X1063433Y740792D01*
X1063183Y740583D01*
X1062850Y740500D01*
X1062517Y740583D01*
X1062267Y740792D01*
X1062100Y741042D01*
X1061975Y741375D01*
X1061933Y741750D01*
X1061975Y742125D01*
X1062100Y742458D01*
X1062267Y742708D01*
X1062517Y742917D01*
X1062850Y743000D01*
G01X1076000Y145017D02*
X1078500D01*
Y146017D01*
X1078375Y146350D01*
X1078083Y146600D01*
X1077750Y146683D01*
X1077417Y146600D01*
X1077167Y146392D01*
X1077042Y146017D01*
Y145017D01*
G01X1078292Y149867D02*
X1078417Y149617D01*
X1078500Y149325D01*
Y148992D01*
X1078375Y148617D01*
X1078167Y148325D01*
X1077917Y148117D01*
X1077500Y147950D01*
X1077125Y147908D01*
X1076750Y147992D01*
X1076500Y148117D01*
X1076250Y148367D01*
X1076083Y148658D01*
X1076000Y148950D01*
Y149242D01*
X1076083Y149533D01*
X1076208Y149783D01*
X1076375Y149992D01*
G01X1076000Y152550D02*
X1078500D01*
X1076708Y151008D01*
Y153092D01*
G01X1076000Y155067D02*
X1076542Y155150D01*
X1077000Y155275D01*
X1077417Y155442D01*
X1077875Y155650D01*
X1078500Y155983D01*
Y154317D01*
G01X1084300Y628000D02*
Y632000D01*
X1091700D01*
G01X1090700Y642000D02*
Y638000D01*
X1083300D01*
G01X1083200Y642000D02*
Y638000D01*
X1075800D01*
G01X1082483Y654000D02*
Y656500D01*
X1081442D01*
X1081108Y656375D01*
X1080900Y656208D01*
X1080817Y655875D01*
X1080900Y655542D01*
X1081150Y655333D01*
X1081442Y655208D01*
X1082483D01*
G01X1081442D02*
X1080817Y654000D01*
G01X1079467Y654375D02*
X1079217Y654167D01*
X1078925Y654042D01*
X1078550Y654000D01*
X1078175Y654083D01*
X1077883Y654250D01*
X1077675Y654542D01*
X1077633Y654875D01*
X1077717Y655208D01*
X1077925Y655417D01*
X1078217Y655583D01*
X1078508Y655625D01*
X1078800Y655583D01*
X1079175Y655417D01*
X1079050Y656500D01*
X1077925D01*
G01X1074950Y654000D02*
Y656500D01*
X1076492Y654708D01*
X1074408D01*
G01X1072350Y656500D02*
X1072683Y656417D01*
X1072933Y656208D01*
X1073100Y655958D01*
X1073225Y655625D01*
X1073267Y655250D01*
X1073225Y654875D01*
X1073100Y654542D01*
X1072933Y654292D01*
X1072683Y654083D01*
X1072350Y654000D01*
X1072017Y654083D01*
X1071767Y654292D01*
X1071600Y654542D01*
X1071475Y654875D01*
X1071433Y655250D01*
X1071475Y655625D01*
X1071600Y655958D01*
X1071767Y656208D01*
X1072017Y656417D01*
X1072350Y656500D01*
G01X1082471Y649584D02*
Y652084D01*
X1081430D01*
X1081096Y651959D01*
X1080888Y651792D01*
X1080805Y651459D01*
X1080888Y651126D01*
X1081138Y650917D01*
X1081430Y650792D01*
X1082471D01*
G01X1081430D02*
X1080805Y649584D01*
G01X1079330Y651667D02*
X1079080Y651917D01*
X1078788Y652042D01*
X1078455Y652084D01*
X1078038Y652001D01*
X1077746Y651792D01*
X1077663Y651542D01*
X1077705Y651292D01*
X1077871Y651084D01*
X1078705Y650667D01*
X1079080Y650376D01*
X1079330Y649959D01*
X1079413Y649584D01*
X1077663D01*
G01X1076355Y650084D02*
X1076105Y649792D01*
X1075771Y649626D01*
X1075396Y649584D01*
X1075063Y649626D01*
X1074730Y649834D01*
X1074521Y650084D01*
X1074480Y650334D01*
X1074563Y650626D01*
X1074855Y650834D01*
X1075146Y650917D01*
X1075521D01*
G01X1075146D02*
X1074896Y651042D01*
X1074688Y651251D01*
X1074605Y651501D01*
X1074688Y651751D01*
X1074896Y651959D01*
X1075271Y652084D01*
X1075646Y652042D01*
X1076021Y651876D01*
G01X1073130Y650626D02*
X1072838Y650917D01*
X1072588Y651084D01*
X1072255Y651167D01*
X1071963Y651084D01*
X1071755Y650917D01*
X1071588Y650667D01*
X1071546Y650376D01*
X1071588Y650126D01*
X1071755Y649876D01*
X1072005Y649667D01*
X1072296Y649584D01*
X1072630Y649667D01*
X1072921Y649917D01*
X1073088Y650292D01*
X1073130Y650709D01*
X1073046Y651251D01*
X1072921Y651542D01*
X1072713Y651834D01*
X1072421Y652042D01*
X1072130Y652084D01*
X1071838Y652001D01*
X1071630Y651792D01*
G01X1075800Y665500D02*
Y669500D01*
X1083200D01*
G01X1075800Y677500D02*
Y681500D01*
X1083200D01*
G01X1075800Y673500D02*
Y677500D01*
X1083200D01*
G01X1075800Y669500D02*
Y673500D01*
X1083200D01*
G01X1075800Y681500D02*
Y685500D01*
X1083200D01*
G01X1075800Y693500D02*
Y697500D01*
X1083200D01*
G01X1075800Y685500D02*
Y689500D01*
X1083200D01*
G01X1075800D02*
Y693500D01*
X1083200D01*
G01X1075800Y697500D02*
Y701500D01*
X1083200D01*
G01X1075800Y709500D02*
Y713500D01*
X1083200D01*
G01X1075800Y705500D02*
Y709500D01*
X1083200D01*
G01X1075800Y701500D02*
Y705500D01*
X1083200D01*
G01X1075800Y721500D02*
Y725500D01*
X1083200D01*
G01X1075800Y717500D02*
Y721500D01*
X1083200D01*
G01X1075800Y713500D02*
Y717500D01*
X1083200D01*
G01X1075800Y725500D02*
Y729500D01*
X1083200D01*
G01X1076800Y734500D02*
Y738500D01*
X1084200D01*
G01X1104983Y629000D02*
Y631500D01*
X1103942D01*
X1103608Y631375D01*
X1103400Y631208D01*
X1103317Y630875D01*
X1103400Y630542D01*
X1103650Y630333D01*
X1103942Y630208D01*
X1104983D01*
G01X1103942D02*
X1103317Y629000D01*
G01X1101967Y629500D02*
X1101717Y629208D01*
X1101383Y629042D01*
X1101008Y629000D01*
X1100675Y629042D01*
X1100342Y629250D01*
X1100133Y629500D01*
X1100092Y629750D01*
X1100175Y630042D01*
X1100467Y630250D01*
X1100758Y630333D01*
X1101133D01*
G01X1100758D02*
X1100508Y630458D01*
X1100300Y630667D01*
X1100217Y630917D01*
X1100300Y631167D01*
X1100508Y631375D01*
X1100883Y631500D01*
X1101258Y631458D01*
X1101633Y631292D01*
G01X1098867Y629500D02*
X1098617Y629208D01*
X1098283Y629042D01*
X1097908Y629000D01*
X1097575Y629042D01*
X1097242Y629250D01*
X1097033Y629500D01*
X1096992Y629750D01*
X1097075Y630042D01*
X1097367Y630250D01*
X1097658Y630333D01*
X1098033D01*
G01X1097658D02*
X1097408Y630458D01*
X1097200Y630667D01*
X1097117Y630917D01*
X1097200Y631167D01*
X1097408Y631375D01*
X1097783Y631500D01*
X1098158Y631458D01*
X1098533Y631292D01*
G01X1094850Y629000D02*
Y631500D01*
X1095350Y631000D01*
G01Y629000D02*
X1094350D01*
G01X1103983Y638500D02*
Y641000D01*
X1102942D01*
X1102608Y640875D01*
X1102400Y640708D01*
X1102317Y640375D01*
X1102400Y640042D01*
X1102650Y639833D01*
X1102942Y639708D01*
X1103983D01*
G01X1102942D02*
X1102317Y638500D01*
G01X1100967Y639000D02*
X1100717Y638708D01*
X1100383Y638542D01*
X1100008Y638500D01*
X1099675Y638542D01*
X1099342Y638750D01*
X1099133Y639000D01*
X1099092Y639250D01*
X1099175Y639542D01*
X1099467Y639750D01*
X1099758Y639833D01*
X1100133D01*
G01X1099758D02*
X1099508Y639958D01*
X1099300Y640167D01*
X1099217Y640417D01*
X1099300Y640667D01*
X1099508Y640875D01*
X1099883Y641000D01*
X1100258Y640958D01*
X1100633Y640792D01*
G01X1097742Y640583D02*
X1097492Y640833D01*
X1097200Y640958D01*
X1096867Y641000D01*
X1096450Y640917D01*
X1096158Y640708D01*
X1096075Y640458D01*
X1096117Y640208D01*
X1096283Y640000D01*
X1097117Y639583D01*
X1097492Y639292D01*
X1097742Y638875D01*
X1097825Y638500D01*
X1096075D01*
G01X1094558Y638792D02*
X1094267Y638583D01*
X1093933Y638500D01*
X1093600Y638583D01*
X1093308Y638833D01*
X1093100Y639208D01*
X1093017Y639583D01*
Y640042D01*
X1093100Y640417D01*
X1093308Y640750D01*
X1093558Y640917D01*
X1093850Y641000D01*
X1094183Y640917D01*
X1094433Y640750D01*
X1094600Y640500D01*
X1094683Y640167D01*
X1094600Y639875D01*
X1094392Y639583D01*
X1094142Y639417D01*
X1093850Y639375D01*
X1093517Y639458D01*
X1093267Y639667D01*
X1093017Y640042D01*
G01X1085800Y653000D02*
Y657000D01*
X1093200D01*
G01X1085788Y648584D02*
Y652584D01*
X1093188D01*
G01X1112483Y688000D02*
Y690500D01*
X1111442D01*
X1111108Y690375D01*
X1110900Y690208D01*
X1110817Y689875D01*
X1110900Y689542D01*
X1111150Y689333D01*
X1111442Y689208D01*
X1112483D01*
G01X1111442D02*
X1110817Y688000D01*
G01X1109342Y690083D02*
X1109092Y690333D01*
X1108800Y690458D01*
X1108467Y690500D01*
X1108050Y690417D01*
X1107758Y690208D01*
X1107675Y689958D01*
X1107717Y689708D01*
X1107883Y689500D01*
X1108717Y689083D01*
X1109092Y688792D01*
X1109342Y688375D01*
X1109425Y688000D01*
X1107675D01*
G01X1106367Y688500D02*
X1106117Y688208D01*
X1105783Y688042D01*
X1105408Y688000D01*
X1105075Y688042D01*
X1104742Y688250D01*
X1104533Y688500D01*
X1104492Y688750D01*
X1104575Y689042D01*
X1104867Y689250D01*
X1105158Y689333D01*
X1105533D01*
G01X1105158D02*
X1104908Y689458D01*
X1104700Y689667D01*
X1104617Y689917D01*
X1104700Y690167D01*
X1104908Y690375D01*
X1105283Y690500D01*
X1105658Y690458D01*
X1106033Y690292D01*
G01X1102350Y690500D02*
X1102683Y690417D01*
X1102933Y690208D01*
X1103100Y689958D01*
X1103225Y689625D01*
X1103267Y689250D01*
X1103225Y688875D01*
X1103100Y688542D01*
X1102933Y688292D01*
X1102683Y688083D01*
X1102350Y688000D01*
X1102017Y688083D01*
X1101767Y688292D01*
X1101600Y688542D01*
X1101475Y688875D01*
X1101433Y689250D01*
X1101475Y689625D01*
X1101600Y689958D01*
X1101767Y690208D01*
X1102017Y690417D01*
X1102350Y690500D01*
G01X1118200Y665500D02*
Y663000D01*
G01X1119158Y665500D02*
X1117242D01*
G01X1115933Y663000D02*
Y665500D01*
X1114933D01*
X1114600Y665375D01*
X1114350Y665083D01*
X1114267Y664750D01*
X1114350Y664417D01*
X1114558Y664167D01*
X1114933Y664042D01*
X1115933D01*
G01X1112000Y663000D02*
Y665500D01*
X1112500Y665000D01*
G01Y663000D02*
X1111500D01*
G01X1109692Y664042D02*
X1109400Y664333D01*
X1109150Y664500D01*
X1108817Y664583D01*
X1108525Y664500D01*
X1108317Y664333D01*
X1108150Y664083D01*
X1108108Y663792D01*
X1108150Y663542D01*
X1108317Y663292D01*
X1108567Y663083D01*
X1108858Y663000D01*
X1109192Y663083D01*
X1109483Y663333D01*
X1109650Y663708D01*
X1109692Y664125D01*
X1109608Y664667D01*
X1109483Y664958D01*
X1109275Y665250D01*
X1108983Y665458D01*
X1108692Y665500D01*
X1108400Y665417D01*
X1108192Y665208D01*
G01X1106717Y663500D02*
X1106467Y663208D01*
X1106133Y663042D01*
X1105758Y663000D01*
X1105425Y663042D01*
X1105092Y663250D01*
X1104883Y663500D01*
X1104842Y663750D01*
X1104925Y664042D01*
X1105217Y664250D01*
X1105508Y664333D01*
X1105883D01*
G01X1105508D02*
X1105258Y664458D01*
X1105050Y664667D01*
X1104967Y664917D01*
X1105050Y665167D01*
X1105258Y665375D01*
X1105633Y665500D01*
X1106008Y665458D01*
X1106383Y665292D01*
G01X1131200Y672500D02*
Y670000D01*
G01X1132158Y672500D02*
X1130242D01*
G01X1128933Y670000D02*
Y672500D01*
X1127933D01*
X1127600Y672375D01*
X1127350Y672083D01*
X1127267Y671750D01*
X1127350Y671417D01*
X1127558Y671167D01*
X1127933Y671042D01*
X1128933D01*
G01X1125000Y670000D02*
Y672500D01*
X1125500Y672000D01*
G01Y670000D02*
X1124500D01*
G01X1122817Y670500D02*
X1122567Y670208D01*
X1122233Y670042D01*
X1121858Y670000D01*
X1121525Y670042D01*
X1121192Y670250D01*
X1120983Y670500D01*
X1120942Y670750D01*
X1121025Y671042D01*
X1121317Y671250D01*
X1121608Y671333D01*
X1121983D01*
G01X1121608D02*
X1121358Y671458D01*
X1121150Y671667D01*
X1121067Y671917D01*
X1121150Y672167D01*
X1121358Y672375D01*
X1121733Y672500D01*
X1122108Y672458D01*
X1122483Y672292D01*
G01X1118883Y670000D02*
X1118800Y670542D01*
X1118675Y671000D01*
X1118508Y671417D01*
X1118300Y671875D01*
X1117967Y672500D01*
X1119633D01*
G01X1124201Y690076D02*
X1124451Y690201D01*
X1124743Y690284D01*
X1125076D01*
X1125451Y690159D01*
X1125743Y689951D01*
X1125951Y689701D01*
X1126118Y689284D01*
X1126160Y688909D01*
X1126076Y688534D01*
X1125951Y688284D01*
X1125701Y688034D01*
X1125410Y687867D01*
X1125118Y687784D01*
X1124826D01*
X1124535Y687867D01*
X1124285Y687992D01*
X1124076Y688159D01*
G01X1122810Y689867D02*
X1122560Y690117D01*
X1122268Y690242D01*
X1121935Y690284D01*
X1121518Y690201D01*
X1121226Y689992D01*
X1121143Y689742D01*
X1121185Y689492D01*
X1121351Y689284D01*
X1122185Y688867D01*
X1122560Y688576D01*
X1122810Y688159D01*
X1122893Y687784D01*
X1121143D01*
G01X1118918D02*
Y690284D01*
X1119418Y689784D01*
G01Y687784D02*
X1118418D01*
G01X1116610Y689867D02*
X1116360Y690117D01*
X1116068Y690242D01*
X1115735Y690284D01*
X1115318Y690201D01*
X1115026Y689992D01*
X1114943Y689742D01*
X1114985Y689492D01*
X1115151Y689284D01*
X1115985Y688867D01*
X1116360Y688576D01*
X1116610Y688159D01*
X1116693Y687784D01*
X1114943D01*
G01X1124233Y685792D02*
X1124483Y685917D01*
X1124775Y686000D01*
X1125108D01*
X1125483Y685875D01*
X1125775Y685667D01*
X1125983Y685417D01*
X1126150Y685000D01*
X1126192Y684625D01*
X1126108Y684250D01*
X1125983Y684000D01*
X1125733Y683750D01*
X1125442Y683583D01*
X1125150Y683500D01*
X1124858D01*
X1124567Y683583D01*
X1124317Y683708D01*
X1124108Y683875D01*
G01X1122842Y685583D02*
X1122592Y685833D01*
X1122300Y685958D01*
X1121967Y686000D01*
X1121550Y685917D01*
X1121258Y685708D01*
X1121175Y685458D01*
X1121217Y685208D01*
X1121383Y685000D01*
X1122217Y684583D01*
X1122592Y684292D01*
X1122842Y683875D01*
X1122925Y683500D01*
X1121175D01*
G01X1118950Y686000D02*
X1119283Y685917D01*
X1119533Y685708D01*
X1119700Y685458D01*
X1119825Y685125D01*
X1119867Y684750D01*
X1119825Y684375D01*
X1119700Y684042D01*
X1119533Y683792D01*
X1119283Y683583D01*
X1118950Y683500D01*
X1118617Y683583D01*
X1118367Y683792D01*
X1118200Y684042D01*
X1118075Y684375D01*
X1118033Y684750D01*
X1118075Y685125D01*
X1118200Y685458D01*
X1118367Y685708D01*
X1118617Y685917D01*
X1118950Y686000D01*
G01X1116558Y683792D02*
X1116267Y683583D01*
X1115933Y683500D01*
X1115600Y683583D01*
X1115308Y683833D01*
X1115100Y684208D01*
X1115017Y684583D01*
Y685042D01*
X1115100Y685417D01*
X1115308Y685750D01*
X1115558Y685917D01*
X1115850Y686000D01*
X1116183Y685917D01*
X1116433Y685750D01*
X1116600Y685500D01*
X1116683Y685167D01*
X1116600Y684875D01*
X1116392Y684583D01*
X1116142Y684417D01*
X1115850Y684375D01*
X1115517Y684458D01*
X1115267Y684667D01*
X1115017Y685042D01*
G01X1131500Y638300D02*
X1129000D01*
G01X1131500Y637342D02*
Y639258D01*
G01X1129000Y640567D02*
X1131500D01*
Y641567D01*
X1131375Y641900D01*
X1131083Y642150D01*
X1130750Y642233D01*
X1130417Y642150D01*
X1130167Y641942D01*
X1130042Y641567D01*
Y640567D01*
G01X1129000Y644500D02*
X1131500D01*
X1131000Y644000D01*
G01X1129000D02*
Y645000D01*
G01X1129500Y646683D02*
X1129208Y646933D01*
X1129042Y647267D01*
X1129000Y647642D01*
X1129042Y647975D01*
X1129250Y648308D01*
X1129500Y648517D01*
X1129750Y648558D01*
X1130042Y648475D01*
X1130250Y648183D01*
X1130333Y647892D01*
Y647517D01*
G01Y647892D02*
X1130458Y648142D01*
X1130667Y648350D01*
X1130917Y648433D01*
X1131167Y648350D01*
X1131375Y648142D01*
X1131500Y647767D01*
X1131458Y647392D01*
X1131292Y647017D01*
G01X1129000Y651200D02*
X1131500D01*
X1129708Y649658D01*
Y651742D01*
G01X1147700Y644500D02*
Y642000D01*
G01X1148658Y644500D02*
X1146742D01*
G01X1145433Y642000D02*
Y644500D01*
X1144433D01*
X1144100Y644375D01*
X1143850Y644083D01*
X1143767Y643750D01*
X1143850Y643417D01*
X1144058Y643167D01*
X1144433Y643042D01*
X1145433D01*
G01X1141500Y642000D02*
Y644500D01*
X1142000Y644000D01*
G01Y642000D02*
X1141000D01*
G01X1139317Y642500D02*
X1139067Y642208D01*
X1138733Y642042D01*
X1138358Y642000D01*
X1138025Y642042D01*
X1137692Y642250D01*
X1137483Y642500D01*
X1137442Y642750D01*
X1137525Y643042D01*
X1137817Y643250D01*
X1138108Y643333D01*
X1138483D01*
G01X1138108D02*
X1137858Y643458D01*
X1137650Y643667D01*
X1137567Y643917D01*
X1137650Y644167D01*
X1137858Y644375D01*
X1138233Y644500D01*
X1138608Y644458D01*
X1138983Y644292D01*
G01X1135300Y642000D02*
X1135008Y642042D01*
X1134675Y642167D01*
X1134467Y642375D01*
X1134383Y642667D01*
X1134467Y642958D01*
X1134717Y643208D01*
X1135092Y643333D01*
X1135508D01*
X1135758Y643417D01*
X1135967Y643625D01*
X1136050Y643917D01*
X1135925Y644208D01*
X1135633Y644417D01*
X1135300Y644500D01*
X1134967Y644417D01*
X1134675Y644208D01*
X1134550Y643917D01*
X1134633Y643625D01*
X1134842Y643417D01*
X1135092Y643333D01*
X1135508D01*
X1135883Y643208D01*
X1136133Y642958D01*
X1136217Y642667D01*
X1136133Y642375D01*
X1135925Y642167D01*
X1135592Y642042D01*
X1135300Y642000D01*
G01X1147700Y648500D02*
Y646000D01*
G01X1148658Y648500D02*
X1146742D01*
G01X1145433Y646000D02*
Y648500D01*
X1144433D01*
X1144100Y648375D01*
X1143850Y648083D01*
X1143767Y647750D01*
X1143850Y647417D01*
X1144058Y647167D01*
X1144433Y647042D01*
X1145433D01*
G01X1141500Y646000D02*
Y648500D01*
X1142000Y648000D01*
G01Y646000D02*
X1141000D01*
G01X1137900D02*
Y648500D01*
X1139442Y646708D01*
X1137358D01*
G01X1136092Y648083D02*
X1135842Y648333D01*
X1135550Y648458D01*
X1135217Y648500D01*
X1134800Y648417D01*
X1134508Y648208D01*
X1134425Y647958D01*
X1134467Y647708D01*
X1134633Y647500D01*
X1135467Y647083D01*
X1135842Y646792D01*
X1136092Y646375D01*
X1136175Y646000D01*
X1134425D01*
G01X1127000Y638300D02*
X1124500D01*
G01X1127000Y637342D02*
Y639258D01*
G01X1124500Y640567D02*
X1127000D01*
Y641567D01*
X1126875Y641900D01*
X1126583Y642150D01*
X1126250Y642233D01*
X1125917Y642150D01*
X1125667Y641942D01*
X1125542Y641567D01*
Y640567D01*
G01X1124500Y644500D02*
X1127000D01*
X1126500Y644000D01*
G01X1124500D02*
Y645000D01*
G01Y647600D02*
X1124542Y647892D01*
X1124667Y648225D01*
X1124875Y648433D01*
X1125167Y648517D01*
X1125458Y648433D01*
X1125708Y648183D01*
X1125833Y647808D01*
Y647392D01*
X1125917Y647142D01*
X1126125Y646933D01*
X1126417Y646850D01*
X1126708Y646975D01*
X1126917Y647267D01*
X1127000Y647600D01*
X1126917Y647933D01*
X1126708Y648225D01*
X1126417Y648350D01*
X1126125Y648267D01*
X1125917Y648058D01*
X1125833Y647808D01*
Y647392D01*
X1125708Y647017D01*
X1125458Y646767D01*
X1125167Y646683D01*
X1124875Y646767D01*
X1124667Y646975D01*
X1124542Y647308D01*
X1124500Y647600D01*
G01X1125000Y649783D02*
X1124708Y650033D01*
X1124542Y650367D01*
X1124500Y650742D01*
X1124542Y651075D01*
X1124750Y651408D01*
X1125000Y651617D01*
X1125250Y651658D01*
X1125542Y651575D01*
X1125750Y651283D01*
X1125833Y650992D01*
Y650617D01*
G01Y650992D02*
X1125958Y651242D01*
X1126167Y651450D01*
X1126417Y651533D01*
X1126667Y651450D01*
X1126875Y651242D01*
X1127000Y650867D01*
X1126958Y650492D01*
X1126792Y650117D01*
G01X1138200Y669000D02*
Y666500D01*
G01X1139158Y669000D02*
X1137242D01*
G01X1135933Y666500D02*
Y669000D01*
X1134933D01*
X1134600Y668875D01*
X1134350Y668583D01*
X1134267Y668250D01*
X1134350Y667917D01*
X1134558Y667667D01*
X1134933Y667542D01*
X1135933D01*
G01X1132000Y666500D02*
Y669000D01*
X1132500Y668500D01*
G01Y666500D02*
X1131500D01*
G01X1128900D02*
Y669000D01*
X1129400Y668500D01*
G01Y666500D02*
X1128400D01*
G01X1125800D02*
X1125508Y666542D01*
X1125175Y666667D01*
X1124967Y666875D01*
X1124883Y667167D01*
X1124967Y667458D01*
X1125217Y667708D01*
X1125592Y667833D01*
X1126008D01*
X1126258Y667917D01*
X1126467Y668125D01*
X1126550Y668417D01*
X1126425Y668708D01*
X1126133Y668917D01*
X1125800Y669000D01*
X1125467Y668917D01*
X1125175Y668708D01*
X1125050Y668417D01*
X1125133Y668125D01*
X1125342Y667917D01*
X1125592Y667833D01*
X1126008D01*
X1126383Y667708D01*
X1126633Y667458D01*
X1126717Y667167D01*
X1126633Y666875D01*
X1126425Y666667D01*
X1126092Y666542D01*
X1125800Y666500D01*
G01X1135200Y680500D02*
Y678000D01*
G01X1136158Y680500D02*
X1134242D01*
G01X1132933Y678000D02*
Y680500D01*
X1131933D01*
X1131600Y680375D01*
X1131350Y680083D01*
X1131267Y679750D01*
X1131350Y679417D01*
X1131558Y679167D01*
X1131933Y679042D01*
X1132933D01*
G01X1129000Y678000D02*
Y680500D01*
X1129500Y680000D01*
G01Y678000D02*
X1128500D01*
G01X1125900D02*
X1125608Y678042D01*
X1125275Y678167D01*
X1125067Y678375D01*
X1124983Y678667D01*
X1125067Y678958D01*
X1125317Y679208D01*
X1125692Y679333D01*
X1126108D01*
X1126358Y679417D01*
X1126567Y679625D01*
X1126650Y679917D01*
X1126525Y680208D01*
X1126233Y680417D01*
X1125900Y680500D01*
X1125567Y680417D01*
X1125275Y680208D01*
X1125150Y679917D01*
X1125233Y679625D01*
X1125442Y679417D01*
X1125692Y679333D01*
X1126108D01*
X1126483Y679208D01*
X1126733Y678958D01*
X1126817Y678667D01*
X1126733Y678375D01*
X1126525Y678167D01*
X1126192Y678042D01*
X1125900Y678000D01*
G01X1123592Y680083D02*
X1123342Y680333D01*
X1123050Y680458D01*
X1122717Y680500D01*
X1122300Y680417D01*
X1122008Y680208D01*
X1121925Y679958D01*
X1121967Y679708D01*
X1122133Y679500D01*
X1122967Y679083D01*
X1123342Y678792D01*
X1123592Y678375D01*
X1123675Y678000D01*
X1121925D01*
G01X1137538Y690864D02*
Y686864D01*
X1130138D01*
G01X1132701Y698076D02*
X1132951Y698201D01*
X1133243Y698284D01*
X1133576D01*
X1133951Y698159D01*
X1134243Y697951D01*
X1134451Y697701D01*
X1134618Y697284D01*
X1134660Y696909D01*
X1134576Y696534D01*
X1134451Y696284D01*
X1134201Y696034D01*
X1133910Y695867D01*
X1133618Y695784D01*
X1133326D01*
X1133035Y695867D01*
X1132785Y695992D01*
X1132576Y696159D01*
G01X1131310Y697867D02*
X1131060Y698117D01*
X1130768Y698242D01*
X1130435Y698284D01*
X1130018Y698201D01*
X1129726Y697992D01*
X1129643Y697742D01*
X1129685Y697492D01*
X1129851Y697284D01*
X1130685Y696867D01*
X1131060Y696576D01*
X1131310Y696159D01*
X1131393Y695784D01*
X1129643D01*
G01X1127418D02*
Y698284D01*
X1127918Y697784D01*
G01Y695784D02*
X1126918D01*
G01X1124318Y698284D02*
X1124651Y698201D01*
X1124901Y697992D01*
X1125068Y697742D01*
X1125193Y697409D01*
X1125235Y697034D01*
X1125193Y696659D01*
X1125068Y696326D01*
X1124901Y696076D01*
X1124651Y695867D01*
X1124318Y695784D01*
X1123985Y695867D01*
X1123735Y696076D01*
X1123568Y696326D01*
X1123443Y696659D01*
X1123401Y697034D01*
X1123443Y697409D01*
X1123568Y697742D01*
X1123735Y697992D01*
X1123985Y698201D01*
X1124318Y698284D01*
G01X1142200Y712000D02*
Y709500D01*
G01X1143158Y712000D02*
X1141242D01*
G01X1139933Y709500D02*
Y712000D01*
X1138933D01*
X1138600Y711875D01*
X1138350Y711583D01*
X1138267Y711250D01*
X1138350Y710917D01*
X1138558Y710667D01*
X1138933Y710542D01*
X1139933D01*
G01X1136000Y709500D02*
Y712000D01*
X1136500Y711500D01*
G01Y709500D02*
X1135500D01*
G01X1133817Y709875D02*
X1133567Y709667D01*
X1133275Y709542D01*
X1132900Y709500D01*
X1132525Y709583D01*
X1132233Y709750D01*
X1132025Y710042D01*
X1131983Y710375D01*
X1132067Y710708D01*
X1132275Y710917D01*
X1132567Y711083D01*
X1132858Y711125D01*
X1133150Y711083D01*
X1133525Y710917D01*
X1133400Y712000D01*
X1132275D01*
G01X1129800Y709500D02*
Y712000D01*
X1130300Y711500D01*
G01Y709500D02*
X1129300D01*
G01X1132733Y702792D02*
X1132983Y702917D01*
X1133275Y703000D01*
X1133608D01*
X1133983Y702875D01*
X1134275Y702667D01*
X1134483Y702417D01*
X1134650Y702000D01*
X1134692Y701625D01*
X1134608Y701250D01*
X1134483Y701000D01*
X1134233Y700750D01*
X1133942Y700583D01*
X1133650Y700500D01*
X1133358D01*
X1133067Y700583D01*
X1132817Y700708D01*
X1132608Y700875D01*
G01X1131342Y702583D02*
X1131092Y702833D01*
X1130800Y702958D01*
X1130467Y703000D01*
X1130050Y702917D01*
X1129758Y702708D01*
X1129675Y702458D01*
X1129717Y702208D01*
X1129883Y702000D01*
X1130717Y701583D01*
X1131092Y701292D01*
X1131342Y700875D01*
X1131425Y700500D01*
X1129675D01*
G01X1127450Y703000D02*
X1127783Y702917D01*
X1128033Y702708D01*
X1128200Y702458D01*
X1128325Y702125D01*
X1128367Y701750D01*
X1128325Y701375D01*
X1128200Y701042D01*
X1128033Y700792D01*
X1127783Y700583D01*
X1127450Y700500D01*
X1127117Y700583D01*
X1126867Y700792D01*
X1126700Y701042D01*
X1126575Y701375D01*
X1126533Y701750D01*
X1126575Y702125D01*
X1126700Y702458D01*
X1126867Y702708D01*
X1127117Y702917D01*
X1127450Y703000D01*
G01X1124433Y700500D02*
X1124350Y701042D01*
X1124225Y701500D01*
X1124058Y701917D01*
X1123850Y702375D01*
X1123517Y703000D01*
X1125183D01*
G01X1126092Y815767D02*
X1126217Y815517D01*
X1126300Y815225D01*
Y814892D01*
X1126175Y814517D01*
X1125967Y814225D01*
X1125717Y814017D01*
X1125300Y813850D01*
X1124925Y813808D01*
X1124550Y813892D01*
X1124300Y814017D01*
X1124050Y814267D01*
X1123883Y814558D01*
X1123800Y814850D01*
Y815142D01*
X1123883Y815433D01*
X1124008Y815683D01*
X1124175Y815892D01*
G01X1123800Y817950D02*
X1126300D01*
X1125800Y817450D01*
G01X1123800D02*
Y818450D01*
G01X1124092Y820342D02*
X1123883Y820633D01*
X1123800Y820967D01*
X1123883Y821300D01*
X1124133Y821592D01*
X1124508Y821800D01*
X1124883Y821883D01*
X1125342D01*
X1125717Y821800D01*
X1126050Y821592D01*
X1126217Y821342D01*
X1126300Y821050D01*
X1126217Y820717D01*
X1126050Y820467D01*
X1125800Y820300D01*
X1125467Y820217D01*
X1125175Y820300D01*
X1124883Y820508D01*
X1124717Y820758D01*
X1124675Y821050D01*
X1124758Y821383D01*
X1124967Y821633D01*
X1125342Y821883D01*
G01X1124092Y823442D02*
X1123883Y823733D01*
X1123800Y824067D01*
X1123883Y824400D01*
X1124133Y824692D01*
X1124508Y824900D01*
X1124883Y824983D01*
X1125342D01*
X1125717Y824900D01*
X1126050Y824692D01*
X1126217Y824442D01*
X1126300Y824150D01*
X1126217Y823817D01*
X1126050Y823567D01*
X1125800Y823400D01*
X1125467Y823317D01*
X1125175Y823400D01*
X1124883Y823608D01*
X1124717Y823858D01*
X1124675Y824150D01*
X1124758Y824483D01*
X1124967Y824733D01*
X1125342Y824983D01*
G01X1132592Y815767D02*
X1132717Y815517D01*
X1132800Y815225D01*
Y814892D01*
X1132675Y814517D01*
X1132467Y814225D01*
X1132217Y814017D01*
X1131800Y813850D01*
X1131425Y813808D01*
X1131050Y813892D01*
X1130800Y814017D01*
X1130550Y814267D01*
X1130383Y814558D01*
X1130300Y814850D01*
Y815142D01*
X1130383Y815433D01*
X1130508Y815683D01*
X1130675Y815892D01*
G01X1130300Y817950D02*
X1132800D01*
X1132300Y817450D01*
G01X1130300D02*
Y818450D01*
G01X1130592Y820342D02*
X1130383Y820633D01*
X1130300Y820967D01*
X1130383Y821300D01*
X1130633Y821592D01*
X1131008Y821800D01*
X1131383Y821883D01*
X1131842D01*
X1132217Y821800D01*
X1132550Y821592D01*
X1132717Y821342D01*
X1132800Y821050D01*
X1132717Y820717D01*
X1132550Y820467D01*
X1132300Y820300D01*
X1131967Y820217D01*
X1131675Y820300D01*
X1131383Y820508D01*
X1131217Y820758D01*
X1131175Y821050D01*
X1131258Y821383D01*
X1131467Y821633D01*
X1131842Y821883D01*
G01X1130300Y824150D02*
X1130342Y824442D01*
X1130467Y824775D01*
X1130675Y824983D01*
X1130967Y825067D01*
X1131258Y824983D01*
X1131508Y824733D01*
X1131633Y824358D01*
Y823942D01*
X1131717Y823692D01*
X1131925Y823483D01*
X1132217Y823400D01*
X1132508Y823525D01*
X1132717Y823817D01*
X1132800Y824150D01*
X1132717Y824483D01*
X1132508Y824775D01*
X1132217Y824900D01*
X1131925Y824817D01*
X1131717Y824608D01*
X1131633Y824358D01*
Y823942D01*
X1131508Y823567D01*
X1131258Y823317D01*
X1130967Y823233D01*
X1130675Y823317D01*
X1130467Y823525D01*
X1130342Y823858D01*
X1130300Y824150D01*
G01X1138500Y628517D02*
X1141000D01*
Y629558D01*
X1140875Y629892D01*
X1140708Y630100D01*
X1140375Y630183D01*
X1140042Y630100D01*
X1139833Y629850D01*
X1139708Y629558D01*
Y628517D01*
G01Y629558D02*
X1138500Y630183D01*
G01X1140583Y631658D02*
X1140833Y631908D01*
X1140958Y632200D01*
X1141000Y632533D01*
X1140917Y632950D01*
X1140708Y633242D01*
X1140458Y633325D01*
X1140208Y633283D01*
X1140000Y633117D01*
X1139583Y632283D01*
X1139292Y631908D01*
X1138875Y631658D01*
X1138500Y631575D01*
Y633325D01*
G01X1138875Y634633D02*
X1138667Y634883D01*
X1138542Y635175D01*
X1138500Y635550D01*
X1138583Y635925D01*
X1138750Y636217D01*
X1139042Y636425D01*
X1139375Y636467D01*
X1139708Y636383D01*
X1139917Y636175D01*
X1140083Y635883D01*
X1140125Y635592D01*
X1140083Y635300D01*
X1139917Y634925D01*
X1141000Y635050D01*
Y636175D01*
G01X1139000Y637733D02*
X1138708Y637983D01*
X1138542Y638317D01*
X1138500Y638692D01*
X1138542Y639025D01*
X1138750Y639358D01*
X1139000Y639567D01*
X1139250Y639608D01*
X1139542Y639525D01*
X1139750Y639233D01*
X1139833Y638942D01*
Y638567D01*
G01Y638942D02*
X1139958Y639192D01*
X1140167Y639400D01*
X1140417Y639483D01*
X1140667Y639400D01*
X1140875Y639192D01*
X1141000Y638817D01*
X1140958Y638442D01*
X1140792Y638067D01*
G01X1146500Y628517D02*
X1149000D01*
Y629558D01*
X1148875Y629892D01*
X1148708Y630100D01*
X1148375Y630183D01*
X1148042Y630100D01*
X1147833Y629850D01*
X1147708Y629558D01*
Y628517D01*
G01Y629558D02*
X1146500Y630183D01*
G01X1148583Y631658D02*
X1148833Y631908D01*
X1148958Y632200D01*
X1149000Y632533D01*
X1148917Y632950D01*
X1148708Y633242D01*
X1148458Y633325D01*
X1148208Y633283D01*
X1148000Y633117D01*
X1147583Y632283D01*
X1147292Y631908D01*
X1146875Y631658D01*
X1146500Y631575D01*
Y633325D01*
G01Y635550D02*
X1146542Y635842D01*
X1146667Y636175D01*
X1146875Y636383D01*
X1147167Y636467D01*
X1147458Y636383D01*
X1147708Y636133D01*
X1147833Y635758D01*
Y635342D01*
X1147917Y635092D01*
X1148125Y634883D01*
X1148417Y634800D01*
X1148708Y634925D01*
X1148917Y635217D01*
X1149000Y635550D01*
X1148917Y635883D01*
X1148708Y636175D01*
X1148417Y636300D01*
X1148125Y636217D01*
X1147917Y636008D01*
X1147833Y635758D01*
Y635342D01*
X1147708Y634967D01*
X1147458Y634717D01*
X1147167Y634633D01*
X1146875Y634717D01*
X1146667Y634925D01*
X1146542Y635258D01*
X1146500Y635550D01*
G01X1146875Y637733D02*
X1146667Y637983D01*
X1146542Y638275D01*
X1146500Y638650D01*
X1146583Y639025D01*
X1146750Y639317D01*
X1147042Y639525D01*
X1147375Y639567D01*
X1147708Y639483D01*
X1147917Y639275D01*
X1148083Y638983D01*
X1148125Y638692D01*
X1148083Y638400D01*
X1147917Y638025D01*
X1149000Y638150D01*
Y639275D01*
G01X1158200Y665500D02*
Y663000D01*
G01X1159158Y665500D02*
X1157242D01*
G01X1155933Y663000D02*
Y665500D01*
X1154933D01*
X1154600Y665375D01*
X1154350Y665083D01*
X1154267Y664750D01*
X1154350Y664417D01*
X1154558Y664167D01*
X1154933Y664042D01*
X1155933D01*
G01X1152000Y663000D02*
Y665500D01*
X1152500Y665000D01*
G01Y663000D02*
X1151500D01*
G01X1148400D02*
Y665500D01*
X1149942Y663708D01*
X1147858D01*
G01X1145800Y663000D02*
Y665500D01*
X1146300Y665000D01*
G01Y663000D02*
X1145300D01*
G01X1139500Y650800D02*
X1135500D01*
Y658200D01*
G01X1155150Y670000D02*
Y667500D01*
G01X1156108Y670000D02*
X1154192D01*
G01X1152883Y667500D02*
Y670000D01*
X1151883D01*
X1151550Y669875D01*
X1151300Y669583D01*
X1151217Y669250D01*
X1151300Y668917D01*
X1151508Y668667D01*
X1151883Y668542D01*
X1152883D01*
G01X1148950Y667500D02*
X1148658Y667542D01*
X1148325Y667667D01*
X1148117Y667875D01*
X1148033Y668167D01*
X1148117Y668458D01*
X1148367Y668708D01*
X1148742Y668833D01*
X1149158D01*
X1149408Y668917D01*
X1149617Y669125D01*
X1149700Y669417D01*
X1149575Y669708D01*
X1149283Y669917D01*
X1148950Y670000D01*
X1148617Y669917D01*
X1148325Y669708D01*
X1148200Y669417D01*
X1148283Y669125D01*
X1148492Y668917D01*
X1148742Y668833D01*
X1149158D01*
X1149533Y668708D01*
X1149783Y668458D01*
X1149867Y668167D01*
X1149783Y667875D01*
X1149575Y667667D01*
X1149242Y667542D01*
X1148950Y667500D01*
G01X1146767Y667875D02*
X1146517Y667667D01*
X1146225Y667542D01*
X1145850Y667500D01*
X1145475Y667583D01*
X1145183Y667750D01*
X1144975Y668042D01*
X1144933Y668375D01*
X1145017Y668708D01*
X1145225Y668917D01*
X1145517Y669083D01*
X1145808Y669125D01*
X1146100Y669083D01*
X1146475Y668917D01*
X1146350Y670000D01*
X1145225D01*
G01X1150560Y685051D02*
X1150685Y684801D01*
X1150768Y684509D01*
Y684176D01*
X1150643Y683801D01*
X1150435Y683509D01*
X1150185Y683301D01*
X1149768Y683134D01*
X1149393Y683092D01*
X1149018Y683176D01*
X1148768Y683301D01*
X1148518Y683551D01*
X1148351Y683842D01*
X1148268Y684134D01*
Y684426D01*
X1148351Y684717D01*
X1148476Y684967D01*
X1148643Y685176D01*
G01X1150351Y686442D02*
X1150601Y686692D01*
X1150726Y686984D01*
X1150768Y687317D01*
X1150685Y687734D01*
X1150476Y688026D01*
X1150226Y688109D01*
X1149976Y688067D01*
X1149768Y687901D01*
X1149351Y687067D01*
X1149060Y686692D01*
X1148643Y686442D01*
X1148268Y686359D01*
Y688109D01*
G01Y690334D02*
X1150768D01*
X1150268Y689834D01*
G01X1148268D02*
Y690834D01*
G01X1148768Y692517D02*
X1148476Y692767D01*
X1148310Y693101D01*
X1148268Y693476D01*
X1148310Y693809D01*
X1148518Y694142D01*
X1148768Y694351D01*
X1149018Y694392D01*
X1149310Y694309D01*
X1149518Y694017D01*
X1149601Y693726D01*
Y693351D01*
G01Y693726D02*
X1149726Y693976D01*
X1149935Y694184D01*
X1150185Y694267D01*
X1150435Y694184D01*
X1150643Y693976D01*
X1150768Y693601D01*
X1150726Y693226D01*
X1150560Y692851D01*
G01X1148792Y715267D02*
X1148917Y715017D01*
X1149000Y714725D01*
Y714392D01*
X1148875Y714017D01*
X1148667Y713725D01*
X1148417Y713517D01*
X1148000Y713350D01*
X1147625Y713308D01*
X1147250Y713392D01*
X1147000Y713517D01*
X1146750Y713767D01*
X1146583Y714058D01*
X1146500Y714350D01*
Y714642D01*
X1146583Y714933D01*
X1146708Y715183D01*
X1146875Y715392D01*
G01X1148583Y716658D02*
X1148833Y716908D01*
X1148958Y717200D01*
X1149000Y717533D01*
X1148917Y717950D01*
X1148708Y718242D01*
X1148458Y718325D01*
X1148208Y718283D01*
X1148000Y718117D01*
X1147583Y717283D01*
X1147292Y716908D01*
X1146875Y716658D01*
X1146500Y716575D01*
Y718325D01*
G01X1149000Y720550D02*
X1148917Y720217D01*
X1148708Y719967D01*
X1148458Y719800D01*
X1148125Y719675D01*
X1147750Y719633D01*
X1147375Y719675D01*
X1147042Y719800D01*
X1146792Y719967D01*
X1146583Y720217D01*
X1146500Y720550D01*
X1146583Y720883D01*
X1146792Y721133D01*
X1147042Y721300D01*
X1147375Y721425D01*
X1147750Y721467D01*
X1148125Y721425D01*
X1148458Y721300D01*
X1148708Y721133D01*
X1148917Y720883D01*
X1149000Y720550D01*
G01X1146500Y724150D02*
X1149000D01*
X1147208Y722608D01*
Y724692D01*
G01X1148292Y800267D02*
X1148417Y800017D01*
X1148500Y799725D01*
Y799392D01*
X1148375Y799017D01*
X1148167Y798725D01*
X1147917Y798517D01*
X1147500Y798350D01*
X1147125Y798308D01*
X1146750Y798392D01*
X1146500Y798517D01*
X1146250Y798767D01*
X1146083Y799058D01*
X1146000Y799350D01*
Y799642D01*
X1146083Y799933D01*
X1146208Y800183D01*
X1146375Y800392D01*
G01X1146000Y802450D02*
X1148500D01*
X1148000Y801950D01*
G01X1146000D02*
Y802950D01*
G01X1146292Y804842D02*
X1146083Y805133D01*
X1146000Y805467D01*
X1146083Y805800D01*
X1146333Y806092D01*
X1146708Y806300D01*
X1147083Y806383D01*
X1147542D01*
X1147917Y806300D01*
X1148250Y806092D01*
X1148417Y805842D01*
X1148500Y805550D01*
X1148417Y805217D01*
X1148250Y804967D01*
X1148000Y804800D01*
X1147667Y804717D01*
X1147375Y804800D01*
X1147083Y805008D01*
X1146917Y805258D01*
X1146875Y805550D01*
X1146958Y805883D01*
X1147167Y806133D01*
X1147542Y806383D01*
G01X1146000Y808567D02*
X1146542Y808650D01*
X1147000Y808775D01*
X1147417Y808942D01*
X1147875Y809150D01*
X1148500Y809483D01*
Y807817D01*
G01X1164500Y630017D02*
X1167000D01*
Y631058D01*
X1166875Y631392D01*
X1166708Y631600D01*
X1166375Y631683D01*
X1166042Y631600D01*
X1165833Y631350D01*
X1165708Y631058D01*
Y630017D01*
G01Y631058D02*
X1164500Y631683D01*
G01X1166583Y633158D02*
X1166833Y633408D01*
X1166958Y633700D01*
X1167000Y634033D01*
X1166917Y634450D01*
X1166708Y634742D01*
X1166458Y634825D01*
X1166208Y634783D01*
X1166000Y634617D01*
X1165583Y633783D01*
X1165292Y633408D01*
X1164875Y633158D01*
X1164500Y633075D01*
Y634825D01*
G01Y637050D02*
X1164542Y637342D01*
X1164667Y637675D01*
X1164875Y637883D01*
X1165167Y637967D01*
X1165458Y637883D01*
X1165708Y637633D01*
X1165833Y637258D01*
Y636842D01*
X1165917Y636592D01*
X1166125Y636383D01*
X1166417Y636300D01*
X1166708Y636425D01*
X1166917Y636717D01*
X1167000Y637050D01*
X1166917Y637383D01*
X1166708Y637675D01*
X1166417Y637800D01*
X1166125Y637717D01*
X1165917Y637508D01*
X1165833Y637258D01*
Y636842D01*
X1165708Y636467D01*
X1165458Y636217D01*
X1165167Y636133D01*
X1164875Y636217D01*
X1164667Y636425D01*
X1164542Y636758D01*
X1164500Y637050D01*
G01X1166583Y639358D02*
X1166833Y639608D01*
X1166958Y639900D01*
X1167000Y640233D01*
X1166917Y640650D01*
X1166708Y640942D01*
X1166458Y641025D01*
X1166208Y640983D01*
X1166000Y640817D01*
X1165583Y639983D01*
X1165292Y639608D01*
X1164875Y639358D01*
X1164500Y639275D01*
Y641025D01*
G01X1156500Y630017D02*
X1159000D01*
Y631058D01*
X1158875Y631392D01*
X1158708Y631600D01*
X1158375Y631683D01*
X1158042Y631600D01*
X1157833Y631350D01*
X1157708Y631058D01*
Y630017D01*
G01Y631058D02*
X1156500Y631683D01*
G01X1158583Y633158D02*
X1158833Y633408D01*
X1158958Y633700D01*
X1159000Y634033D01*
X1158917Y634450D01*
X1158708Y634742D01*
X1158458Y634825D01*
X1158208Y634783D01*
X1158000Y634617D01*
X1157583Y633783D01*
X1157292Y633408D01*
X1156875Y633158D01*
X1156500Y633075D01*
Y634825D01*
G01Y637050D02*
X1156542Y637342D01*
X1156667Y637675D01*
X1156875Y637883D01*
X1157167Y637967D01*
X1157458Y637883D01*
X1157708Y637633D01*
X1157833Y637258D01*
Y636842D01*
X1157917Y636592D01*
X1158125Y636383D01*
X1158417Y636300D01*
X1158708Y636425D01*
X1158917Y636717D01*
X1159000Y637050D01*
X1158917Y637383D01*
X1158708Y637675D01*
X1158417Y637800D01*
X1158125Y637717D01*
X1157917Y637508D01*
X1157833Y637258D01*
Y636842D01*
X1157708Y636467D01*
X1157458Y636217D01*
X1157167Y636133D01*
X1156875Y636217D01*
X1156667Y636425D01*
X1156542Y636758D01*
X1156500Y637050D01*
G01Y640067D02*
X1157042Y640150D01*
X1157500Y640275D01*
X1157917Y640442D01*
X1158375Y640650D01*
X1159000Y640983D01*
Y639317D01*
G01X1160500Y630017D02*
X1163000D01*
Y631058D01*
X1162875Y631392D01*
X1162708Y631600D01*
X1162375Y631683D01*
X1162042Y631600D01*
X1161833Y631350D01*
X1161708Y631058D01*
Y630017D01*
G01Y631058D02*
X1160500Y631683D01*
G01X1162583Y633158D02*
X1162833Y633408D01*
X1162958Y633700D01*
X1163000Y634033D01*
X1162917Y634450D01*
X1162708Y634742D01*
X1162458Y634825D01*
X1162208Y634783D01*
X1162000Y634617D01*
X1161583Y633783D01*
X1161292Y633408D01*
X1160875Y633158D01*
X1160500Y633075D01*
Y634825D01*
G01Y637050D02*
X1160542Y637342D01*
X1160667Y637675D01*
X1160875Y637883D01*
X1161167Y637967D01*
X1161458Y637883D01*
X1161708Y637633D01*
X1161833Y637258D01*
Y636842D01*
X1161917Y636592D01*
X1162125Y636383D01*
X1162417Y636300D01*
X1162708Y636425D01*
X1162917Y636717D01*
X1163000Y637050D01*
X1162917Y637383D01*
X1162708Y637675D01*
X1162417Y637800D01*
X1162125Y637717D01*
X1161917Y637508D01*
X1161833Y637258D01*
Y636842D01*
X1161708Y636467D01*
X1161458Y636217D01*
X1161167Y636133D01*
X1160875Y636217D01*
X1160667Y636425D01*
X1160542Y636758D01*
X1160500Y637050D01*
G01Y640150D02*
X1160542Y640442D01*
X1160667Y640775D01*
X1160875Y640983D01*
X1161167Y641067D01*
X1161458Y640983D01*
X1161708Y640733D01*
X1161833Y640358D01*
Y639942D01*
X1161917Y639692D01*
X1162125Y639483D01*
X1162417Y639400D01*
X1162708Y639525D01*
X1162917Y639817D01*
X1163000Y640150D01*
X1162917Y640483D01*
X1162708Y640775D01*
X1162417Y640900D01*
X1162125Y640817D01*
X1161917Y640608D01*
X1161833Y640358D01*
Y639942D01*
X1161708Y639567D01*
X1161458Y639317D01*
X1161167Y639233D01*
X1160875Y639317D01*
X1160667Y639525D01*
X1160542Y639858D01*
X1160500Y640150D01*
G01X1168000Y642800D02*
X1164000D01*
Y650200D01*
G01X1155000Y642800D02*
X1151000D01*
Y650200D01*
G01X1160000Y642800D02*
X1156000D01*
Y650200D01*
G01X1164000Y642800D02*
X1160000D01*
Y650200D01*
G01X1174700Y666500D02*
Y664000D01*
G01X1175658Y666500D02*
X1173742D01*
G01X1172433Y664000D02*
Y666500D01*
X1171433D01*
X1171100Y666375D01*
X1170850Y666083D01*
X1170767Y665750D01*
X1170850Y665417D01*
X1171058Y665167D01*
X1171433Y665042D01*
X1172433D01*
G01X1168500Y664000D02*
Y666500D01*
X1169000Y666000D01*
G01Y664000D02*
X1168000D01*
G01X1166317Y664375D02*
X1166067Y664167D01*
X1165775Y664042D01*
X1165400Y664000D01*
X1165025Y664083D01*
X1164733Y664250D01*
X1164525Y664542D01*
X1164483Y664875D01*
X1164567Y665208D01*
X1164775Y665417D01*
X1165067Y665583D01*
X1165358Y665625D01*
X1165650Y665583D01*
X1166025Y665417D01*
X1165900Y666500D01*
X1164775D01*
G01X1163092Y665042D02*
X1162800Y665333D01*
X1162550Y665500D01*
X1162217Y665583D01*
X1161925Y665500D01*
X1161717Y665333D01*
X1161550Y665083D01*
X1161508Y664792D01*
X1161550Y664542D01*
X1161717Y664292D01*
X1161967Y664083D01*
X1162258Y664000D01*
X1162592Y664083D01*
X1162883Y664333D01*
X1163050Y664708D01*
X1163092Y665125D01*
X1163008Y665667D01*
X1162883Y665958D01*
X1162675Y666250D01*
X1162383Y666458D01*
X1162092Y666500D01*
X1161800Y666417D01*
X1161592Y666208D01*
G01X1166500Y677300D02*
Y681300D01*
X1173900D01*
G01X1154792Y685267D02*
X1154917Y685017D01*
X1155000Y684725D01*
Y684392D01*
X1154875Y684017D01*
X1154667Y683725D01*
X1154417Y683517D01*
X1154000Y683350D01*
X1153625Y683308D01*
X1153250Y683392D01*
X1153000Y683517D01*
X1152750Y683767D01*
X1152583Y684058D01*
X1152500Y684350D01*
Y684642D01*
X1152583Y684933D01*
X1152708Y685183D01*
X1152875Y685392D01*
G01X1154583Y686658D02*
X1154833Y686908D01*
X1154958Y687200D01*
X1155000Y687533D01*
X1154917Y687950D01*
X1154708Y688242D01*
X1154458Y688325D01*
X1154208Y688283D01*
X1154000Y688117D01*
X1153583Y687283D01*
X1153292Y686908D01*
X1152875Y686658D01*
X1152500Y686575D01*
Y688325D01*
G01Y690550D02*
X1155000D01*
X1154500Y690050D01*
G01X1152500D02*
Y691050D01*
G01Y693650D02*
X1152542Y693942D01*
X1152667Y694275D01*
X1152875Y694483D01*
X1153167Y694567D01*
X1153458Y694483D01*
X1153708Y694233D01*
X1153833Y693858D01*
Y693442D01*
X1153917Y693192D01*
X1154125Y692983D01*
X1154417Y692900D01*
X1154708Y693025D01*
X1154917Y693317D01*
X1155000Y693650D01*
X1154917Y693983D01*
X1154708Y694275D01*
X1154417Y694400D01*
X1154125Y694317D01*
X1153917Y694108D01*
X1153833Y693858D01*
Y693442D01*
X1153708Y693067D01*
X1153458Y692817D01*
X1153167Y692733D01*
X1152875Y692817D01*
X1152667Y693025D01*
X1152542Y693358D01*
X1152500Y693650D01*
G01X1159292Y685267D02*
X1159417Y685017D01*
X1159500Y684725D01*
Y684392D01*
X1159375Y684017D01*
X1159167Y683725D01*
X1158917Y683517D01*
X1158500Y683350D01*
X1158125Y683308D01*
X1157750Y683392D01*
X1157500Y683517D01*
X1157250Y683767D01*
X1157083Y684058D01*
X1157000Y684350D01*
Y684642D01*
X1157083Y684933D01*
X1157208Y685183D01*
X1157375Y685392D01*
G01X1159083Y686658D02*
X1159333Y686908D01*
X1159458Y687200D01*
X1159500Y687533D01*
X1159417Y687950D01*
X1159208Y688242D01*
X1158958Y688325D01*
X1158708Y688283D01*
X1158500Y688117D01*
X1158083Y687283D01*
X1157792Y686908D01*
X1157375Y686658D01*
X1157000Y686575D01*
Y688325D01*
G01Y690550D02*
X1159500D01*
X1159000Y690050D01*
G01X1157000D02*
Y691050D01*
G01Y693567D02*
X1157542Y693650D01*
X1158000Y693775D01*
X1158417Y693942D01*
X1158875Y694150D01*
X1159500Y694483D01*
Y692817D01*
G01X1160292Y709267D02*
X1160417Y709017D01*
X1160500Y708725D01*
Y708392D01*
X1160375Y708017D01*
X1160167Y707725D01*
X1159917Y707517D01*
X1159500Y707350D01*
X1159125Y707308D01*
X1158750Y707392D01*
X1158500Y707517D01*
X1158250Y707767D01*
X1158083Y708058D01*
X1158000Y708350D01*
Y708642D01*
X1158083Y708933D01*
X1158208Y709183D01*
X1158375Y709392D01*
G01X1160083Y710658D02*
X1160333Y710908D01*
X1160458Y711200D01*
X1160500Y711533D01*
X1160417Y711950D01*
X1160208Y712242D01*
X1159958Y712325D01*
X1159708Y712283D01*
X1159500Y712117D01*
X1159083Y711283D01*
X1158792Y710908D01*
X1158375Y710658D01*
X1158000Y710575D01*
Y712325D01*
G01Y714550D02*
X1160500D01*
X1160000Y714050D01*
G01X1158000D02*
Y715050D01*
G01Y717650D02*
X1160500D01*
X1160000Y717150D01*
G01X1158000D02*
Y718150D01*
G01X1173070Y722680D02*
Y720180D01*
G01X1174028Y722680D02*
X1172112D01*
G01X1170803Y720180D02*
Y722680D01*
X1169803D01*
X1169470Y722555D01*
X1169220Y722263D01*
X1169137Y721930D01*
X1169220Y721597D01*
X1169428Y721347D01*
X1169803Y721222D01*
X1170803D01*
G01X1166870Y720180D02*
Y722680D01*
X1167370Y722180D01*
G01Y720180D02*
X1166370D01*
G01X1163770Y722680D02*
X1164103Y722597D01*
X1164353Y722388D01*
X1164520Y722138D01*
X1164645Y721805D01*
X1164687Y721430D01*
X1164645Y721055D01*
X1164520Y720722D01*
X1164353Y720472D01*
X1164103Y720263D01*
X1163770Y720180D01*
X1163437Y720263D01*
X1163187Y720472D01*
X1163020Y720722D01*
X1162895Y721055D01*
X1162853Y721430D01*
X1162895Y721805D01*
X1163020Y722138D01*
X1163187Y722388D01*
X1163437Y722597D01*
X1163770Y722680D01*
G01X1160170Y720180D02*
Y722680D01*
X1161712Y720888D01*
X1159628D01*
G01X1177200Y727500D02*
Y725000D01*
G01X1178158Y727500D02*
X1176242D01*
G01X1174933Y725000D02*
Y727500D01*
X1173933D01*
X1173600Y727375D01*
X1173350Y727083D01*
X1173267Y726750D01*
X1173350Y726417D01*
X1173558Y726167D01*
X1173933Y726042D01*
X1174933D01*
G01X1171000Y725000D02*
Y727500D01*
X1171500Y727000D01*
G01Y725000D02*
X1170500D01*
G01X1167900D02*
Y727500D01*
X1168400Y727000D01*
G01Y725000D02*
X1167400D01*
G01X1165592Y726042D02*
X1165300Y726333D01*
X1165050Y726500D01*
X1164717Y726583D01*
X1164425Y726500D01*
X1164217Y726333D01*
X1164050Y726083D01*
X1164008Y725792D01*
X1164050Y725542D01*
X1164217Y725292D01*
X1164467Y725083D01*
X1164758Y725000D01*
X1165092Y725083D01*
X1165383Y725333D01*
X1165550Y725708D01*
X1165592Y726125D01*
X1165508Y726667D01*
X1165383Y726958D01*
X1165175Y727250D01*
X1164883Y727458D01*
X1164592Y727500D01*
X1164300Y727417D01*
X1164092Y727208D01*
G01X1176150Y718000D02*
Y715500D01*
G01X1177108Y718000D02*
X1175192D01*
G01X1173883Y715500D02*
Y718000D01*
X1172883D01*
X1172550Y717875D01*
X1172300Y717583D01*
X1172217Y717250D01*
X1172300Y716917D01*
X1172508Y716667D01*
X1172883Y716542D01*
X1173883D01*
G01X1169950Y715500D02*
X1169658Y715542D01*
X1169325Y715667D01*
X1169117Y715875D01*
X1169033Y716167D01*
X1169117Y716458D01*
X1169367Y716708D01*
X1169742Y716833D01*
X1170158D01*
X1170408Y716917D01*
X1170617Y717125D01*
X1170700Y717417D01*
X1170575Y717708D01*
X1170283Y717917D01*
X1169950Y718000D01*
X1169617Y717917D01*
X1169325Y717708D01*
X1169200Y717417D01*
X1169283Y717125D01*
X1169492Y716917D01*
X1169742Y716833D01*
X1170158D01*
X1170533Y716708D01*
X1170783Y716458D01*
X1170867Y716167D01*
X1170783Y715875D01*
X1170575Y715667D01*
X1170242Y715542D01*
X1169950Y715500D01*
G01X1167558Y715792D02*
X1167267Y715583D01*
X1166933Y715500D01*
X1166600Y715583D01*
X1166308Y715833D01*
X1166100Y716208D01*
X1166017Y716583D01*
Y717042D01*
X1166100Y717417D01*
X1166308Y717750D01*
X1166558Y717917D01*
X1166850Y718000D01*
X1167183Y717917D01*
X1167433Y717750D01*
X1167600Y717500D01*
X1167683Y717167D01*
X1167600Y716875D01*
X1167392Y716583D01*
X1167142Y716417D01*
X1166850Y716375D01*
X1166517Y716458D01*
X1166267Y716667D01*
X1166017Y717042D01*
G01X1177700Y732000D02*
Y729500D01*
G01X1178658Y732000D02*
X1176742D01*
G01X1175433Y729500D02*
Y732000D01*
X1174433D01*
X1174100Y731875D01*
X1173850Y731583D01*
X1173767Y731250D01*
X1173850Y730917D01*
X1174058Y730667D01*
X1174433Y730542D01*
X1175433D01*
G01X1171500Y729500D02*
Y732000D01*
X1172000Y731500D01*
G01Y729500D02*
X1171000D01*
G01X1169108Y729792D02*
X1168817Y729583D01*
X1168483Y729500D01*
X1168150Y729583D01*
X1167858Y729833D01*
X1167650Y730208D01*
X1167567Y730583D01*
Y731042D01*
X1167650Y731417D01*
X1167858Y731750D01*
X1168108Y731917D01*
X1168400Y732000D01*
X1168733Y731917D01*
X1168983Y731750D01*
X1169150Y731500D01*
X1169233Y731167D01*
X1169150Y730875D01*
X1168942Y730583D01*
X1168692Y730417D01*
X1168400Y730375D01*
X1168067Y730458D01*
X1167817Y730667D01*
X1167567Y731042D01*
G01X1165300Y729500D02*
Y732000D01*
X1165800Y731500D01*
G01Y729500D02*
X1164800D01*
G01X1155592Y812267D02*
X1155717Y812017D01*
X1155800Y811725D01*
Y811392D01*
X1155675Y811017D01*
X1155467Y810725D01*
X1155217Y810517D01*
X1154800Y810350D01*
X1154425Y810308D01*
X1154050Y810392D01*
X1153800Y810517D01*
X1153550Y810767D01*
X1153383Y811058D01*
X1153300Y811350D01*
Y811642D01*
X1153383Y811933D01*
X1153508Y812183D01*
X1153675Y812392D01*
G01X1153300Y814450D02*
X1155800D01*
X1155300Y813950D01*
G01X1153300D02*
Y814950D01*
G01Y817467D02*
X1153842Y817550D01*
X1154300Y817675D01*
X1154717Y817842D01*
X1155175Y818050D01*
X1155800Y818383D01*
Y816717D01*
G01X1153300Y820650D02*
X1155800D01*
X1155300Y820150D01*
G01X1153300D02*
Y821150D01*
G01X1161592Y810767D02*
X1161717Y810517D01*
X1161800Y810225D01*
Y809892D01*
X1161675Y809517D01*
X1161467Y809225D01*
X1161217Y809017D01*
X1160800Y808850D01*
X1160425Y808808D01*
X1160050Y808892D01*
X1159800Y809017D01*
X1159550Y809267D01*
X1159383Y809558D01*
X1159300Y809850D01*
Y810142D01*
X1159383Y810433D01*
X1159508Y810683D01*
X1159675Y810892D01*
G01X1159300Y812950D02*
X1161800D01*
X1161300Y812450D01*
G01X1159300D02*
Y813450D01*
G01Y815967D02*
X1159842Y816050D01*
X1160300Y816175D01*
X1160717Y816342D01*
X1161175Y816550D01*
X1161800Y816883D01*
Y815217D01*
G01X1159800Y818233D02*
X1159508Y818483D01*
X1159342Y818817D01*
X1159300Y819192D01*
X1159342Y819525D01*
X1159550Y819858D01*
X1159800Y820067D01*
X1160050Y820108D01*
X1160342Y820025D01*
X1160550Y819733D01*
X1160633Y819442D01*
Y819067D01*
G01Y819442D02*
X1160758Y819692D01*
X1160967Y819900D01*
X1161217Y819983D01*
X1161467Y819900D01*
X1161675Y819692D01*
X1161800Y819317D01*
X1161758Y818942D01*
X1161592Y818567D01*
G01X1166592Y810767D02*
X1166717Y810517D01*
X1166800Y810225D01*
Y809892D01*
X1166675Y809517D01*
X1166467Y809225D01*
X1166217Y809017D01*
X1165800Y808850D01*
X1165425Y808808D01*
X1165050Y808892D01*
X1164800Y809017D01*
X1164550Y809267D01*
X1164383Y809558D01*
X1164300Y809850D01*
Y810142D01*
X1164383Y810433D01*
X1164508Y810683D01*
X1164675Y810892D01*
G01X1164300Y812950D02*
X1166800D01*
X1166300Y812450D01*
G01X1164300D02*
Y813450D01*
G01Y816050D02*
X1164342Y816342D01*
X1164467Y816675D01*
X1164675Y816883D01*
X1164967Y816967D01*
X1165258Y816883D01*
X1165508Y816633D01*
X1165633Y816258D01*
Y815842D01*
X1165717Y815592D01*
X1165925Y815383D01*
X1166217Y815300D01*
X1166508Y815425D01*
X1166717Y815717D01*
X1166800Y816050D01*
X1166717Y816383D01*
X1166508Y816675D01*
X1166217Y816800D01*
X1165925Y816717D01*
X1165717Y816508D01*
X1165633Y816258D01*
Y815842D01*
X1165508Y815467D01*
X1165258Y815217D01*
X1164967Y815133D01*
X1164675Y815217D01*
X1164467Y815425D01*
X1164342Y815758D01*
X1164300Y816050D01*
G01Y819150D02*
X1166800D01*
X1166300Y818650D01*
G01X1164300D02*
Y819650D01*
G01X1177000Y629517D02*
X1179500D01*
Y630558D01*
X1179375Y630892D01*
X1179208Y631100D01*
X1178875Y631183D01*
X1178542Y631100D01*
X1178333Y630850D01*
X1178208Y630558D01*
Y629517D01*
G01Y630558D02*
X1177000Y631183D01*
G01X1177375Y632533D02*
X1177167Y632783D01*
X1177042Y633075D01*
X1177000Y633450D01*
X1177083Y633825D01*
X1177250Y634117D01*
X1177542Y634325D01*
X1177875Y634367D01*
X1178208Y634283D01*
X1178417Y634075D01*
X1178583Y633783D01*
X1178625Y633492D01*
X1178583Y633200D01*
X1178417Y632825D01*
X1179500Y632950D01*
Y634075D01*
G01X1177500Y635633D02*
X1177208Y635883D01*
X1177042Y636217D01*
X1177000Y636592D01*
X1177042Y636925D01*
X1177250Y637258D01*
X1177500Y637467D01*
X1177750Y637508D01*
X1178042Y637425D01*
X1178250Y637133D01*
X1178333Y636842D01*
Y636467D01*
G01Y636842D02*
X1178458Y637092D01*
X1178667Y637300D01*
X1178917Y637383D01*
X1179167Y637300D01*
X1179375Y637092D01*
X1179500Y636717D01*
X1179458Y636342D01*
X1179292Y635967D01*
G01X1177000Y639650D02*
X1177042Y639942D01*
X1177167Y640275D01*
X1177375Y640483D01*
X1177667Y640567D01*
X1177958Y640483D01*
X1178208Y640233D01*
X1178333Y639858D01*
Y639442D01*
X1178417Y639192D01*
X1178625Y638983D01*
X1178917Y638900D01*
X1179208Y639025D01*
X1179417Y639317D01*
X1179500Y639650D01*
X1179417Y639983D01*
X1179208Y640275D01*
X1178917Y640400D01*
X1178625Y640317D01*
X1178417Y640108D01*
X1178333Y639858D01*
Y639442D01*
X1178208Y639067D01*
X1177958Y638817D01*
X1177667Y638733D01*
X1177375Y638817D01*
X1177167Y639025D01*
X1177042Y639358D01*
X1177000Y639650D01*
G01X1172000Y645300D02*
X1169500D01*
G01X1172000Y644342D02*
Y646258D01*
G01X1169500Y647567D02*
X1172000D01*
Y648567D01*
X1171875Y648900D01*
X1171583Y649150D01*
X1171250Y649233D01*
X1170917Y649150D01*
X1170667Y648942D01*
X1170542Y648567D01*
Y647567D01*
G01X1169500Y651500D02*
X1172000D01*
X1171500Y651000D01*
G01X1169500D02*
Y652000D01*
G01X1169875Y653683D02*
X1169667Y653933D01*
X1169542Y654225D01*
X1169500Y654600D01*
X1169583Y654975D01*
X1169750Y655267D01*
X1170042Y655475D01*
X1170375Y655517D01*
X1170708Y655433D01*
X1170917Y655225D01*
X1171083Y654933D01*
X1171125Y654642D01*
X1171083Y654350D01*
X1170917Y653975D01*
X1172000Y654100D01*
Y655225D01*
G01X1171583Y656908D02*
X1171833Y657158D01*
X1171958Y657450D01*
X1172000Y657783D01*
X1171917Y658200D01*
X1171708Y658492D01*
X1171458Y658575D01*
X1171208Y658533D01*
X1171000Y658367D01*
X1170583Y657533D01*
X1170292Y657158D01*
X1169875Y656908D01*
X1169500Y656825D01*
Y658575D01*
G01X1176500Y649700D02*
X1180500D01*
Y642300D01*
G01X1190200Y682000D02*
Y679500D01*
G01X1191158Y682000D02*
X1189242D01*
G01X1187933Y679500D02*
Y682000D01*
X1186933D01*
X1186600Y681875D01*
X1186350Y681583D01*
X1186267Y681250D01*
X1186350Y680917D01*
X1186558Y680667D01*
X1186933Y680542D01*
X1187933D01*
G01X1184000Y679500D02*
Y682000D01*
X1184500Y681500D01*
G01Y679500D02*
X1183500D01*
G01X1180983D02*
X1180900Y680042D01*
X1180775Y680500D01*
X1180608Y680917D01*
X1180400Y681375D01*
X1180067Y682000D01*
X1181733D01*
G01X1178508Y679792D02*
X1178217Y679583D01*
X1177883Y679500D01*
X1177550Y679583D01*
X1177258Y679833D01*
X1177050Y680208D01*
X1176967Y680583D01*
Y681042D01*
X1177050Y681417D01*
X1177258Y681750D01*
X1177508Y681917D01*
X1177800Y682000D01*
X1178133Y681917D01*
X1178383Y681750D01*
X1178550Y681500D01*
X1178633Y681167D01*
X1178550Y680875D01*
X1178342Y680583D01*
X1178092Y680417D01*
X1177800Y680375D01*
X1177467Y680458D01*
X1177217Y680667D01*
X1176967Y681042D01*
G01X1183733Y674292D02*
X1183983Y674417D01*
X1184275Y674500D01*
X1184608D01*
X1184983Y674375D01*
X1185275Y674167D01*
X1185483Y673917D01*
X1185650Y673500D01*
X1185692Y673125D01*
X1185608Y672750D01*
X1185483Y672500D01*
X1185233Y672250D01*
X1184942Y672083D01*
X1184650Y672000D01*
X1184358D01*
X1184067Y672083D01*
X1183817Y672208D01*
X1183608Y672375D01*
G01X1182342Y674083D02*
X1182092Y674333D01*
X1181800Y674458D01*
X1181467Y674500D01*
X1181050Y674417D01*
X1180758Y674208D01*
X1180675Y673958D01*
X1180717Y673708D01*
X1180883Y673500D01*
X1181717Y673083D01*
X1182092Y672792D01*
X1182342Y672375D01*
X1182425Y672000D01*
X1180675D01*
G01X1178450D02*
Y674500D01*
X1178950Y674000D01*
G01Y672000D02*
X1177950D01*
G01X1176142Y673042D02*
X1175850Y673333D01*
X1175600Y673500D01*
X1175267Y673583D01*
X1174975Y673500D01*
X1174767Y673333D01*
X1174600Y673083D01*
X1174558Y672792D01*
X1174600Y672542D01*
X1174767Y672292D01*
X1175017Y672083D01*
X1175308Y672000D01*
X1175642Y672083D01*
X1175933Y672333D01*
X1176100Y672708D01*
X1176142Y673125D01*
X1176058Y673667D01*
X1175933Y673958D01*
X1175725Y674250D01*
X1175433Y674458D01*
X1175142Y674500D01*
X1174850Y674417D01*
X1174642Y674208D01*
G01X1186733Y686792D02*
X1186983Y686917D01*
X1187275Y687000D01*
X1187608D01*
X1187983Y686875D01*
X1188275Y686667D01*
X1188483Y686417D01*
X1188650Y686000D01*
X1188692Y685625D01*
X1188608Y685250D01*
X1188483Y685000D01*
X1188233Y684750D01*
X1187942Y684583D01*
X1187650Y684500D01*
X1187358D01*
X1187067Y684583D01*
X1186817Y684708D01*
X1186608Y684875D01*
G01X1185342Y686583D02*
X1185092Y686833D01*
X1184800Y686958D01*
X1184467Y687000D01*
X1184050Y686917D01*
X1183758Y686708D01*
X1183675Y686458D01*
X1183717Y686208D01*
X1183883Y686000D01*
X1184717Y685583D01*
X1185092Y685292D01*
X1185342Y684875D01*
X1185425Y684500D01*
X1183675D01*
G01X1181450D02*
Y687000D01*
X1181950Y686500D01*
G01Y684500D02*
X1180950D01*
G01X1179267Y684875D02*
X1179017Y684667D01*
X1178725Y684542D01*
X1178350Y684500D01*
X1177975Y684583D01*
X1177683Y684750D01*
X1177475Y685042D01*
X1177433Y685375D01*
X1177517Y685708D01*
X1177725Y685917D01*
X1178017Y686083D01*
X1178308Y686125D01*
X1178600Y686083D01*
X1178975Y685917D01*
X1178850Y687000D01*
X1177725D01*
G01X1184233Y694792D02*
X1184483Y694917D01*
X1184775Y695000D01*
X1185108D01*
X1185483Y694875D01*
X1185775Y694667D01*
X1185983Y694417D01*
X1186150Y694000D01*
X1186192Y693625D01*
X1186108Y693250D01*
X1185983Y693000D01*
X1185733Y692750D01*
X1185442Y692583D01*
X1185150Y692500D01*
X1184858D01*
X1184567Y692583D01*
X1184317Y692708D01*
X1184108Y692875D01*
G01X1182842Y694583D02*
X1182592Y694833D01*
X1182300Y694958D01*
X1181967Y695000D01*
X1181550Y694917D01*
X1181258Y694708D01*
X1181175Y694458D01*
X1181217Y694208D01*
X1181383Y694000D01*
X1182217Y693583D01*
X1182592Y693292D01*
X1182842Y692875D01*
X1182925Y692500D01*
X1181175D01*
G01X1178950D02*
Y695000D01*
X1179450Y694500D01*
G01Y692500D02*
X1178450D01*
G01X1175350D02*
Y695000D01*
X1176892Y693208D01*
X1174808D01*
G01X1184233Y690792D02*
X1184483Y690917D01*
X1184775Y691000D01*
X1185108D01*
X1185483Y690875D01*
X1185775Y690667D01*
X1185983Y690417D01*
X1186150Y690000D01*
X1186192Y689625D01*
X1186108Y689250D01*
X1185983Y689000D01*
X1185733Y688750D01*
X1185442Y688583D01*
X1185150Y688500D01*
X1184858D01*
X1184567Y688583D01*
X1184317Y688708D01*
X1184108Y688875D01*
G01X1182842Y690583D02*
X1182592Y690833D01*
X1182300Y690958D01*
X1181967Y691000D01*
X1181550Y690917D01*
X1181258Y690708D01*
X1181175Y690458D01*
X1181217Y690208D01*
X1181383Y690000D01*
X1182217Y689583D01*
X1182592Y689292D01*
X1182842Y688875D01*
X1182925Y688500D01*
X1181175D01*
G01X1178950Y691000D02*
X1179283Y690917D01*
X1179533Y690708D01*
X1179700Y690458D01*
X1179825Y690125D01*
X1179867Y689750D01*
X1179825Y689375D01*
X1179700Y689042D01*
X1179533Y688792D01*
X1179283Y688583D01*
X1178950Y688500D01*
X1178617Y688583D01*
X1178367Y688792D01*
X1178200Y689042D01*
X1178075Y689375D01*
X1178033Y689750D01*
X1178075Y690125D01*
X1178200Y690458D01*
X1178367Y690708D01*
X1178617Y690917D01*
X1178950Y691000D01*
G01X1176642Y689542D02*
X1176350Y689833D01*
X1176100Y690000D01*
X1175767Y690083D01*
X1175475Y690000D01*
X1175267Y689833D01*
X1175100Y689583D01*
X1175058Y689292D01*
X1175100Y689042D01*
X1175267Y688792D01*
X1175517Y688583D01*
X1175808Y688500D01*
X1176142Y688583D01*
X1176433Y688833D01*
X1176600Y689208D01*
X1176642Y689625D01*
X1176558Y690167D01*
X1176433Y690458D01*
X1176225Y690750D01*
X1175933Y690958D01*
X1175642Y691000D01*
X1175350Y690917D01*
X1175142Y690708D01*
G01X1184233Y698792D02*
X1184483Y698917D01*
X1184775Y699000D01*
X1185108D01*
X1185483Y698875D01*
X1185775Y698667D01*
X1185983Y698417D01*
X1186150Y698000D01*
X1186192Y697625D01*
X1186108Y697250D01*
X1185983Y697000D01*
X1185733Y696750D01*
X1185442Y696583D01*
X1185150Y696500D01*
X1184858D01*
X1184567Y696583D01*
X1184317Y696708D01*
X1184108Y696875D01*
G01X1182842Y698583D02*
X1182592Y698833D01*
X1182300Y698958D01*
X1181967Y699000D01*
X1181550Y698917D01*
X1181258Y698708D01*
X1181175Y698458D01*
X1181217Y698208D01*
X1181383Y698000D01*
X1182217Y697583D01*
X1182592Y697292D01*
X1182842Y696875D01*
X1182925Y696500D01*
X1181175D01*
G01X1178950Y699000D02*
X1179283Y698917D01*
X1179533Y698708D01*
X1179700Y698458D01*
X1179825Y698125D01*
X1179867Y697750D01*
X1179825Y697375D01*
X1179700Y697042D01*
X1179533Y696792D01*
X1179283Y696583D01*
X1178950Y696500D01*
X1178617Y696583D01*
X1178367Y696792D01*
X1178200Y697042D01*
X1178075Y697375D01*
X1178033Y697750D01*
X1178075Y698125D01*
X1178200Y698458D01*
X1178367Y698708D01*
X1178617Y698917D01*
X1178950Y699000D01*
G01X1176767Y696875D02*
X1176517Y696667D01*
X1176225Y696542D01*
X1175850Y696500D01*
X1175475Y696583D01*
X1175183Y696750D01*
X1174975Y697042D01*
X1174933Y697375D01*
X1175017Y697708D01*
X1175225Y697917D01*
X1175517Y698083D01*
X1175808Y698125D01*
X1176100Y698083D01*
X1176475Y697917D01*
X1176350Y699000D01*
X1175225D01*
G01X1195700Y710500D02*
Y708000D01*
G01X1196658Y710500D02*
X1194742D01*
G01X1193433Y708000D02*
Y710500D01*
X1192433D01*
X1192100Y710375D01*
X1191850Y710083D01*
X1191767Y709750D01*
X1191850Y709417D01*
X1192058Y709167D01*
X1192433Y709042D01*
X1193433D01*
G01X1189500Y708000D02*
Y710500D01*
X1190000Y710000D01*
G01Y708000D02*
X1189000D01*
G01X1187317Y708375D02*
X1187067Y708167D01*
X1186775Y708042D01*
X1186400Y708000D01*
X1186025Y708083D01*
X1185733Y708250D01*
X1185525Y708542D01*
X1185483Y708875D01*
X1185567Y709208D01*
X1185775Y709417D01*
X1186067Y709583D01*
X1186358Y709625D01*
X1186650Y709583D01*
X1187025Y709417D01*
X1186900Y710500D01*
X1185775D01*
G01X1184008Y708292D02*
X1183717Y708083D01*
X1183383Y708000D01*
X1183050Y708083D01*
X1182758Y708333D01*
X1182550Y708708D01*
X1182467Y709083D01*
Y709542D01*
X1182550Y709917D01*
X1182758Y710250D01*
X1183008Y710417D01*
X1183300Y710500D01*
X1183633Y710417D01*
X1183883Y710250D01*
X1184050Y710000D01*
X1184133Y709667D01*
X1184050Y709375D01*
X1183842Y709083D01*
X1183592Y708917D01*
X1183300Y708875D01*
X1182967Y708958D01*
X1182717Y709167D01*
X1182467Y709542D01*
G01X1180292Y705767D02*
X1180417Y705517D01*
X1180500Y705225D01*
Y704892D01*
X1180375Y704517D01*
X1180167Y704225D01*
X1179917Y704017D01*
X1179500Y703850D01*
X1179125Y703808D01*
X1178750Y703892D01*
X1178500Y704017D01*
X1178250Y704267D01*
X1178083Y704558D01*
X1178000Y704850D01*
Y705142D01*
X1178083Y705433D01*
X1178208Y705683D01*
X1178375Y705892D01*
G01X1180083Y707158D02*
X1180333Y707408D01*
X1180458Y707700D01*
X1180500Y708033D01*
X1180417Y708450D01*
X1180208Y708742D01*
X1179958Y708825D01*
X1179708Y708783D01*
X1179500Y708617D01*
X1179083Y707783D01*
X1178792Y707408D01*
X1178375Y707158D01*
X1178000Y707075D01*
Y708825D01*
G01X1180500Y711050D02*
X1180417Y710717D01*
X1180208Y710467D01*
X1179958Y710300D01*
X1179625Y710175D01*
X1179250Y710133D01*
X1178875Y710175D01*
X1178542Y710300D01*
X1178292Y710467D01*
X1178083Y710717D01*
X1178000Y711050D01*
X1178083Y711383D01*
X1178292Y711633D01*
X1178542Y711800D01*
X1178875Y711925D01*
X1179250Y711967D01*
X1179625Y711925D01*
X1179958Y711800D01*
X1180208Y711633D01*
X1180417Y711383D01*
X1180500Y711050D01*
G01X1178000Y714150D02*
X1178042Y714442D01*
X1178167Y714775D01*
X1178375Y714983D01*
X1178667Y715067D01*
X1178958Y714983D01*
X1179208Y714733D01*
X1179333Y714358D01*
Y713942D01*
X1179417Y713692D01*
X1179625Y713483D01*
X1179917Y713400D01*
X1180208Y713525D01*
X1180417Y713817D01*
X1180500Y714150D01*
X1180417Y714483D01*
X1180208Y714775D01*
X1179917Y714900D01*
X1179625Y714817D01*
X1179417Y714608D01*
X1179333Y714358D01*
Y713942D01*
X1179208Y713567D01*
X1178958Y713317D01*
X1178667Y713233D01*
X1178375Y713317D01*
X1178167Y713525D01*
X1178042Y713858D01*
X1178000Y714150D01*
G01X1183000Y744300D02*
X1180500D01*
G01X1183000Y743342D02*
Y745258D01*
G01X1180500Y746567D02*
X1183000D01*
Y747567D01*
X1182875Y747900D01*
X1182583Y748150D01*
X1182250Y748233D01*
X1181917Y748150D01*
X1181667Y747942D01*
X1181542Y747567D01*
Y746567D01*
G01X1180500Y750500D02*
X1183000D01*
X1182500Y750000D01*
G01X1180500D02*
Y751000D01*
G01Y753600D02*
X1183000D01*
X1182500Y753100D01*
G01X1180500D02*
Y754100D01*
G01Y756700D02*
X1183000D01*
X1182500Y756200D01*
G01X1180500D02*
Y757200D01*
G01X1187200Y737000D02*
Y734500D01*
G01X1188158Y737000D02*
X1186242D01*
G01X1184933Y734500D02*
Y737000D01*
X1183933D01*
X1183600Y736875D01*
X1183350Y736583D01*
X1183267Y736250D01*
X1183350Y735917D01*
X1183558Y735667D01*
X1183933Y735542D01*
X1184933D01*
G01X1181000Y734500D02*
Y737000D01*
X1181500Y736500D01*
G01Y734500D02*
X1180500D01*
G01X1178692Y735542D02*
X1178400Y735833D01*
X1178150Y736000D01*
X1177817Y736083D01*
X1177525Y736000D01*
X1177317Y735833D01*
X1177150Y735583D01*
X1177108Y735292D01*
X1177150Y735042D01*
X1177317Y734792D01*
X1177567Y734583D01*
X1177858Y734500D01*
X1178192Y734583D01*
X1178483Y734833D01*
X1178650Y735208D01*
X1178692Y735625D01*
X1178608Y736167D01*
X1178483Y736458D01*
X1178275Y736750D01*
X1177983Y736958D01*
X1177692Y737000D01*
X1177400Y736917D01*
X1177192Y736708D01*
G01X1174800Y737000D02*
X1175133Y736917D01*
X1175383Y736708D01*
X1175550Y736458D01*
X1175675Y736125D01*
X1175717Y735750D01*
X1175675Y735375D01*
X1175550Y735042D01*
X1175383Y734792D01*
X1175133Y734583D01*
X1174800Y734500D01*
X1174467Y734583D01*
X1174217Y734792D01*
X1174050Y735042D01*
X1173925Y735375D01*
X1173883Y735750D01*
X1173925Y736125D01*
X1174050Y736458D01*
X1174217Y736708D01*
X1174467Y736917D01*
X1174800Y737000D01*
G01X1185700Y762500D02*
Y760000D01*
G01X1186658Y762500D02*
X1184742D01*
G01X1183433Y760000D02*
Y762500D01*
X1182433D01*
X1182100Y762375D01*
X1181850Y762083D01*
X1181767Y761750D01*
X1181850Y761417D01*
X1182058Y761167D01*
X1182433Y761042D01*
X1183433D01*
G01X1179500Y760000D02*
Y762500D01*
X1180000Y762000D01*
G01Y760000D02*
X1179000D01*
G01X1175900D02*
Y762500D01*
X1177442Y760708D01*
X1175358D01*
G01X1174217Y760375D02*
X1173967Y760167D01*
X1173675Y760042D01*
X1173300Y760000D01*
X1172925Y760083D01*
X1172633Y760250D01*
X1172425Y760542D01*
X1172383Y760875D01*
X1172467Y761208D01*
X1172675Y761417D01*
X1172967Y761583D01*
X1173258Y761625D01*
X1173550Y761583D01*
X1173925Y761417D01*
X1173800Y762500D01*
X1172675D01*
G01X1171592Y810767D02*
X1171717Y810517D01*
X1171800Y810225D01*
Y809892D01*
X1171675Y809517D01*
X1171467Y809225D01*
X1171217Y809017D01*
X1170800Y808850D01*
X1170425Y808808D01*
X1170050Y808892D01*
X1169800Y809017D01*
X1169550Y809267D01*
X1169383Y809558D01*
X1169300Y809850D01*
Y810142D01*
X1169383Y810433D01*
X1169508Y810683D01*
X1169675Y810892D01*
G01X1169300Y812950D02*
X1171800D01*
X1171300Y812450D01*
G01X1169300D02*
Y813450D01*
G01Y816050D02*
X1169342Y816342D01*
X1169467Y816675D01*
X1169675Y816883D01*
X1169967Y816967D01*
X1170258Y816883D01*
X1170508Y816633D01*
X1170633Y816258D01*
Y815842D01*
X1170717Y815592D01*
X1170925Y815383D01*
X1171217Y815300D01*
X1171508Y815425D01*
X1171717Y815717D01*
X1171800Y816050D01*
X1171717Y816383D01*
X1171508Y816675D01*
X1171217Y816800D01*
X1170925Y816717D01*
X1170717Y816508D01*
X1170633Y816258D01*
Y815842D01*
X1170508Y815467D01*
X1170258Y815217D01*
X1169967Y815133D01*
X1169675Y815217D01*
X1169467Y815425D01*
X1169342Y815758D01*
X1169300Y816050D01*
G01X1171383Y818358D02*
X1171633Y818608D01*
X1171758Y818900D01*
X1171800Y819233D01*
X1171717Y819650D01*
X1171508Y819942D01*
X1171258Y820025D01*
X1171008Y819983D01*
X1170800Y819817D01*
X1170383Y818983D01*
X1170092Y818608D01*
X1169675Y818358D01*
X1169300Y818275D01*
Y820025D01*
G01X1198000Y625017D02*
X1200500D01*
Y626058D01*
X1200375Y626392D01*
X1200208Y626600D01*
X1199875Y626683D01*
X1199542Y626600D01*
X1199333Y626350D01*
X1199208Y626058D01*
Y625017D01*
G01Y626058D02*
X1198000Y626683D01*
G01Y629450D02*
X1200500D01*
X1198708Y627908D01*
Y629992D01*
G01X1199042Y631258D02*
X1199333Y631550D01*
X1199500Y631800D01*
X1199583Y632133D01*
X1199500Y632425D01*
X1199333Y632633D01*
X1199083Y632800D01*
X1198792Y632842D01*
X1198542Y632800D01*
X1198292Y632633D01*
X1198083Y632383D01*
X1198000Y632092D01*
X1198083Y631758D01*
X1198333Y631467D01*
X1198708Y631300D01*
X1199125Y631258D01*
X1199667Y631342D01*
X1199958Y631467D01*
X1200250Y631675D01*
X1200458Y631967D01*
X1200500Y632258D01*
X1200417Y632550D01*
X1200208Y632758D01*
G01X1200083Y634358D02*
X1200333Y634608D01*
X1200458Y634900D01*
X1200500Y635233D01*
X1200417Y635650D01*
X1200208Y635942D01*
X1199958Y636025D01*
X1199708Y635983D01*
X1199500Y635817D01*
X1199083Y634983D01*
X1198792Y634608D01*
X1198375Y634358D01*
X1198000Y634275D01*
Y636025D01*
G01X1194000Y625017D02*
X1196500D01*
Y626058D01*
X1196375Y626392D01*
X1196208Y626600D01*
X1195875Y626683D01*
X1195542Y626600D01*
X1195333Y626350D01*
X1195208Y626058D01*
Y625017D01*
G01Y626058D02*
X1194000Y626683D01*
G01Y629450D02*
X1196500D01*
X1194708Y627908D01*
Y629992D01*
G01X1195042Y631258D02*
X1195333Y631550D01*
X1195500Y631800D01*
X1195583Y632133D01*
X1195500Y632425D01*
X1195333Y632633D01*
X1195083Y632800D01*
X1194792Y632842D01*
X1194542Y632800D01*
X1194292Y632633D01*
X1194083Y632383D01*
X1194000Y632092D01*
X1194083Y631758D01*
X1194333Y631467D01*
X1194708Y631300D01*
X1195125Y631258D01*
X1195667Y631342D01*
X1195958Y631467D01*
X1196250Y631675D01*
X1196458Y631967D01*
X1196500Y632258D01*
X1196417Y632550D01*
X1196208Y632758D01*
G01X1194375Y634233D02*
X1194167Y634483D01*
X1194042Y634775D01*
X1194000Y635150D01*
X1194083Y635525D01*
X1194250Y635817D01*
X1194542Y636025D01*
X1194875Y636067D01*
X1195208Y635983D01*
X1195417Y635775D01*
X1195583Y635483D01*
X1195625Y635192D01*
X1195583Y634900D01*
X1195417Y634525D01*
X1196500Y634650D01*
Y635775D01*
G01X1197700Y662000D02*
Y659500D01*
G01X1198658Y662000D02*
X1196742D01*
G01X1195433Y659500D02*
Y662000D01*
X1194433D01*
X1194100Y661875D01*
X1193850Y661583D01*
X1193767Y661250D01*
X1193850Y660917D01*
X1194058Y660667D01*
X1194433Y660542D01*
X1195433D01*
G01X1191500Y659500D02*
Y662000D01*
X1192000Y661500D01*
G01Y659500D02*
X1191000D01*
G01X1189317Y659875D02*
X1189067Y659667D01*
X1188775Y659542D01*
X1188400Y659500D01*
X1188025Y659583D01*
X1187733Y659750D01*
X1187525Y660042D01*
X1187483Y660375D01*
X1187567Y660708D01*
X1187775Y660917D01*
X1188067Y661083D01*
X1188358Y661125D01*
X1188650Y661083D01*
X1189025Y660917D01*
X1188900Y662000D01*
X1187775D01*
G01X1186217Y659875D02*
X1185967Y659667D01*
X1185675Y659542D01*
X1185300Y659500D01*
X1184925Y659583D01*
X1184633Y659750D01*
X1184425Y660042D01*
X1184383Y660375D01*
X1184467Y660708D01*
X1184675Y660917D01*
X1184967Y661083D01*
X1185258Y661125D01*
X1185550Y661083D01*
X1185925Y660917D01*
X1185800Y662000D01*
X1184675D01*
G01X1210200Y667500D02*
Y665000D01*
G01X1211158Y667500D02*
X1209242D01*
G01X1207933Y665000D02*
Y667500D01*
X1206933D01*
X1206600Y667375D01*
X1206350Y667083D01*
X1206267Y666750D01*
X1206350Y666417D01*
X1206558Y666167D01*
X1206933Y666042D01*
X1207933D01*
G01X1204000Y665000D02*
Y667500D01*
X1204500Y667000D01*
G01Y665000D02*
X1203500D01*
G01X1201817Y665375D02*
X1201567Y665167D01*
X1201275Y665042D01*
X1200900Y665000D01*
X1200525Y665083D01*
X1200233Y665250D01*
X1200025Y665542D01*
X1199983Y665875D01*
X1200067Y666208D01*
X1200275Y666417D01*
X1200567Y666583D01*
X1200858Y666625D01*
X1201150Y666583D01*
X1201525Y666417D01*
X1201400Y667500D01*
X1200275D01*
G01X1198717Y665500D02*
X1198467Y665208D01*
X1198133Y665042D01*
X1197758Y665000D01*
X1197425Y665042D01*
X1197092Y665250D01*
X1196883Y665500D01*
X1196842Y665750D01*
X1196925Y666042D01*
X1197217Y666250D01*
X1197508Y666333D01*
X1197883D01*
G01X1197508D02*
X1197258Y666458D01*
X1197050Y666667D01*
X1196967Y666917D01*
X1197050Y667167D01*
X1197258Y667375D01*
X1197633Y667500D01*
X1198008Y667458D01*
X1198383Y667292D01*
G01X1198983Y672000D02*
Y674500D01*
X1197942D01*
X1197608Y674375D01*
X1197400Y674208D01*
X1197317Y673875D01*
X1197400Y673542D01*
X1197650Y673333D01*
X1197942Y673208D01*
X1198983D01*
G01X1197942D02*
X1197317Y672000D01*
G01X1195967Y672500D02*
X1195717Y672208D01*
X1195383Y672042D01*
X1195008Y672000D01*
X1194675Y672042D01*
X1194342Y672250D01*
X1194133Y672500D01*
X1194092Y672750D01*
X1194175Y673042D01*
X1194467Y673250D01*
X1194758Y673333D01*
X1195133D01*
G01X1194758D02*
X1194508Y673458D01*
X1194300Y673667D01*
X1194217Y673917D01*
X1194300Y674167D01*
X1194508Y674375D01*
X1194883Y674500D01*
X1195258Y674458D01*
X1195633Y674292D01*
G01X1192867Y672500D02*
X1192617Y672208D01*
X1192283Y672042D01*
X1191908Y672000D01*
X1191575Y672042D01*
X1191242Y672250D01*
X1191033Y672500D01*
X1190992Y672750D01*
X1191075Y673042D01*
X1191367Y673250D01*
X1191658Y673333D01*
X1192033D01*
G01X1191658D02*
X1191408Y673458D01*
X1191200Y673667D01*
X1191117Y673917D01*
X1191200Y674167D01*
X1191408Y674375D01*
X1191783Y674500D01*
X1192158Y674458D01*
X1192533Y674292D01*
G01X1189767Y672375D02*
X1189517Y672167D01*
X1189225Y672042D01*
X1188850Y672000D01*
X1188475Y672083D01*
X1188183Y672250D01*
X1187975Y672542D01*
X1187933Y672875D01*
X1188017Y673208D01*
X1188225Y673417D01*
X1188517Y673583D01*
X1188808Y673625D01*
X1189100Y673583D01*
X1189475Y673417D01*
X1189350Y674500D01*
X1188225D01*
G01X1204733Y694292D02*
X1204983Y694417D01*
X1205275Y694500D01*
X1205608D01*
X1205983Y694375D01*
X1206275Y694167D01*
X1206483Y693917D01*
X1206650Y693500D01*
X1206692Y693125D01*
X1206608Y692750D01*
X1206483Y692500D01*
X1206233Y692250D01*
X1205942Y692083D01*
X1205650Y692000D01*
X1205358D01*
X1205067Y692083D01*
X1204817Y692208D01*
X1204608Y692375D01*
G01X1203342Y694083D02*
X1203092Y694333D01*
X1202800Y694458D01*
X1202467Y694500D01*
X1202050Y694417D01*
X1201758Y694208D01*
X1201675Y693958D01*
X1201717Y693708D01*
X1201883Y693500D01*
X1202717Y693083D01*
X1203092Y692792D01*
X1203342Y692375D01*
X1203425Y692000D01*
X1201675D01*
G01X1199450D02*
Y694500D01*
X1199950Y694000D01*
G01Y692000D02*
X1198950D01*
G01X1197058Y692292D02*
X1196767Y692083D01*
X1196433Y692000D01*
X1196100Y692083D01*
X1195808Y692333D01*
X1195600Y692708D01*
X1195517Y693083D01*
Y693542D01*
X1195600Y693917D01*
X1195808Y694250D01*
X1196058Y694417D01*
X1196350Y694500D01*
X1196683Y694417D01*
X1196933Y694250D01*
X1197100Y694000D01*
X1197183Y693667D01*
X1197100Y693375D01*
X1196892Y693083D01*
X1196642Y692917D01*
X1196350Y692875D01*
X1196017Y692958D01*
X1195767Y693167D01*
X1195517Y693542D01*
G01X1201162Y715017D02*
X1201287Y714767D01*
X1201370Y714475D01*
Y714142D01*
X1201245Y713767D01*
X1201037Y713475D01*
X1200787Y713267D01*
X1200370Y713100D01*
X1199995Y713058D01*
X1199620Y713142D01*
X1199370Y713267D01*
X1199120Y713517D01*
X1198953Y713808D01*
X1198870Y714100D01*
Y714392D01*
X1198953Y714683D01*
X1199078Y714933D01*
X1199245Y715142D01*
G01X1198870Y717200D02*
X1201370D01*
X1200870Y716700D01*
G01X1198870D02*
Y717700D01*
G01X1199162Y719592D02*
X1198953Y719883D01*
X1198870Y720217D01*
X1198953Y720550D01*
X1199203Y720842D01*
X1199578Y721050D01*
X1199953Y721133D01*
X1200412D01*
X1200787Y721050D01*
X1201120Y720842D01*
X1201287Y720592D01*
X1201370Y720300D01*
X1201287Y719967D01*
X1201120Y719717D01*
X1200870Y719550D01*
X1200537Y719467D01*
X1200245Y719550D01*
X1199953Y719758D01*
X1199787Y720008D01*
X1199745Y720300D01*
X1199828Y720633D01*
X1200037Y720883D01*
X1200412Y721133D01*
G01X1199370Y722483D02*
X1199078Y722733D01*
X1198912Y723067D01*
X1198870Y723442D01*
X1198912Y723775D01*
X1199120Y724108D01*
X1199370Y724317D01*
X1199620Y724358D01*
X1199912Y724275D01*
X1200120Y723983D01*
X1200203Y723692D01*
Y723317D01*
G01Y723692D02*
X1200328Y723942D01*
X1200537Y724150D01*
X1200787Y724233D01*
X1201037Y724150D01*
X1201245Y723942D01*
X1201370Y723567D01*
X1201328Y723192D01*
X1201162Y722817D01*
G01X1201200Y733000D02*
Y730500D01*
G01X1202158Y733000D02*
X1200242D01*
G01X1198933Y730500D02*
Y733000D01*
X1197933D01*
X1197600Y732875D01*
X1197350Y732583D01*
X1197267Y732250D01*
X1197350Y731917D01*
X1197558Y731667D01*
X1197933Y731542D01*
X1198933D01*
G01X1195000Y730500D02*
Y733000D01*
X1195500Y732500D01*
G01Y730500D02*
X1194500D01*
G01X1192692Y731542D02*
X1192400Y731833D01*
X1192150Y732000D01*
X1191817Y732083D01*
X1191525Y732000D01*
X1191317Y731833D01*
X1191150Y731583D01*
X1191108Y731292D01*
X1191150Y731042D01*
X1191317Y730792D01*
X1191567Y730583D01*
X1191858Y730500D01*
X1192192Y730583D01*
X1192483Y730833D01*
X1192650Y731208D01*
X1192692Y731625D01*
X1192608Y732167D01*
X1192483Y732458D01*
X1192275Y732750D01*
X1191983Y732958D01*
X1191692Y733000D01*
X1191400Y732917D01*
X1191192Y732708D01*
G01X1188800Y730500D02*
Y733000D01*
X1189300Y732500D01*
G01Y730500D02*
X1188300D01*
G01X1191000Y744300D02*
X1188500D01*
G01X1191000Y743342D02*
Y745258D01*
G01X1188500Y746567D02*
X1191000D01*
Y747567D01*
X1190875Y747900D01*
X1190583Y748150D01*
X1190250Y748233D01*
X1189917Y748150D01*
X1189667Y747942D01*
X1189542Y747567D01*
Y746567D01*
G01X1188500Y750500D02*
X1191000D01*
X1190500Y750000D01*
G01X1188500D02*
Y751000D01*
G01X1191000Y753600D02*
X1190917Y753267D01*
X1190708Y753017D01*
X1190458Y752850D01*
X1190125Y752725D01*
X1189750Y752683D01*
X1189375Y752725D01*
X1189042Y752850D01*
X1188792Y753017D01*
X1188583Y753267D01*
X1188500Y753600D01*
X1188583Y753933D01*
X1188792Y754183D01*
X1189042Y754350D01*
X1189375Y754475D01*
X1189750Y754517D01*
X1190125Y754475D01*
X1190458Y754350D01*
X1190708Y754183D01*
X1190917Y753933D01*
X1191000Y753600D01*
G01X1188500Y756700D02*
X1191000D01*
X1190500Y756200D01*
G01X1188500D02*
Y757200D01*
G01X1195500Y744300D02*
X1193000D01*
G01X1195500Y743342D02*
Y745258D01*
G01X1193000Y746567D02*
X1195500D01*
Y747567D01*
X1195375Y747900D01*
X1195083Y748150D01*
X1194750Y748233D01*
X1194417Y748150D01*
X1194167Y747942D01*
X1194042Y747567D01*
Y746567D01*
G01X1193000Y750500D02*
X1195500D01*
X1195000Y750000D01*
G01X1193000D02*
Y751000D01*
G01X1195500Y753600D02*
X1195417Y753267D01*
X1195208Y753017D01*
X1194958Y752850D01*
X1194625Y752725D01*
X1194250Y752683D01*
X1193875Y752725D01*
X1193542Y752850D01*
X1193292Y753017D01*
X1193083Y753267D01*
X1193000Y753600D01*
X1193083Y753933D01*
X1193292Y754183D01*
X1193542Y754350D01*
X1193875Y754475D01*
X1194250Y754517D01*
X1194625Y754475D01*
X1194958Y754350D01*
X1195208Y754183D01*
X1195417Y753933D01*
X1195500Y753600D01*
G01X1193500Y755783D02*
X1193208Y756033D01*
X1193042Y756367D01*
X1193000Y756742D01*
X1193042Y757075D01*
X1193250Y757408D01*
X1193500Y757617D01*
X1193750Y757658D01*
X1194042Y757575D01*
X1194250Y757283D01*
X1194333Y756992D01*
Y756617D01*
G01Y756992D02*
X1194458Y757242D01*
X1194667Y757450D01*
X1194917Y757533D01*
X1195167Y757450D01*
X1195375Y757242D01*
X1195500Y756867D01*
X1195458Y756492D01*
X1195292Y756117D01*
G01X1187000Y744300D02*
X1184500D01*
G01X1187000Y743342D02*
Y745258D01*
G01X1184500Y746567D02*
X1187000D01*
Y747567D01*
X1186875Y747900D01*
X1186583Y748150D01*
X1186250Y748233D01*
X1185917Y748150D01*
X1185667Y747942D01*
X1185542Y747567D01*
Y746567D01*
G01X1184500Y750500D02*
X1187000D01*
X1186500Y750000D01*
G01X1184500D02*
Y751000D01*
G01Y753600D02*
X1187000D01*
X1186500Y753100D01*
G01X1184500D02*
Y754100D01*
G01X1186583Y755908D02*
X1186833Y756158D01*
X1186958Y756450D01*
X1187000Y756783D01*
X1186917Y757200D01*
X1186708Y757492D01*
X1186458Y757575D01*
X1186208Y757533D01*
X1186000Y757367D01*
X1185583Y756533D01*
X1185292Y756158D01*
X1184875Y755908D01*
X1184500Y755825D01*
Y757575D01*
G01X1213792Y212767D02*
X1213917Y212517D01*
X1214000Y212225D01*
Y211892D01*
X1213875Y211517D01*
X1213667Y211225D01*
X1213417Y211017D01*
X1213000Y210850D01*
X1212625Y210808D01*
X1212250Y210892D01*
X1212000Y211017D01*
X1211750Y211267D01*
X1211583Y211558D01*
X1211500Y211850D01*
Y212142D01*
X1211583Y212433D01*
X1211708Y212683D01*
X1211875Y212892D01*
G01X1213583Y214158D02*
X1213833Y214408D01*
X1213958Y214700D01*
X1214000Y215033D01*
X1213917Y215450D01*
X1213708Y215742D01*
X1213458Y215825D01*
X1213208Y215783D01*
X1213000Y215617D01*
X1212583Y214783D01*
X1212292Y214408D01*
X1211875Y214158D01*
X1211500Y214075D01*
Y215825D01*
G01Y217967D02*
X1212042Y218050D01*
X1212500Y218175D01*
X1212917Y218342D01*
X1213375Y218550D01*
X1214000Y218883D01*
Y217217D01*
G01X1211500Y221150D02*
X1211542Y221442D01*
X1211667Y221775D01*
X1211875Y221983D01*
X1212167Y222067D01*
X1212458Y221983D01*
X1212708Y221733D01*
X1212833Y221358D01*
Y220942D01*
X1212917Y220692D01*
X1213125Y220483D01*
X1213417Y220400D01*
X1213708Y220525D01*
X1213917Y220817D01*
X1214000Y221150D01*
X1213917Y221483D01*
X1213708Y221775D01*
X1213417Y221900D01*
X1213125Y221817D01*
X1212917Y221608D01*
X1212833Y221358D01*
Y220942D01*
X1212708Y220567D01*
X1212458Y220317D01*
X1212167Y220233D01*
X1211875Y220317D01*
X1211667Y220525D01*
X1211542Y220858D01*
X1211500Y221150D01*
G01X1218292Y212767D02*
X1218417Y212517D01*
X1218500Y212225D01*
Y211892D01*
X1218375Y211517D01*
X1218167Y211225D01*
X1217917Y211017D01*
X1217500Y210850D01*
X1217125Y210808D01*
X1216750Y210892D01*
X1216500Y211017D01*
X1216250Y211267D01*
X1216083Y211558D01*
X1216000Y211850D01*
Y212142D01*
X1216083Y212433D01*
X1216208Y212683D01*
X1216375Y212892D01*
G01X1218083Y214158D02*
X1218333Y214408D01*
X1218458Y214700D01*
X1218500Y215033D01*
X1218417Y215450D01*
X1218208Y215742D01*
X1217958Y215825D01*
X1217708Y215783D01*
X1217500Y215617D01*
X1217083Y214783D01*
X1216792Y214408D01*
X1216375Y214158D01*
X1216000Y214075D01*
Y215825D01*
G01Y217967D02*
X1216542Y218050D01*
X1217000Y218175D01*
X1217417Y218342D01*
X1217875Y218550D01*
X1218500Y218883D01*
Y217217D01*
G01X1216000Y221067D02*
X1216542Y221150D01*
X1217000Y221275D01*
X1217417Y221442D01*
X1217875Y221650D01*
X1218500Y221983D01*
Y220317D01*
G01X1215000Y628800D02*
X1211000D01*
Y636200D01*
G01Y628800D02*
X1207000D01*
Y636200D01*
G01X1202000Y625017D02*
X1204500D01*
Y626058D01*
X1204375Y626392D01*
X1204208Y626600D01*
X1203875Y626683D01*
X1203542Y626600D01*
X1203333Y626350D01*
X1203208Y626058D01*
Y625017D01*
G01Y626058D02*
X1202000Y626683D01*
G01X1204083Y628158D02*
X1204333Y628408D01*
X1204458Y628700D01*
X1204500Y629033D01*
X1204417Y629450D01*
X1204208Y629742D01*
X1203958Y629825D01*
X1203708Y629783D01*
X1203500Y629617D01*
X1203083Y628783D01*
X1202792Y628408D01*
X1202375Y628158D01*
X1202000Y628075D01*
Y629825D01*
G01X1203042Y631258D02*
X1203333Y631550D01*
X1203500Y631800D01*
X1203583Y632133D01*
X1203500Y632425D01*
X1203333Y632633D01*
X1203083Y632800D01*
X1202792Y632842D01*
X1202542Y632800D01*
X1202292Y632633D01*
X1202083Y632383D01*
X1202000Y632092D01*
X1202083Y631758D01*
X1202333Y631467D01*
X1202708Y631300D01*
X1203125Y631258D01*
X1203667Y631342D01*
X1203958Y631467D01*
X1204250Y631675D01*
X1204458Y631967D01*
X1204500Y632258D01*
X1204417Y632550D01*
X1204208Y632758D01*
G01X1202000Y635150D02*
X1204500D01*
X1204000Y634650D01*
G01X1202000D02*
Y635650D01*
G01X1219000Y628800D02*
X1215000D01*
Y636200D01*
G01X1214650Y671500D02*
Y669000D01*
G01X1215608Y671500D02*
X1213692D01*
G01X1212383Y669000D02*
Y671500D01*
X1211383D01*
X1211050Y671375D01*
X1210800Y671083D01*
X1210717Y670750D01*
X1210800Y670417D01*
X1211008Y670167D01*
X1211383Y670042D01*
X1212383D01*
G01X1209158Y669292D02*
X1208867Y669083D01*
X1208533Y669000D01*
X1208200Y669083D01*
X1207908Y669333D01*
X1207700Y669708D01*
X1207617Y670083D01*
Y670542D01*
X1207700Y670917D01*
X1207908Y671250D01*
X1208158Y671417D01*
X1208450Y671500D01*
X1208783Y671417D01*
X1209033Y671250D01*
X1209200Y671000D01*
X1209283Y670667D01*
X1209200Y670375D01*
X1208992Y670083D01*
X1208742Y669917D01*
X1208450Y669875D01*
X1208117Y669958D01*
X1207867Y670167D01*
X1207617Y670542D01*
G01X1206267Y669500D02*
X1206017Y669208D01*
X1205683Y669042D01*
X1205308Y669000D01*
X1204975Y669042D01*
X1204642Y669250D01*
X1204433Y669500D01*
X1204392Y669750D01*
X1204475Y670042D01*
X1204767Y670250D01*
X1205058Y670333D01*
X1205433D01*
G01X1205058D02*
X1204808Y670458D01*
X1204600Y670667D01*
X1204517Y670917D01*
X1204600Y671167D01*
X1204808Y671375D01*
X1205183Y671500D01*
X1205558Y671458D01*
X1205933Y671292D01*
G01X1223150Y676500D02*
Y674000D01*
G01X1224108Y676500D02*
X1222192D01*
G01X1220883Y674000D02*
Y676500D01*
X1219883D01*
X1219550Y676375D01*
X1219300Y676083D01*
X1219217Y675750D01*
X1219300Y675417D01*
X1219508Y675167D01*
X1219883Y675042D01*
X1220883D01*
G01X1217658Y674292D02*
X1217367Y674083D01*
X1217033Y674000D01*
X1216700Y674083D01*
X1216408Y674333D01*
X1216200Y674708D01*
X1216117Y675083D01*
Y675542D01*
X1216200Y675917D01*
X1216408Y676250D01*
X1216658Y676417D01*
X1216950Y676500D01*
X1217283Y676417D01*
X1217533Y676250D01*
X1217700Y676000D01*
X1217783Y675667D01*
X1217700Y675375D01*
X1217492Y675083D01*
X1217242Y674917D01*
X1216950Y674875D01*
X1216617Y674958D01*
X1216367Y675167D01*
X1216117Y675542D01*
G01X1213933Y674000D02*
X1213850Y674542D01*
X1213725Y675000D01*
X1213558Y675417D01*
X1213350Y675875D01*
X1213017Y676500D01*
X1214683D01*
G01X1216700Y699000D02*
Y696500D01*
G01X1217658Y699000D02*
X1215742D01*
G01X1214433Y696500D02*
Y699000D01*
X1213433D01*
X1213100Y698875D01*
X1212850Y698583D01*
X1212767Y698250D01*
X1212850Y697917D01*
X1213058Y697667D01*
X1213433Y697542D01*
X1214433D01*
G01X1210500Y696500D02*
Y699000D01*
X1211000Y698500D01*
G01Y696500D02*
X1210000D01*
G01X1208192Y697542D02*
X1207900Y697833D01*
X1207650Y698000D01*
X1207317Y698083D01*
X1207025Y698000D01*
X1206817Y697833D01*
X1206650Y697583D01*
X1206608Y697292D01*
X1206650Y697042D01*
X1206817Y696792D01*
X1207067Y696583D01*
X1207358Y696500D01*
X1207692Y696583D01*
X1207983Y696833D01*
X1208150Y697208D01*
X1208192Y697625D01*
X1208108Y698167D01*
X1207983Y698458D01*
X1207775Y698750D01*
X1207483Y698958D01*
X1207192Y699000D01*
X1206900Y698917D01*
X1206692Y698708D01*
G01X1205092Y698583D02*
X1204842Y698833D01*
X1204550Y698958D01*
X1204217Y699000D01*
X1203800Y698917D01*
X1203508Y698708D01*
X1203425Y698458D01*
X1203467Y698208D01*
X1203633Y698000D01*
X1204467Y697583D01*
X1204842Y697292D01*
X1205092Y696875D01*
X1205175Y696500D01*
X1203425D01*
G01X1214500Y715700D02*
X1207500D01*
Y702300D01*
X1214500D01*
Y715700D01*
G01X1205182Y714967D02*
X1205307Y714717D01*
X1205390Y714425D01*
Y714092D01*
X1205265Y713717D01*
X1205057Y713425D01*
X1204807Y713217D01*
X1204390Y713050D01*
X1204015Y713008D01*
X1203640Y713092D01*
X1203390Y713217D01*
X1203140Y713467D01*
X1202973Y713758D01*
X1202890Y714050D01*
Y714342D01*
X1202973Y714633D01*
X1203098Y714883D01*
X1203265Y715092D01*
G01X1202890Y717150D02*
X1205390D01*
X1204890Y716650D01*
G01X1202890D02*
Y717650D01*
G01X1203182Y719542D02*
X1202973Y719833D01*
X1202890Y720167D01*
X1202973Y720500D01*
X1203223Y720792D01*
X1203598Y721000D01*
X1203973Y721083D01*
X1204432D01*
X1204807Y721000D01*
X1205140Y720792D01*
X1205307Y720542D01*
X1205390Y720250D01*
X1205307Y719917D01*
X1205140Y719667D01*
X1204890Y719500D01*
X1204557Y719417D01*
X1204265Y719500D01*
X1203973Y719708D01*
X1203807Y719958D01*
X1203765Y720250D01*
X1203848Y720583D01*
X1204057Y720833D01*
X1204432Y721083D01*
G01X1204973Y722558D02*
X1205223Y722808D01*
X1205348Y723100D01*
X1205390Y723433D01*
X1205307Y723850D01*
X1205098Y724142D01*
X1204848Y724225D01*
X1204598Y724183D01*
X1204390Y724017D01*
X1203973Y723183D01*
X1203682Y722808D01*
X1203265Y722558D01*
X1202890Y722475D01*
Y724225D01*
G01X1214000Y718117D02*
X1211500D01*
Y719783D01*
G01Y722550D02*
X1214000D01*
X1212208Y721008D01*
Y723092D01*
G01X1228469Y214267D02*
X1228594Y214017D01*
X1228677Y213725D01*
Y213392D01*
X1228552Y213017D01*
X1228344Y212725D01*
X1228094Y212517D01*
X1227677Y212350D01*
X1227302Y212308D01*
X1226927Y212392D01*
X1226677Y212517D01*
X1226427Y212767D01*
X1226260Y213058D01*
X1226177Y213350D01*
Y213642D01*
X1226260Y213933D01*
X1226385Y214183D01*
X1226552Y214392D01*
G01X1228260Y215658D02*
X1228510Y215908D01*
X1228635Y216200D01*
X1228677Y216533D01*
X1228594Y216950D01*
X1228385Y217242D01*
X1228135Y217325D01*
X1227885Y217283D01*
X1227677Y217117D01*
X1227260Y216283D01*
X1226969Y215908D01*
X1226552Y215658D01*
X1226177Y215575D01*
Y217325D01*
G01Y219467D02*
X1226719Y219550D01*
X1227177Y219675D01*
X1227594Y219842D01*
X1228052Y220050D01*
X1228677Y220383D01*
Y218717D01*
G01X1227219Y221858D02*
X1227510Y222150D01*
X1227677Y222400D01*
X1227760Y222733D01*
X1227677Y223025D01*
X1227510Y223233D01*
X1227260Y223400D01*
X1226969Y223442D01*
X1226719Y223400D01*
X1226469Y223233D01*
X1226260Y222983D01*
X1226177Y222692D01*
X1226260Y222358D01*
X1226510Y222067D01*
X1226885Y221900D01*
X1227302Y221858D01*
X1227844Y221942D01*
X1228135Y222067D01*
X1228427Y222275D01*
X1228635Y222567D01*
X1228677Y222858D01*
X1228594Y223150D01*
X1228385Y223358D01*
G01X1222792Y212767D02*
X1222917Y212517D01*
X1223000Y212225D01*
Y211892D01*
X1222875Y211517D01*
X1222667Y211225D01*
X1222417Y211017D01*
X1222000Y210850D01*
X1221625Y210808D01*
X1221250Y210892D01*
X1221000Y211017D01*
X1220750Y211267D01*
X1220583Y211558D01*
X1220500Y211850D01*
Y212142D01*
X1220583Y212433D01*
X1220708Y212683D01*
X1220875Y212892D01*
G01X1222583Y214158D02*
X1222833Y214408D01*
X1222958Y214700D01*
X1223000Y215033D01*
X1222917Y215450D01*
X1222708Y215742D01*
X1222458Y215825D01*
X1222208Y215783D01*
X1222000Y215617D01*
X1221583Y214783D01*
X1221292Y214408D01*
X1220875Y214158D01*
X1220500Y214075D01*
Y215825D01*
G01Y217967D02*
X1221042Y218050D01*
X1221500Y218175D01*
X1221917Y218342D01*
X1222375Y218550D01*
X1223000Y218883D01*
Y217217D01*
G01X1220792Y220442D02*
X1220583Y220733D01*
X1220500Y221067D01*
X1220583Y221400D01*
X1220833Y221692D01*
X1221208Y221900D01*
X1221583Y221983D01*
X1222042D01*
X1222417Y221900D01*
X1222750Y221692D01*
X1222917Y221442D01*
X1223000Y221150D01*
X1222917Y220817D01*
X1222750Y220567D01*
X1222500Y220400D01*
X1222167Y220317D01*
X1221875Y220400D01*
X1221583Y220608D01*
X1221417Y220858D01*
X1221375Y221150D01*
X1221458Y221483D01*
X1221667Y221733D01*
X1222042Y221983D01*
G01X1231483Y657000D02*
Y659500D01*
X1230442D01*
X1230108Y659375D01*
X1229900Y659208D01*
X1229817Y658875D01*
X1229900Y658542D01*
X1230150Y658333D01*
X1230442Y658208D01*
X1231483D01*
G01X1230442D02*
X1229817Y657000D01*
G01X1228342Y659083D02*
X1228092Y659333D01*
X1227800Y659458D01*
X1227467Y659500D01*
X1227050Y659417D01*
X1226758Y659208D01*
X1226675Y658958D01*
X1226717Y658708D01*
X1226883Y658500D01*
X1227717Y658083D01*
X1228092Y657792D01*
X1228342Y657375D01*
X1228425Y657000D01*
X1226675D01*
G01X1223950D02*
Y659500D01*
X1225492Y657708D01*
X1223408D01*
G01X1222142Y659083D02*
X1221892Y659333D01*
X1221600Y659458D01*
X1221267Y659500D01*
X1220850Y659417D01*
X1220558Y659208D01*
X1220475Y658958D01*
X1220517Y658708D01*
X1220683Y658500D01*
X1221517Y658083D01*
X1221892Y657792D01*
X1222142Y657375D01*
X1222225Y657000D01*
X1220475D01*
G01X1231483Y661000D02*
Y663500D01*
X1230442D01*
X1230108Y663375D01*
X1229900Y663208D01*
X1229817Y662875D01*
X1229900Y662542D01*
X1230150Y662333D01*
X1230442Y662208D01*
X1231483D01*
G01X1230442D02*
X1229817Y661000D01*
G01X1228342Y663083D02*
X1228092Y663333D01*
X1227800Y663458D01*
X1227467Y663500D01*
X1227050Y663417D01*
X1226758Y663208D01*
X1226675Y662958D01*
X1226717Y662708D01*
X1226883Y662500D01*
X1227717Y662083D01*
X1228092Y661792D01*
X1228342Y661375D01*
X1228425Y661000D01*
X1226675D01*
G01X1223950D02*
Y663500D01*
X1225492Y661708D01*
X1223408D01*
G01X1222142Y662042D02*
X1221850Y662333D01*
X1221600Y662500D01*
X1221267Y662583D01*
X1220975Y662500D01*
X1220767Y662333D01*
X1220600Y662083D01*
X1220558Y661792D01*
X1220600Y661542D01*
X1220767Y661292D01*
X1221017Y661083D01*
X1221308Y661000D01*
X1221642Y661083D01*
X1221933Y661333D01*
X1222100Y661708D01*
X1222142Y662125D01*
X1222058Y662667D01*
X1221933Y662958D01*
X1221725Y663250D01*
X1221433Y663458D01*
X1221142Y663500D01*
X1220850Y663417D01*
X1220642Y663208D01*
G01X1220300Y729000D02*
Y733000D01*
X1227700D01*
G01X1220300Y725000D02*
Y729000D01*
X1227700D01*
G01X1220300Y716500D02*
Y720500D01*
X1227700D01*
G01Y724500D02*
Y720500D01*
X1220300D01*
G01Y733500D02*
Y737500D01*
X1227700D01*
G01X1239075Y740333D02*
X1238742Y740125D01*
X1238367Y740000D01*
X1238033D01*
X1237700Y740125D01*
X1237450Y740333D01*
X1237325Y740625D01*
X1237408Y740917D01*
X1237617Y741167D01*
X1237992Y741333D01*
X1238492Y741417D01*
X1238783Y741583D01*
X1238908Y741875D01*
X1238825Y742167D01*
X1238617Y742375D01*
X1238325Y742500D01*
X1238033D01*
X1237742Y742417D01*
X1237492Y742208D01*
G01X1235933Y740000D02*
Y742500D01*
X1234892D01*
X1234558Y742375D01*
X1234350Y742208D01*
X1234267Y741875D01*
X1234350Y741542D01*
X1234600Y741333D01*
X1234892Y741208D01*
X1235933D01*
G01X1234892D02*
X1234267Y740000D01*
G01X1232000D02*
X1231708Y740042D01*
X1231375Y740167D01*
X1231167Y740375D01*
X1231083Y740667D01*
X1231167Y740958D01*
X1231417Y741208D01*
X1231792Y741333D01*
X1232208D01*
X1232458Y741417D01*
X1232667Y741625D01*
X1232750Y741917D01*
X1232625Y742208D01*
X1232333Y742417D01*
X1232000Y742500D01*
X1231667Y742417D01*
X1231375Y742208D01*
X1231250Y741917D01*
X1231333Y741625D01*
X1231542Y741417D01*
X1231792Y741333D01*
X1232208D01*
X1232583Y741208D01*
X1232833Y740958D01*
X1232917Y740667D01*
X1232833Y740375D01*
X1232625Y740167D01*
X1232292Y740042D01*
X1232000Y740000D01*
G01X1229817Y740375D02*
X1229567Y740167D01*
X1229275Y740042D01*
X1228900Y740000D01*
X1228525Y740083D01*
X1228233Y740250D01*
X1228025Y740542D01*
X1227983Y740875D01*
X1228067Y741208D01*
X1228275Y741417D01*
X1228567Y741583D01*
X1228858Y741625D01*
X1229150Y741583D01*
X1229525Y741417D01*
X1229400Y742500D01*
X1228275D01*
G01X1226592Y742083D02*
X1226342Y742333D01*
X1226050Y742458D01*
X1225717Y742500D01*
X1225300Y742417D01*
X1225008Y742208D01*
X1224925Y741958D01*
X1224967Y741708D01*
X1225133Y741500D01*
X1225967Y741083D01*
X1226342Y740792D01*
X1226592Y740375D01*
X1226675Y740000D01*
X1224925D01*
G01X1239075Y744333D02*
X1238742Y744125D01*
X1238367Y744000D01*
X1238033D01*
X1237700Y744125D01*
X1237450Y744333D01*
X1237325Y744625D01*
X1237408Y744917D01*
X1237617Y745167D01*
X1237992Y745333D01*
X1238492Y745417D01*
X1238783Y745583D01*
X1238908Y745875D01*
X1238825Y746167D01*
X1238617Y746375D01*
X1238325Y746500D01*
X1238033D01*
X1237742Y746417D01*
X1237492Y746208D01*
G01X1235933Y744000D02*
Y746500D01*
X1234892D01*
X1234558Y746375D01*
X1234350Y746208D01*
X1234267Y745875D01*
X1234350Y745542D01*
X1234600Y745333D01*
X1234892Y745208D01*
X1235933D01*
G01X1234892D02*
X1234267Y744000D01*
G01X1232708Y744292D02*
X1232417Y744083D01*
X1232083Y744000D01*
X1231750Y744083D01*
X1231458Y744333D01*
X1231250Y744708D01*
X1231167Y745083D01*
Y745542D01*
X1231250Y745917D01*
X1231458Y746250D01*
X1231708Y746417D01*
X1232000Y746500D01*
X1232333Y746417D01*
X1232583Y746250D01*
X1232750Y746000D01*
X1232833Y745667D01*
X1232750Y745375D01*
X1232542Y745083D01*
X1232292Y744917D01*
X1232000Y744875D01*
X1231667Y744958D01*
X1231417Y745167D01*
X1231167Y745542D01*
G01X1228400Y744000D02*
Y746500D01*
X1229942Y744708D01*
X1227858D01*
G01X1225300Y744000D02*
Y746500D01*
X1226842Y744708D01*
X1224758D01*
G01X1237483Y757000D02*
Y759500D01*
X1236442D01*
X1236108Y759375D01*
X1235900Y759208D01*
X1235817Y758875D01*
X1235900Y758542D01*
X1236150Y758333D01*
X1236442Y758208D01*
X1237483D01*
G01X1236442D02*
X1235817Y757000D01*
G01X1234467Y757500D02*
X1234217Y757208D01*
X1233883Y757042D01*
X1233508Y757000D01*
X1233175Y757042D01*
X1232842Y757250D01*
X1232633Y757500D01*
X1232592Y757750D01*
X1232675Y758042D01*
X1232967Y758250D01*
X1233258Y758333D01*
X1233633D01*
G01X1233258D02*
X1233008Y758458D01*
X1232800Y758667D01*
X1232717Y758917D01*
X1232800Y759167D01*
X1233008Y759375D01*
X1233383Y759500D01*
X1233758Y759458D01*
X1234133Y759292D01*
G01X1230450Y759500D02*
X1230783Y759417D01*
X1231033Y759208D01*
X1231200Y758958D01*
X1231325Y758625D01*
X1231367Y758250D01*
X1231325Y757875D01*
X1231200Y757542D01*
X1231033Y757292D01*
X1230783Y757083D01*
X1230450Y757000D01*
X1230117Y757083D01*
X1229867Y757292D01*
X1229700Y757542D01*
X1229575Y757875D01*
X1229533Y758250D01*
X1229575Y758625D01*
X1229700Y758958D01*
X1229867Y759208D01*
X1230117Y759417D01*
X1230450Y759500D01*
G01X1228142Y759083D02*
X1227892Y759333D01*
X1227600Y759458D01*
X1227267Y759500D01*
X1226850Y759417D01*
X1226558Y759208D01*
X1226475Y758958D01*
X1226517Y758708D01*
X1226683Y758500D01*
X1227517Y758083D01*
X1227892Y757792D01*
X1228142Y757375D01*
X1228225Y757000D01*
X1226475D01*
G01X1237483Y752500D02*
Y755000D01*
X1236442D01*
X1236108Y754875D01*
X1235900Y754708D01*
X1235817Y754375D01*
X1235900Y754042D01*
X1236150Y753833D01*
X1236442Y753708D01*
X1237483D01*
G01X1236442D02*
X1235817Y752500D01*
G01X1234467Y753000D02*
X1234217Y752708D01*
X1233883Y752542D01*
X1233508Y752500D01*
X1233175Y752542D01*
X1232842Y752750D01*
X1232633Y753000D01*
X1232592Y753250D01*
X1232675Y753542D01*
X1232967Y753750D01*
X1233258Y753833D01*
X1233633D01*
G01X1233258D02*
X1233008Y753958D01*
X1232800Y754167D01*
X1232717Y754417D01*
X1232800Y754667D01*
X1233008Y754875D01*
X1233383Y755000D01*
X1233758Y754958D01*
X1234133Y754792D01*
G01X1230450Y755000D02*
X1230783Y754917D01*
X1231033Y754708D01*
X1231200Y754458D01*
X1231325Y754125D01*
X1231367Y753750D01*
X1231325Y753375D01*
X1231200Y753042D01*
X1231033Y752792D01*
X1230783Y752583D01*
X1230450Y752500D01*
X1230117Y752583D01*
X1229867Y752792D01*
X1229700Y753042D01*
X1229575Y753375D01*
X1229533Y753750D01*
X1229575Y754125D01*
X1229700Y754458D01*
X1229867Y754708D01*
X1230117Y754917D01*
X1230450Y755000D01*
G01X1228267Y753000D02*
X1228017Y752708D01*
X1227683Y752542D01*
X1227308Y752500D01*
X1226975Y752542D01*
X1226642Y752750D01*
X1226433Y753000D01*
X1226392Y753250D01*
X1226475Y753542D01*
X1226767Y753750D01*
X1227058Y753833D01*
X1227433D01*
G01X1227058D02*
X1226808Y753958D01*
X1226600Y754167D01*
X1226517Y754417D01*
X1226600Y754667D01*
X1226808Y754875D01*
X1227183Y755000D01*
X1227558Y754958D01*
X1227933Y754792D01*
G01X1237483Y748500D02*
Y751000D01*
X1236442D01*
X1236108Y750875D01*
X1235900Y750708D01*
X1235817Y750375D01*
X1235900Y750042D01*
X1236150Y749833D01*
X1236442Y749708D01*
X1237483D01*
G01X1236442D02*
X1235817Y748500D01*
G01X1234467Y749000D02*
X1234217Y748708D01*
X1233883Y748542D01*
X1233508Y748500D01*
X1233175Y748542D01*
X1232842Y748750D01*
X1232633Y749000D01*
X1232592Y749250D01*
X1232675Y749542D01*
X1232967Y749750D01*
X1233258Y749833D01*
X1233633D01*
G01X1233258D02*
X1233008Y749958D01*
X1232800Y750167D01*
X1232717Y750417D01*
X1232800Y750667D01*
X1233008Y750875D01*
X1233383Y751000D01*
X1233758Y750958D01*
X1234133Y750792D01*
G01X1230450Y748500D02*
Y751000D01*
X1230950Y750500D01*
G01Y748500D02*
X1229950D01*
G01X1228267Y749000D02*
X1228017Y748708D01*
X1227683Y748542D01*
X1227308Y748500D01*
X1226975Y748542D01*
X1226642Y748750D01*
X1226433Y749000D01*
X1226392Y749250D01*
X1226475Y749542D01*
X1226767Y749750D01*
X1227058Y749833D01*
X1227433D01*
G01X1227058D02*
X1226808Y749958D01*
X1226600Y750167D01*
X1226517Y750417D01*
X1226600Y750667D01*
X1226808Y750875D01*
X1227183Y751000D01*
X1227558Y750958D01*
X1227933Y750792D01*
G01X1245983Y648500D02*
Y651000D01*
X1244942D01*
X1244608Y650875D01*
X1244400Y650708D01*
X1244317Y650375D01*
X1244400Y650042D01*
X1244650Y649833D01*
X1244942Y649708D01*
X1245983D01*
G01X1244942D02*
X1244317Y648500D01*
G01X1242842Y650583D02*
X1242592Y650833D01*
X1242300Y650958D01*
X1241967Y651000D01*
X1241550Y650917D01*
X1241258Y650708D01*
X1241175Y650458D01*
X1241217Y650208D01*
X1241383Y650000D01*
X1242217Y649583D01*
X1242592Y649292D01*
X1242842Y648875D01*
X1242925Y648500D01*
X1241175D01*
G01X1238450D02*
Y651000D01*
X1239992Y649208D01*
X1237908D01*
G01X1236767Y649000D02*
X1236517Y648708D01*
X1236183Y648542D01*
X1235808Y648500D01*
X1235475Y648542D01*
X1235142Y648750D01*
X1234933Y649000D01*
X1234892Y649250D01*
X1234975Y649542D01*
X1235267Y649750D01*
X1235558Y649833D01*
X1235933D01*
G01X1235558D02*
X1235308Y649958D01*
X1235100Y650167D01*
X1235017Y650417D01*
X1235100Y650667D01*
X1235308Y650875D01*
X1235683Y651000D01*
X1236058Y650958D01*
X1236433Y650792D01*
G01X1255483Y634000D02*
Y636500D01*
X1254442D01*
X1254108Y636375D01*
X1253900Y636208D01*
X1253817Y635875D01*
X1253900Y635542D01*
X1254150Y635333D01*
X1254442Y635208D01*
X1255483D01*
G01X1254442D02*
X1253817Y634000D01*
G01X1252342Y636083D02*
X1252092Y636333D01*
X1251800Y636458D01*
X1251467Y636500D01*
X1251050Y636417D01*
X1250758Y636208D01*
X1250675Y635958D01*
X1250717Y635708D01*
X1250883Y635500D01*
X1251717Y635083D01*
X1252092Y634792D01*
X1252342Y634375D01*
X1252425Y634000D01*
X1250675D01*
G01X1247950D02*
Y636500D01*
X1249492Y634708D01*
X1247408D01*
G01X1244850Y634000D02*
Y636500D01*
X1246392Y634708D01*
X1244308D01*
G01X1255700Y643000D02*
Y639000D01*
X1248300D01*
G01X1245983Y644500D02*
Y647000D01*
X1244942D01*
X1244608Y646875D01*
X1244400Y646708D01*
X1244317Y646375D01*
X1244400Y646042D01*
X1244650Y645833D01*
X1244942Y645708D01*
X1245983D01*
G01X1244942D02*
X1244317Y644500D01*
G01X1242842Y646583D02*
X1242592Y646833D01*
X1242300Y646958D01*
X1241967Y647000D01*
X1241550Y646917D01*
X1241258Y646708D01*
X1241175Y646458D01*
X1241217Y646208D01*
X1241383Y646000D01*
X1242217Y645583D01*
X1242592Y645292D01*
X1242842Y644875D01*
X1242925Y644500D01*
X1241175D01*
G01X1238450D02*
Y647000D01*
X1239992Y645208D01*
X1237908D01*
G01X1236767Y644875D02*
X1236517Y644667D01*
X1236225Y644542D01*
X1235850Y644500D01*
X1235475Y644583D01*
X1235183Y644750D01*
X1234975Y645042D01*
X1234933Y645375D01*
X1235017Y645708D01*
X1235225Y645917D01*
X1235517Y646083D01*
X1235808Y646125D01*
X1236100Y646083D01*
X1236475Y645917D01*
X1236350Y647000D01*
X1235225D01*
G01X1255700Y649000D02*
Y645000D01*
X1248300D01*
G01X1255700Y659000D02*
Y655000D01*
X1248300D01*
G01X1255700Y653000D02*
Y649000D01*
X1248300D01*
G01X1255700Y663000D02*
Y659000D01*
X1248300D01*
G01X1245983Y666000D02*
Y668500D01*
X1244942D01*
X1244608Y668375D01*
X1244400Y668208D01*
X1244317Y667875D01*
X1244400Y667542D01*
X1244650Y667333D01*
X1244942Y667208D01*
X1245983D01*
G01X1244942D02*
X1244317Y666000D01*
G01X1242842Y668083D02*
X1242592Y668333D01*
X1242300Y668458D01*
X1241967Y668500D01*
X1241550Y668417D01*
X1241258Y668208D01*
X1241175Y667958D01*
X1241217Y667708D01*
X1241383Y667500D01*
X1242217Y667083D01*
X1242592Y666792D01*
X1242842Y666375D01*
X1242925Y666000D01*
X1241175D01*
G01X1238450D02*
Y668500D01*
X1239992Y666708D01*
X1237908D01*
G01X1235933Y666000D02*
X1235850Y666542D01*
X1235725Y667000D01*
X1235558Y667417D01*
X1235350Y667875D01*
X1235017Y668500D01*
X1236683D01*
G01X1255700Y669000D02*
Y665000D01*
X1248300D01*
G01X1255700Y677500D02*
Y673500D01*
X1248300D01*
G01X1255700Y681500D02*
Y677500D01*
X1248300D01*
G01Y669000D02*
Y673000D01*
X1255700D01*
G01Y693500D02*
Y689500D01*
X1248300D01*
G01X1255700Y697500D02*
Y693500D01*
X1248300D01*
G01Y685500D02*
Y689500D01*
X1255700D01*
G01X1248300Y681500D02*
Y685500D01*
X1255700D01*
G01Y701500D02*
Y697500D01*
X1248300D01*
G01X1255700Y705500D02*
Y701500D01*
X1248300D01*
G01X1255700Y709500D02*
Y705500D01*
X1248300D01*
G01X1255700Y713500D02*
Y709500D01*
X1248300D01*
G01X1253700Y717500D02*
Y713500D01*
X1246300D01*
G01X1258483Y728500D02*
Y731000D01*
X1257442D01*
X1257108Y730875D01*
X1256900Y730708D01*
X1256817Y730375D01*
X1256900Y730042D01*
X1257150Y729833D01*
X1257442Y729708D01*
X1258483D01*
G01X1257442D02*
X1256817Y728500D01*
G01X1254050D02*
Y731000D01*
X1255592Y729208D01*
X1253508D01*
G01X1252242Y729542D02*
X1251950Y729833D01*
X1251700Y730000D01*
X1251367Y730083D01*
X1251075Y730000D01*
X1250867Y729833D01*
X1250700Y729583D01*
X1250658Y729292D01*
X1250700Y729042D01*
X1250867Y728792D01*
X1251117Y728583D01*
X1251408Y728500D01*
X1251742Y728583D01*
X1252033Y728833D01*
X1252200Y729208D01*
X1252242Y729625D01*
X1252158Y730167D01*
X1252033Y730458D01*
X1251825Y730750D01*
X1251533Y730958D01*
X1251242Y731000D01*
X1250950Y730917D01*
X1250742Y730708D01*
G01X1249142Y729542D02*
X1248850Y729833D01*
X1248600Y730000D01*
X1248267Y730083D01*
X1247975Y730000D01*
X1247767Y729833D01*
X1247600Y729583D01*
X1247558Y729292D01*
X1247600Y729042D01*
X1247767Y728792D01*
X1248017Y728583D01*
X1248308Y728500D01*
X1248642Y728583D01*
X1248933Y728833D01*
X1249100Y729208D01*
X1249142Y729625D01*
X1249058Y730167D01*
X1248933Y730458D01*
X1248725Y730750D01*
X1248433Y730958D01*
X1248142Y731000D01*
X1247850Y730917D01*
X1247642Y730708D01*
G01X1258483Y724000D02*
Y726500D01*
X1257442D01*
X1257108Y726375D01*
X1256900Y726208D01*
X1256817Y725875D01*
X1256900Y725542D01*
X1257150Y725333D01*
X1257442Y725208D01*
X1258483D01*
G01X1257442D02*
X1256817Y724000D01*
G01X1255467Y724500D02*
X1255217Y724208D01*
X1254883Y724042D01*
X1254508Y724000D01*
X1254175Y724042D01*
X1253842Y724250D01*
X1253633Y724500D01*
X1253592Y724750D01*
X1253675Y725042D01*
X1253967Y725250D01*
X1254258Y725333D01*
X1254633D01*
G01X1254258D02*
X1254008Y725458D01*
X1253800Y725667D01*
X1253717Y725917D01*
X1253800Y726167D01*
X1254008Y726375D01*
X1254383Y726500D01*
X1254758Y726458D01*
X1255133Y726292D01*
G01X1251450Y726500D02*
X1251783Y726417D01*
X1252033Y726208D01*
X1252200Y725958D01*
X1252325Y725625D01*
X1252367Y725250D01*
X1252325Y724875D01*
X1252200Y724542D01*
X1252033Y724292D01*
X1251783Y724083D01*
X1251450Y724000D01*
X1251117Y724083D01*
X1250867Y724292D01*
X1250700Y724542D01*
X1250575Y724875D01*
X1250533Y725250D01*
X1250575Y725625D01*
X1250700Y725958D01*
X1250867Y726208D01*
X1251117Y726417D01*
X1251450Y726500D01*
G01X1248350Y724000D02*
Y726500D01*
X1248850Y726000D01*
G01Y724000D02*
X1247850D01*
G01X1253700Y721500D02*
Y717500D01*
X1246300D01*
G01X1258483Y744500D02*
Y747000D01*
X1257442D01*
X1257108Y746875D01*
X1256900Y746708D01*
X1256817Y746375D01*
X1256900Y746042D01*
X1257150Y745833D01*
X1257442Y745708D01*
X1258483D01*
G01X1257442D02*
X1256817Y744500D01*
G01X1255342Y746583D02*
X1255092Y746833D01*
X1254800Y746958D01*
X1254467Y747000D01*
X1254050Y746917D01*
X1253758Y746708D01*
X1253675Y746458D01*
X1253717Y746208D01*
X1253883Y746000D01*
X1254717Y745583D01*
X1255092Y745292D01*
X1255342Y744875D01*
X1255425Y744500D01*
X1253675D01*
G01X1251450D02*
X1251158Y744542D01*
X1250825Y744667D01*
X1250617Y744875D01*
X1250533Y745167D01*
X1250617Y745458D01*
X1250867Y745708D01*
X1251242Y745833D01*
X1251658D01*
X1251908Y745917D01*
X1252117Y746125D01*
X1252200Y746417D01*
X1252075Y746708D01*
X1251783Y746917D01*
X1251450Y747000D01*
X1251117Y746917D01*
X1250825Y746708D01*
X1250700Y746417D01*
X1250783Y746125D01*
X1250992Y745917D01*
X1251242Y745833D01*
X1251658D01*
X1252033Y745708D01*
X1252283Y745458D01*
X1252367Y745167D01*
X1252283Y744875D01*
X1252075Y744667D01*
X1251742Y744542D01*
X1251450Y744500D01*
G01X1248350Y747000D02*
X1248683Y746917D01*
X1248933Y746708D01*
X1249100Y746458D01*
X1249225Y746125D01*
X1249267Y745750D01*
X1249225Y745375D01*
X1249100Y745042D01*
X1248933Y744792D01*
X1248683Y744583D01*
X1248350Y744500D01*
X1248017Y744583D01*
X1247767Y744792D01*
X1247600Y745042D01*
X1247475Y745375D01*
X1247433Y745750D01*
X1247475Y746125D01*
X1247600Y746458D01*
X1247767Y746708D01*
X1248017Y746917D01*
X1248350Y747000D01*
G01X1258483Y732500D02*
Y735000D01*
X1257442D01*
X1257108Y734875D01*
X1256900Y734708D01*
X1256817Y734375D01*
X1256900Y734042D01*
X1257150Y733833D01*
X1257442Y733708D01*
X1258483D01*
G01X1257442D02*
X1256817Y732500D01*
G01X1254050D02*
Y735000D01*
X1255592Y733208D01*
X1253508D01*
G01X1252242Y733542D02*
X1251950Y733833D01*
X1251700Y734000D01*
X1251367Y734083D01*
X1251075Y734000D01*
X1250867Y733833D01*
X1250700Y733583D01*
X1250658Y733292D01*
X1250700Y733042D01*
X1250867Y732792D01*
X1251117Y732583D01*
X1251408Y732500D01*
X1251742Y732583D01*
X1252033Y732833D01*
X1252200Y733208D01*
X1252242Y733625D01*
X1252158Y734167D01*
X1252033Y734458D01*
X1251825Y734750D01*
X1251533Y734958D01*
X1251242Y735000D01*
X1250950Y734917D01*
X1250742Y734708D01*
G01X1248433Y732500D02*
X1248350Y733042D01*
X1248225Y733500D01*
X1248058Y733917D01*
X1247850Y734375D01*
X1247517Y735000D01*
X1249183D01*
G01X1258483Y740500D02*
Y743000D01*
X1257442D01*
X1257108Y742875D01*
X1256900Y742708D01*
X1256817Y742375D01*
X1256900Y742042D01*
X1257150Y741833D01*
X1257442Y741708D01*
X1258483D01*
G01X1257442D02*
X1256817Y740500D01*
G01X1254050D02*
Y743000D01*
X1255592Y741208D01*
X1253508D01*
G01X1252242Y741542D02*
X1251950Y741833D01*
X1251700Y742000D01*
X1251367Y742083D01*
X1251075Y742000D01*
X1250867Y741833D01*
X1250700Y741583D01*
X1250658Y741292D01*
X1250700Y741042D01*
X1250867Y740792D01*
X1251117Y740583D01*
X1251408Y740500D01*
X1251742Y740583D01*
X1252033Y740833D01*
X1252200Y741208D01*
X1252242Y741625D01*
X1252158Y742167D01*
X1252033Y742458D01*
X1251825Y742750D01*
X1251533Y742958D01*
X1251242Y743000D01*
X1250950Y742917D01*
X1250742Y742708D01*
G01X1248350Y740500D02*
X1248058Y740542D01*
X1247725Y740667D01*
X1247517Y740875D01*
X1247433Y741167D01*
X1247517Y741458D01*
X1247767Y741708D01*
X1248142Y741833D01*
X1248558D01*
X1248808Y741917D01*
X1249017Y742125D01*
X1249100Y742417D01*
X1248975Y742708D01*
X1248683Y742917D01*
X1248350Y743000D01*
X1248017Y742917D01*
X1247725Y742708D01*
X1247600Y742417D01*
X1247683Y742125D01*
X1247892Y741917D01*
X1248142Y741833D01*
X1248558D01*
X1248933Y741708D01*
X1249183Y741458D01*
X1249267Y741167D01*
X1249183Y740875D01*
X1248975Y740667D01*
X1248642Y740542D01*
X1248350Y740500D01*
G01X1258483Y736500D02*
Y739000D01*
X1257442D01*
X1257108Y738875D01*
X1256900Y738708D01*
X1256817Y738375D01*
X1256900Y738042D01*
X1257150Y737833D01*
X1257442Y737708D01*
X1258483D01*
G01X1257442D02*
X1256817Y736500D01*
G01X1254050D02*
Y739000D01*
X1255592Y737208D01*
X1253508D01*
G01X1252242Y737542D02*
X1251950Y737833D01*
X1251700Y738000D01*
X1251367Y738083D01*
X1251075Y738000D01*
X1250867Y737833D01*
X1250700Y737583D01*
X1250658Y737292D01*
X1250700Y737042D01*
X1250867Y736792D01*
X1251117Y736583D01*
X1251408Y736500D01*
X1251742Y736583D01*
X1252033Y736833D01*
X1252200Y737208D01*
X1252242Y737625D01*
X1252158Y738167D01*
X1252033Y738458D01*
X1251825Y738750D01*
X1251533Y738958D01*
X1251242Y739000D01*
X1250950Y738917D01*
X1250742Y738708D01*
G01X1249058Y736792D02*
X1248767Y736583D01*
X1248433Y736500D01*
X1248100Y736583D01*
X1247808Y736833D01*
X1247600Y737208D01*
X1247517Y737583D01*
Y738042D01*
X1247600Y738417D01*
X1247808Y738750D01*
X1248058Y738917D01*
X1248350Y739000D01*
X1248683Y738917D01*
X1248933Y738750D01*
X1249100Y738500D01*
X1249183Y738167D01*
X1249100Y737875D01*
X1248892Y737583D01*
X1248642Y737417D01*
X1248350Y737375D01*
X1248017Y737458D01*
X1247767Y737667D01*
X1247517Y738042D01*
G01X1258483Y748500D02*
Y751000D01*
X1257442D01*
X1257108Y750875D01*
X1256900Y750708D01*
X1256817Y750375D01*
X1256900Y750042D01*
X1257150Y749833D01*
X1257442Y749708D01*
X1258483D01*
G01X1257442D02*
X1256817Y748500D01*
G01X1255467Y749000D02*
X1255217Y748708D01*
X1254883Y748542D01*
X1254508Y748500D01*
X1254175Y748542D01*
X1253842Y748750D01*
X1253633Y749000D01*
X1253592Y749250D01*
X1253675Y749542D01*
X1253967Y749750D01*
X1254258Y749833D01*
X1254633D01*
G01X1254258D02*
X1254008Y749958D01*
X1253800Y750167D01*
X1253717Y750417D01*
X1253800Y750667D01*
X1254008Y750875D01*
X1254383Y751000D01*
X1254758Y750958D01*
X1255133Y750792D01*
G01X1251450Y748500D02*
Y751000D01*
X1251950Y750500D01*
G01Y748500D02*
X1250950D01*
G01X1249267Y748875D02*
X1249017Y748667D01*
X1248725Y748542D01*
X1248350Y748500D01*
X1247975Y748583D01*
X1247683Y748750D01*
X1247475Y749042D01*
X1247433Y749375D01*
X1247517Y749708D01*
X1247725Y749917D01*
X1248017Y750083D01*
X1248308Y750125D01*
X1248600Y750083D01*
X1248975Y749917D01*
X1248850Y751000D01*
X1247725D01*
G01X1258483Y752500D02*
Y755000D01*
X1257442D01*
X1257108Y754875D01*
X1256900Y754708D01*
X1256817Y754375D01*
X1256900Y754042D01*
X1257150Y753833D01*
X1257442Y753708D01*
X1258483D01*
G01X1257442D02*
X1256817Y752500D01*
G01X1255467Y753000D02*
X1255217Y752708D01*
X1254883Y752542D01*
X1254508Y752500D01*
X1254175Y752542D01*
X1253842Y752750D01*
X1253633Y753000D01*
X1253592Y753250D01*
X1253675Y753542D01*
X1253967Y753750D01*
X1254258Y753833D01*
X1254633D01*
G01X1254258D02*
X1254008Y753958D01*
X1253800Y754167D01*
X1253717Y754417D01*
X1253800Y754667D01*
X1254008Y754875D01*
X1254383Y755000D01*
X1254758Y754958D01*
X1255133Y754792D01*
G01X1251450Y752500D02*
Y755000D01*
X1251950Y754500D01*
G01Y752500D02*
X1250950D01*
G01X1249142Y753542D02*
X1248850Y753833D01*
X1248600Y754000D01*
X1248267Y754083D01*
X1247975Y754000D01*
X1247767Y753833D01*
X1247600Y753583D01*
X1247558Y753292D01*
X1247600Y753042D01*
X1247767Y752792D01*
X1248017Y752583D01*
X1248308Y752500D01*
X1248642Y752583D01*
X1248933Y752833D01*
X1249100Y753208D01*
X1249142Y753625D01*
X1249058Y754167D01*
X1248933Y754458D01*
X1248725Y754750D01*
X1248433Y754958D01*
X1248142Y755000D01*
X1247850Y754917D01*
X1247642Y754708D01*
G01X1258483Y756500D02*
Y759000D01*
X1257442D01*
X1257108Y758875D01*
X1256900Y758708D01*
X1256817Y758375D01*
X1256900Y758042D01*
X1257150Y757833D01*
X1257442Y757708D01*
X1258483D01*
G01X1257442D02*
X1256817Y756500D01*
G01X1255467Y757000D02*
X1255217Y756708D01*
X1254883Y756542D01*
X1254508Y756500D01*
X1254175Y756542D01*
X1253842Y756750D01*
X1253633Y757000D01*
X1253592Y757250D01*
X1253675Y757542D01*
X1253967Y757750D01*
X1254258Y757833D01*
X1254633D01*
G01X1254258D02*
X1254008Y757958D01*
X1253800Y758167D01*
X1253717Y758417D01*
X1253800Y758667D01*
X1254008Y758875D01*
X1254383Y759000D01*
X1254758Y758958D01*
X1255133Y758792D01*
G01X1251450Y756500D02*
Y759000D01*
X1251950Y758500D01*
G01Y756500D02*
X1250950D01*
G01X1248350D02*
X1248058Y756542D01*
X1247725Y756667D01*
X1247517Y756875D01*
X1247433Y757167D01*
X1247517Y757458D01*
X1247767Y757708D01*
X1248142Y757833D01*
X1248558D01*
X1248808Y757917D01*
X1249017Y758125D01*
X1249100Y758417D01*
X1248975Y758708D01*
X1248683Y758917D01*
X1248350Y759000D01*
X1248017Y758917D01*
X1247725Y758708D01*
X1247600Y758417D01*
X1247683Y758125D01*
X1247892Y757917D01*
X1248142Y757833D01*
X1248558D01*
X1248933Y757708D01*
X1249183Y757458D01*
X1249267Y757167D01*
X1249183Y756875D01*
X1248975Y756667D01*
X1248642Y756542D01*
X1248350Y756500D01*
G01X1258483Y760500D02*
Y763000D01*
X1257442D01*
X1257108Y762875D01*
X1256900Y762708D01*
X1256817Y762375D01*
X1256900Y762042D01*
X1257150Y761833D01*
X1257442Y761708D01*
X1258483D01*
G01X1257442D02*
X1256817Y760500D01*
G01X1255467Y761000D02*
X1255217Y760708D01*
X1254883Y760542D01*
X1254508Y760500D01*
X1254175Y760542D01*
X1253842Y760750D01*
X1253633Y761000D01*
X1253592Y761250D01*
X1253675Y761542D01*
X1253967Y761750D01*
X1254258Y761833D01*
X1254633D01*
G01X1254258D02*
X1254008Y761958D01*
X1253800Y762167D01*
X1253717Y762417D01*
X1253800Y762667D01*
X1254008Y762875D01*
X1254383Y763000D01*
X1254758Y762958D01*
X1255133Y762792D01*
G01X1252242Y762583D02*
X1251992Y762833D01*
X1251700Y762958D01*
X1251367Y763000D01*
X1250950Y762917D01*
X1250658Y762708D01*
X1250575Y762458D01*
X1250617Y762208D01*
X1250783Y762000D01*
X1251617Y761583D01*
X1251992Y761292D01*
X1252242Y760875D01*
X1252325Y760500D01*
X1250575D01*
G01X1248350D02*
Y763000D01*
X1248850Y762500D01*
G01Y760500D02*
X1247850D01*
G01X1258483Y764500D02*
Y767000D01*
X1257442D01*
X1257108Y766875D01*
X1256900Y766708D01*
X1256817Y766375D01*
X1256900Y766042D01*
X1257150Y765833D01*
X1257442Y765708D01*
X1258483D01*
G01X1257442D02*
X1256817Y764500D01*
G01X1255467Y765000D02*
X1255217Y764708D01*
X1254883Y764542D01*
X1254508Y764500D01*
X1254175Y764542D01*
X1253842Y764750D01*
X1253633Y765000D01*
X1253592Y765250D01*
X1253675Y765542D01*
X1253967Y765750D01*
X1254258Y765833D01*
X1254633D01*
G01X1254258D02*
X1254008Y765958D01*
X1253800Y766167D01*
X1253717Y766417D01*
X1253800Y766667D01*
X1254008Y766875D01*
X1254383Y767000D01*
X1254758Y766958D01*
X1255133Y766792D01*
G01X1252242Y766583D02*
X1251992Y766833D01*
X1251700Y766958D01*
X1251367Y767000D01*
X1250950Y766917D01*
X1250658Y766708D01*
X1250575Y766458D01*
X1250617Y766208D01*
X1250783Y766000D01*
X1251617Y765583D01*
X1251992Y765292D01*
X1252242Y764875D01*
X1252325Y764500D01*
X1250575D01*
G01X1249142Y766583D02*
X1248892Y766833D01*
X1248600Y766958D01*
X1248267Y767000D01*
X1247850Y766917D01*
X1247558Y766708D01*
X1247475Y766458D01*
X1247517Y766208D01*
X1247683Y766000D01*
X1248517Y765583D01*
X1248892Y765292D01*
X1249142Y764875D01*
X1249225Y764500D01*
X1247475D01*
G01X1250483Y769000D02*
Y771500D01*
X1249442D01*
X1249108Y771375D01*
X1248900Y771208D01*
X1248817Y770875D01*
X1248900Y770542D01*
X1249150Y770333D01*
X1249442Y770208D01*
X1250483D01*
G01X1249442D02*
X1248817Y769000D01*
G01X1247467Y769500D02*
X1247217Y769208D01*
X1246883Y769042D01*
X1246508Y769000D01*
X1246175Y769042D01*
X1245842Y769250D01*
X1245633Y769500D01*
X1245592Y769750D01*
X1245675Y770042D01*
X1245967Y770250D01*
X1246258Y770333D01*
X1246633D01*
G01X1246258D02*
X1246008Y770458D01*
X1245800Y770667D01*
X1245717Y770917D01*
X1245800Y771167D01*
X1246008Y771375D01*
X1246383Y771500D01*
X1246758Y771458D01*
X1247133Y771292D01*
G01X1243533Y769000D02*
X1243450Y769542D01*
X1243325Y770000D01*
X1243158Y770417D01*
X1242950Y770875D01*
X1242617Y771500D01*
X1244283D01*
G01X1241267Y769500D02*
X1241017Y769208D01*
X1240683Y769042D01*
X1240308Y769000D01*
X1239975Y769042D01*
X1239642Y769250D01*
X1239433Y769500D01*
X1239392Y769750D01*
X1239475Y770042D01*
X1239767Y770250D01*
X1240058Y770333D01*
X1240433D01*
G01X1240058D02*
X1239808Y770458D01*
X1239600Y770667D01*
X1239517Y770917D01*
X1239600Y771167D01*
X1239808Y771375D01*
X1240183Y771500D01*
X1240558Y771458D01*
X1240933Y771292D01*
G01X1252033Y773000D02*
Y775500D01*
X1250992D01*
X1250658Y775375D01*
X1250450Y775208D01*
X1250367Y774875D01*
X1250450Y774542D01*
X1250700Y774333D01*
X1250992Y774208D01*
X1252033D01*
G01X1250992D02*
X1250367Y773000D01*
G01X1249017Y773500D02*
X1248767Y773208D01*
X1248433Y773042D01*
X1248058Y773000D01*
X1247725Y773042D01*
X1247392Y773250D01*
X1247183Y773500D01*
X1247142Y773750D01*
X1247225Y774042D01*
X1247517Y774250D01*
X1247808Y774333D01*
X1248183D01*
G01X1247808D02*
X1247558Y774458D01*
X1247350Y774667D01*
X1247267Y774917D01*
X1247350Y775167D01*
X1247558Y775375D01*
X1247933Y775500D01*
X1248308Y775458D01*
X1248683Y775292D01*
G01X1245000Y775500D02*
X1245333Y775417D01*
X1245583Y775208D01*
X1245750Y774958D01*
X1245875Y774625D01*
X1245917Y774250D01*
X1245875Y773875D01*
X1245750Y773542D01*
X1245583Y773292D01*
X1245333Y773083D01*
X1245000Y773000D01*
X1244667Y773083D01*
X1244417Y773292D01*
X1244250Y773542D01*
X1244125Y773875D01*
X1244083Y774250D01*
X1244125Y774625D01*
X1244250Y774958D01*
X1244417Y775208D01*
X1244667Y775417D01*
X1245000Y775500D01*
G01X1242608Y773292D02*
X1242317Y773083D01*
X1241983Y773000D01*
X1241650Y773083D01*
X1241358Y773333D01*
X1241150Y773708D01*
X1241067Y774083D01*
Y774542D01*
X1241150Y774917D01*
X1241358Y775250D01*
X1241608Y775417D01*
X1241900Y775500D01*
X1242233Y775417D01*
X1242483Y775250D01*
X1242650Y775000D01*
X1242733Y774667D01*
X1242650Y774375D01*
X1242442Y774083D01*
X1242192Y773917D01*
X1241900Y773875D01*
X1241567Y773958D01*
X1241317Y774167D01*
X1241067Y774542D01*
G01X1239508Y773292D02*
X1239217Y773083D01*
X1238883Y773000D01*
X1238550Y773083D01*
X1238258Y773333D01*
X1238050Y773708D01*
X1237967Y774083D01*
Y774542D01*
X1238050Y774917D01*
X1238258Y775250D01*
X1238508Y775417D01*
X1238800Y775500D01*
X1239133Y775417D01*
X1239383Y775250D01*
X1239550Y775000D01*
X1239633Y774667D01*
X1239550Y774375D01*
X1239342Y774083D01*
X1239092Y773917D01*
X1238800Y773875D01*
X1238467Y773958D01*
X1238217Y774167D01*
X1237967Y774542D01*
G01X1264800Y429500D02*
X1270000D01*
G01X1264800D02*
Y436500D01*
G01D02*
X1272600D01*
G01X1260000Y623017D02*
X1262500D01*
Y624058D01*
X1262375Y624392D01*
X1262208Y624600D01*
X1261875Y624683D01*
X1261542Y624600D01*
X1261333Y624350D01*
X1261208Y624058D01*
Y623017D01*
G01Y624058D02*
X1260000Y624683D01*
G01Y627450D02*
X1262500D01*
X1260708Y625908D01*
Y627992D01*
G01X1260500Y629133D02*
X1260208Y629383D01*
X1260042Y629717D01*
X1260000Y630092D01*
X1260042Y630425D01*
X1260250Y630758D01*
X1260500Y630967D01*
X1260750Y631008D01*
X1261042Y630925D01*
X1261250Y630633D01*
X1261333Y630342D01*
Y629967D01*
G01Y630342D02*
X1261458Y630592D01*
X1261667Y630800D01*
X1261917Y630883D01*
X1262167Y630800D01*
X1262375Y630592D01*
X1262500Y630217D01*
X1262458Y629842D01*
X1262292Y629467D01*
G01X1260292Y632442D02*
X1260083Y632733D01*
X1260000Y633067D01*
X1260083Y633400D01*
X1260333Y633692D01*
X1260708Y633900D01*
X1261083Y633983D01*
X1261542D01*
X1261917Y633900D01*
X1262250Y633692D01*
X1262417Y633442D01*
X1262500Y633150D01*
X1262417Y632817D01*
X1262250Y632567D01*
X1262000Y632400D01*
X1261667Y632317D01*
X1261375Y632400D01*
X1261083Y632608D01*
X1260917Y632858D01*
X1260875Y633150D01*
X1260958Y633483D01*
X1261167Y633733D01*
X1261542Y633983D01*
G01X1275483Y641000D02*
Y643500D01*
X1274442D01*
X1274108Y643375D01*
X1273900Y643208D01*
X1273817Y642875D01*
X1273900Y642542D01*
X1274150Y642333D01*
X1274442Y642208D01*
X1275483D01*
G01X1274442D02*
X1273817Y641000D01*
G01X1271050D02*
Y643500D01*
X1272592Y641708D01*
X1270508D01*
G01X1269367Y641500D02*
X1269117Y641208D01*
X1268783Y641042D01*
X1268408Y641000D01*
X1268075Y641042D01*
X1267742Y641250D01*
X1267533Y641500D01*
X1267492Y641750D01*
X1267575Y642042D01*
X1267867Y642250D01*
X1268158Y642333D01*
X1268533D01*
G01X1268158D02*
X1267908Y642458D01*
X1267700Y642667D01*
X1267617Y642917D01*
X1267700Y643167D01*
X1267908Y643375D01*
X1268283Y643500D01*
X1268658Y643458D01*
X1269033Y643292D01*
G01X1265350Y641000D02*
X1265058Y641042D01*
X1264725Y641167D01*
X1264517Y641375D01*
X1264433Y641667D01*
X1264517Y641958D01*
X1264767Y642208D01*
X1265142Y642333D01*
X1265558D01*
X1265808Y642417D01*
X1266017Y642625D01*
X1266100Y642917D01*
X1265975Y643208D01*
X1265683Y643417D01*
X1265350Y643500D01*
X1265017Y643417D01*
X1264725Y643208D01*
X1264600Y642917D01*
X1264683Y642625D01*
X1264892Y642417D01*
X1265142Y642333D01*
X1265558D01*
X1265933Y642208D01*
X1266183Y641958D01*
X1266267Y641667D01*
X1266183Y641375D01*
X1265975Y641167D01*
X1265642Y641042D01*
X1265350Y641000D01*
G01X1263200Y649000D02*
Y645000D01*
X1255800D01*
G01X1262500Y635800D02*
X1258500D01*
Y643200D01*
G01X1275483Y650000D02*
Y652500D01*
X1274442D01*
X1274108Y652375D01*
X1273900Y652208D01*
X1273817Y651875D01*
X1273900Y651542D01*
X1274150Y651333D01*
X1274442Y651208D01*
X1275483D01*
G01X1274442D02*
X1273817Y650000D01*
G01X1272467Y650500D02*
X1272217Y650208D01*
X1271883Y650042D01*
X1271508Y650000D01*
X1271175Y650042D01*
X1270842Y650250D01*
X1270633Y650500D01*
X1270592Y650750D01*
X1270675Y651042D01*
X1270967Y651250D01*
X1271258Y651333D01*
X1271633D01*
G01X1271258D02*
X1271008Y651458D01*
X1270800Y651667D01*
X1270717Y651917D01*
X1270800Y652167D01*
X1271008Y652375D01*
X1271383Y652500D01*
X1271758Y652458D01*
X1272133Y652292D01*
G01X1268450Y650000D02*
Y652500D01*
X1268950Y652000D01*
G01Y650000D02*
X1267950D01*
G01X1264850D02*
Y652500D01*
X1266392Y650708D01*
X1264308D01*
G01X1255800Y649000D02*
Y653000D01*
X1263200D01*
G01X1274983Y655000D02*
Y657500D01*
X1273942D01*
X1273608Y657375D01*
X1273400Y657208D01*
X1273317Y656875D01*
X1273400Y656542D01*
X1273650Y656333D01*
X1273942Y656208D01*
X1274983D01*
G01X1273942D02*
X1273317Y655000D01*
G01X1270550D02*
Y657500D01*
X1272092Y655708D01*
X1270008D01*
G01X1267950Y655000D02*
Y657500D01*
X1268450Y657000D01*
G01Y655000D02*
X1267450D01*
G01X1264850D02*
Y657500D01*
X1265350Y657000D01*
G01Y655000D02*
X1264350D01*
G01X1255800D02*
Y659000D01*
X1263200D01*
G01X1274983D02*
Y661500D01*
X1273942D01*
X1273608Y661375D01*
X1273400Y661208D01*
X1273317Y660875D01*
X1273400Y660542D01*
X1273650Y660333D01*
X1273942Y660208D01*
X1274983D01*
G01X1273942D02*
X1273317Y659000D01*
G01X1270550D02*
Y661500D01*
X1272092Y659708D01*
X1270008D01*
G01X1268867Y659500D02*
X1268617Y659208D01*
X1268283Y659042D01*
X1267908Y659000D01*
X1267575Y659042D01*
X1267242Y659250D01*
X1267033Y659500D01*
X1266992Y659750D01*
X1267075Y660042D01*
X1267367Y660250D01*
X1267658Y660333D01*
X1268033D01*
G01X1267658D02*
X1267408Y660458D01*
X1267200Y660667D01*
X1267117Y660917D01*
X1267200Y661167D01*
X1267408Y661375D01*
X1267783Y661500D01*
X1268158Y661458D01*
X1268533Y661292D01*
G01X1264933Y659000D02*
X1264850Y659542D01*
X1264725Y660000D01*
X1264558Y660417D01*
X1264350Y660875D01*
X1264017Y661500D01*
X1265683D01*
G01X1255800Y659000D02*
Y663000D01*
X1263200D01*
G01X1275483Y666500D02*
Y669000D01*
X1274442D01*
X1274108Y668875D01*
X1273900Y668708D01*
X1273817Y668375D01*
X1273900Y668042D01*
X1274150Y667833D01*
X1274442Y667708D01*
X1275483D01*
G01X1274442D02*
X1273817Y666500D01*
G01X1271050D02*
Y669000D01*
X1272592Y667208D01*
X1270508D01*
G01X1269367Y667000D02*
X1269117Y666708D01*
X1268783Y666542D01*
X1268408Y666500D01*
X1268075Y666542D01*
X1267742Y666750D01*
X1267533Y667000D01*
X1267492Y667250D01*
X1267575Y667542D01*
X1267867Y667750D01*
X1268158Y667833D01*
X1268533D01*
G01X1268158D02*
X1267908Y667958D01*
X1267700Y668167D01*
X1267617Y668417D01*
X1267700Y668667D01*
X1267908Y668875D01*
X1268283Y669000D01*
X1268658Y668958D01*
X1269033Y668792D01*
G01X1266142Y667542D02*
X1265850Y667833D01*
X1265600Y668000D01*
X1265267Y668083D01*
X1264975Y668000D01*
X1264767Y667833D01*
X1264600Y667583D01*
X1264558Y667292D01*
X1264600Y667042D01*
X1264767Y666792D01*
X1265017Y666583D01*
X1265308Y666500D01*
X1265642Y666583D01*
X1265933Y666833D01*
X1266100Y667208D01*
X1266142Y667625D01*
X1266058Y668167D01*
X1265933Y668458D01*
X1265725Y668750D01*
X1265433Y668958D01*
X1265142Y669000D01*
X1264850Y668917D01*
X1264642Y668708D01*
G01X1255800Y665500D02*
Y669500D01*
X1263200D01*
G01X1261200Y717500D02*
Y713500D01*
X1253800D01*
G01X1268033Y769000D02*
Y771500D01*
X1266992D01*
X1266658Y771375D01*
X1266450Y771208D01*
X1266367Y770875D01*
X1266450Y770542D01*
X1266700Y770333D01*
X1266992Y770208D01*
X1268033D01*
G01X1266992D02*
X1266367Y769000D01*
G01X1265017Y769375D02*
X1264767Y769167D01*
X1264475Y769042D01*
X1264100Y769000D01*
X1263725Y769083D01*
X1263433Y769250D01*
X1263225Y769542D01*
X1263183Y769875D01*
X1263267Y770208D01*
X1263475Y770417D01*
X1263767Y770583D01*
X1264058Y770625D01*
X1264350Y770583D01*
X1264725Y770417D01*
X1264600Y771500D01*
X1263475D01*
G01X1261083Y769000D02*
X1261000Y769542D01*
X1260875Y770000D01*
X1260708Y770417D01*
X1260500Y770875D01*
X1260167Y771500D01*
X1261833D01*
G01X1257983Y769000D02*
X1257900Y769542D01*
X1257775Y770000D01*
X1257608Y770417D01*
X1257400Y770875D01*
X1257067Y771500D01*
X1258733D01*
G01X1255592Y771083D02*
X1255342Y771333D01*
X1255050Y771458D01*
X1254717Y771500D01*
X1254300Y771417D01*
X1254008Y771208D01*
X1253925Y770958D01*
X1253967Y770708D01*
X1254133Y770500D01*
X1254967Y770083D01*
X1255342Y769792D01*
X1255592Y769375D01*
X1255675Y769000D01*
X1253925D01*
G01X1266283Y775292D02*
X1266533Y775417D01*
X1266825Y775500D01*
X1267158D01*
X1267533Y775375D01*
X1267825Y775167D01*
X1268033Y774917D01*
X1268200Y774500D01*
X1268242Y774125D01*
X1268158Y773750D01*
X1268033Y773500D01*
X1267783Y773250D01*
X1267492Y773083D01*
X1267200Y773000D01*
X1266908D01*
X1266617Y773083D01*
X1266367Y773208D01*
X1266158Y773375D01*
G01X1264100Y773000D02*
X1263808Y773042D01*
X1263475Y773167D01*
X1263267Y773375D01*
X1263183Y773667D01*
X1263267Y773958D01*
X1263517Y774208D01*
X1263892Y774333D01*
X1264308D01*
X1264558Y774417D01*
X1264767Y774625D01*
X1264850Y774917D01*
X1264725Y775208D01*
X1264433Y775417D01*
X1264100Y775500D01*
X1263767Y775417D01*
X1263475Y775208D01*
X1263350Y774917D01*
X1263433Y774625D01*
X1263642Y774417D01*
X1263892Y774333D01*
X1264308D01*
X1264683Y774208D01*
X1264933Y773958D01*
X1265017Y773667D01*
X1264933Y773375D01*
X1264725Y773167D01*
X1264392Y773042D01*
X1264100Y773000D01*
G01X1261000Y775500D02*
X1261333Y775417D01*
X1261583Y775208D01*
X1261750Y774958D01*
X1261875Y774625D01*
X1261917Y774250D01*
X1261875Y773875D01*
X1261750Y773542D01*
X1261583Y773292D01*
X1261333Y773083D01*
X1261000Y773000D01*
X1260667Y773083D01*
X1260417Y773292D01*
X1260250Y773542D01*
X1260125Y773875D01*
X1260083Y774250D01*
X1260125Y774625D01*
X1260250Y774958D01*
X1260417Y775208D01*
X1260667Y775417D01*
X1261000Y775500D01*
G01X1257900Y773000D02*
X1257608Y773042D01*
X1257275Y773167D01*
X1257067Y773375D01*
X1256983Y773667D01*
X1257067Y773958D01*
X1257317Y774208D01*
X1257692Y774333D01*
X1258108D01*
X1258358Y774417D01*
X1258567Y774625D01*
X1258650Y774917D01*
X1258525Y775208D01*
X1258233Y775417D01*
X1257900Y775500D01*
X1257567Y775417D01*
X1257275Y775208D01*
X1257150Y774917D01*
X1257233Y774625D01*
X1257442Y774417D01*
X1257692Y774333D01*
X1258108D01*
X1258483Y774208D01*
X1258733Y773958D01*
X1258817Y773667D01*
X1258733Y773375D01*
X1258525Y773167D01*
X1258192Y773042D01*
X1257900Y773000D01*
G01X1255508Y773292D02*
X1255217Y773083D01*
X1254883Y773000D01*
X1254550Y773083D01*
X1254258Y773333D01*
X1254050Y773708D01*
X1253967Y774083D01*
Y774542D01*
X1254050Y774917D01*
X1254258Y775250D01*
X1254508Y775417D01*
X1254800Y775500D01*
X1255133Y775417D01*
X1255383Y775250D01*
X1255550Y775000D01*
X1255633Y774667D01*
X1255550Y774375D01*
X1255342Y774083D01*
X1255092Y773917D01*
X1254800Y773875D01*
X1254467Y773958D01*
X1254217Y774167D01*
X1253967Y774542D01*
G01X1273000Y416017D02*
X1275500D01*
Y417017D01*
X1275375Y417350D01*
X1275083Y417600D01*
X1274750Y417683D01*
X1274417Y417600D01*
X1274167Y417392D01*
X1274042Y417017D01*
Y416017D01*
G01X1273000Y419117D02*
X1275500D01*
Y420158D01*
X1275375Y420492D01*
X1275208Y420700D01*
X1274875Y420783D01*
X1274542Y420700D01*
X1274333Y420450D01*
X1274208Y420158D01*
Y419117D01*
G01Y420158D02*
X1273000Y420783D01*
G01X1275083Y422258D02*
X1275333Y422508D01*
X1275458Y422800D01*
X1275500Y423133D01*
X1275417Y423550D01*
X1275208Y423842D01*
X1274958Y423925D01*
X1274708Y423883D01*
X1274500Y423717D01*
X1274083Y422883D01*
X1273792Y422508D01*
X1273375Y422258D01*
X1273000Y422175D01*
Y423925D01*
G01X1275500Y426150D02*
X1275417Y425817D01*
X1275208Y425567D01*
X1274958Y425400D01*
X1274625Y425275D01*
X1274250Y425233D01*
X1273875Y425275D01*
X1273542Y425400D01*
X1273292Y425567D01*
X1273083Y425817D01*
X1273000Y426150D01*
X1273083Y426483D01*
X1273292Y426733D01*
X1273542Y426900D01*
X1273875Y427025D01*
X1274250Y427067D01*
X1274625Y427025D01*
X1274958Y426900D01*
X1275208Y426733D01*
X1275417Y426483D01*
X1275500Y426150D01*
G01X1278200Y429500D02*
X1269500D01*
G01X1278200Y436500D02*
Y429500D01*
G01X1271800Y436500D02*
X1278200D01*
G01X1279000Y685300D02*
X1275000D01*
Y692700D01*
G01X1271000Y703700D02*
X1275000D01*
Y696300D01*
G01X1279000Y692700D02*
X1283000D01*
Y685300D01*
G01X1279000Y711200D02*
X1283000D01*
Y703800D01*
G01X1275000D02*
X1271000D01*
Y711200D01*
G01X1279000Y703700D02*
X1283000D01*
Y696300D01*
G01Y714300D02*
X1279000D01*
Y721700D01*
G01Y722300D02*
X1275000D01*
Y729700D01*
G01Y721700D02*
X1279000D01*
Y714300D01*
G01Y729700D02*
X1283000D01*
Y722300D01*
G01X1306983Y414000D02*
Y416500D01*
X1305983D01*
X1305650Y416375D01*
X1305400Y416083D01*
X1305317Y415750D01*
X1305400Y415417D01*
X1305608Y415167D01*
X1305983Y415042D01*
X1306983D01*
G01X1303883Y414000D02*
Y416500D01*
X1302842D01*
X1302508Y416375D01*
X1302300Y416208D01*
X1302217Y415875D01*
X1302300Y415542D01*
X1302550Y415333D01*
X1302842Y415208D01*
X1303883D01*
G01X1302842D02*
X1302217Y414000D01*
G01X1300742Y416083D02*
X1300492Y416333D01*
X1300200Y416458D01*
X1299867Y416500D01*
X1299450Y416417D01*
X1299158Y416208D01*
X1299075Y415958D01*
X1299117Y415708D01*
X1299283Y415500D01*
X1300117Y415083D01*
X1300492Y414792D01*
X1300742Y414375D01*
X1300825Y414000D01*
X1299075D01*
G01X1297642Y415042D02*
X1297350Y415333D01*
X1297100Y415500D01*
X1296767Y415583D01*
X1296475Y415500D01*
X1296267Y415333D01*
X1296100Y415083D01*
X1296058Y414792D01*
X1296100Y414542D01*
X1296267Y414292D01*
X1296517Y414083D01*
X1296808Y414000D01*
X1297142Y414083D01*
X1297433Y414333D01*
X1297600Y414708D01*
X1297642Y415125D01*
X1297558Y415667D01*
X1297433Y415958D01*
X1297225Y416250D01*
X1296933Y416458D01*
X1296642Y416500D01*
X1296350Y416417D01*
X1296142Y416208D01*
G01X1290500Y418700D02*
X1294500D01*
Y411300D01*
G01X1285000Y416017D02*
X1287500D01*
Y417017D01*
X1287375Y417350D01*
X1287083Y417600D01*
X1286750Y417683D01*
X1286417Y417600D01*
X1286167Y417392D01*
X1286042Y417017D01*
Y416017D01*
G01X1287292Y420867D02*
X1287417Y420617D01*
X1287500Y420325D01*
Y419992D01*
X1287375Y419617D01*
X1287167Y419325D01*
X1286917Y419117D01*
X1286500Y418950D01*
X1286125Y418908D01*
X1285750Y418992D01*
X1285500Y419117D01*
X1285250Y419367D01*
X1285083Y419658D01*
X1285000Y419950D01*
Y420242D01*
X1285083Y420533D01*
X1285208Y420783D01*
X1285375Y420992D01*
G01X1287083Y422258D02*
X1287333Y422508D01*
X1287458Y422800D01*
X1287500Y423133D01*
X1287417Y423550D01*
X1287208Y423842D01*
X1286958Y423925D01*
X1286708Y423883D01*
X1286500Y423717D01*
X1286083Y422883D01*
X1285792Y422508D01*
X1285375Y422258D01*
X1285000Y422175D01*
Y423925D01*
G01Y426067D02*
X1285542Y426150D01*
X1286000Y426275D01*
X1286417Y426442D01*
X1286875Y426650D01*
X1287500Y426983D01*
Y425317D01*
G01X1306983Y405500D02*
Y408000D01*
X1305983D01*
X1305650Y407875D01*
X1305400Y407583D01*
X1305317Y407250D01*
X1305400Y406917D01*
X1305608Y406667D01*
X1305983Y406542D01*
X1306983D01*
G01X1302133Y407792D02*
X1302383Y407917D01*
X1302675Y408000D01*
X1303008D01*
X1303383Y407875D01*
X1303675Y407667D01*
X1303883Y407417D01*
X1304050Y407000D01*
X1304092Y406625D01*
X1304008Y406250D01*
X1303883Y406000D01*
X1303633Y405750D01*
X1303342Y405583D01*
X1303050Y405500D01*
X1302758D01*
X1302467Y405583D01*
X1302217Y405708D01*
X1302008Y405875D01*
G01X1300867Y406000D02*
X1300617Y405708D01*
X1300283Y405542D01*
X1299908Y405500D01*
X1299575Y405542D01*
X1299242Y405750D01*
X1299033Y406000D01*
X1298992Y406250D01*
X1299075Y406542D01*
X1299367Y406750D01*
X1299658Y406833D01*
X1300033D01*
G01X1299658D02*
X1299408Y406958D01*
X1299200Y407167D01*
X1299117Y407417D01*
X1299200Y407667D01*
X1299408Y407875D01*
X1299783Y408000D01*
X1300158Y407958D01*
X1300533Y407792D01*
G01X1296850Y408000D02*
X1297183Y407917D01*
X1297433Y407708D01*
X1297600Y407458D01*
X1297725Y407125D01*
X1297767Y406750D01*
X1297725Y406375D01*
X1297600Y406042D01*
X1297433Y405792D01*
X1297183Y405583D01*
X1296850Y405500D01*
X1296517Y405583D01*
X1296267Y405792D01*
X1296100Y406042D01*
X1295975Y406375D01*
X1295933Y406750D01*
X1295975Y407125D01*
X1296100Y407458D01*
X1296267Y407708D01*
X1296517Y407917D01*
X1296850Y408000D01*
G01X1313292Y646367D02*
X1313417Y646117D01*
X1313500Y645825D01*
Y645492D01*
X1313375Y645117D01*
X1313167Y644825D01*
X1312917Y644617D01*
X1312500Y644450D01*
X1312125Y644408D01*
X1311750Y644492D01*
X1311500Y644617D01*
X1311250Y644867D01*
X1311083Y645158D01*
X1311000Y645450D01*
Y645742D01*
X1311083Y646033D01*
X1311208Y646283D01*
X1311375Y646492D01*
G01X1311000Y649050D02*
X1313500D01*
X1311708Y647508D01*
Y649592D01*
G01X1305000Y676967D02*
X1307500D01*
Y678008D01*
X1307375Y678342D01*
X1307208Y678550D01*
X1306875Y678633D01*
X1306542Y678550D01*
X1306333Y678300D01*
X1306208Y678008D01*
Y676967D01*
G01Y678008D02*
X1305000Y678633D01*
G01X1305375Y679983D02*
X1305167Y680233D01*
X1305042Y680525D01*
X1305000Y680900D01*
X1305083Y681275D01*
X1305250Y681567D01*
X1305542Y681775D01*
X1305875Y681817D01*
X1306208Y681733D01*
X1306417Y681525D01*
X1306583Y681233D01*
X1306625Y680942D01*
X1306583Y680650D01*
X1306417Y680275D01*
X1307500Y680400D01*
Y681525D01*
G01X1305000Y683917D02*
X1305542Y684000D01*
X1306000Y684125D01*
X1306417Y684292D01*
X1306875Y684500D01*
X1307500Y684833D01*
Y683167D01*
G01X1306042Y686308D02*
X1306333Y686600D01*
X1306500Y686850D01*
X1306583Y687183D01*
X1306500Y687475D01*
X1306333Y687683D01*
X1306083Y687850D01*
X1305792Y687892D01*
X1305542Y687850D01*
X1305292Y687683D01*
X1305083Y687433D01*
X1305000Y687142D01*
X1305083Y686808D01*
X1305333Y686517D01*
X1305708Y686350D01*
X1306125Y686308D01*
X1306667Y686392D01*
X1306958Y686517D01*
X1307250Y686725D01*
X1307458Y687017D01*
X1307500Y687308D01*
X1307417Y687600D01*
X1307208Y687808D01*
G01X1306042Y689408D02*
X1306333Y689700D01*
X1306500Y689950D01*
X1306583Y690283D01*
X1306500Y690575D01*
X1306333Y690783D01*
X1306083Y690950D01*
X1305792Y690992D01*
X1305542Y690950D01*
X1305292Y690783D01*
X1305083Y690533D01*
X1305000Y690242D01*
X1305083Y689908D01*
X1305333Y689617D01*
X1305708Y689450D01*
X1306125Y689408D01*
X1306667Y689492D01*
X1306958Y689617D01*
X1307250Y689825D01*
X1307458Y690117D01*
X1307500Y690408D01*
X1307417Y690700D01*
X1307208Y690908D01*
G01X1309000Y676967D02*
X1311500D01*
Y678008D01*
X1311375Y678342D01*
X1311208Y678550D01*
X1310875Y678633D01*
X1310542Y678550D01*
X1310333Y678300D01*
X1310208Y678008D01*
Y676967D01*
G01Y678008D02*
X1309000Y678633D01*
G01X1309375Y679983D02*
X1309167Y680233D01*
X1309042Y680525D01*
X1309000Y680900D01*
X1309083Y681275D01*
X1309250Y681567D01*
X1309542Y681775D01*
X1309875Y681817D01*
X1310208Y681733D01*
X1310417Y681525D01*
X1310583Y681233D01*
X1310625Y680942D01*
X1310583Y680650D01*
X1310417Y680275D01*
X1311500Y680400D01*
Y681525D01*
G01X1309000Y683917D02*
X1309542Y684000D01*
X1310000Y684125D01*
X1310417Y684292D01*
X1310875Y684500D01*
X1311500Y684833D01*
Y683167D01*
G01X1310042Y686308D02*
X1310333Y686600D01*
X1310500Y686850D01*
X1310583Y687183D01*
X1310500Y687475D01*
X1310333Y687683D01*
X1310083Y687850D01*
X1309792Y687892D01*
X1309542Y687850D01*
X1309292Y687683D01*
X1309083Y687433D01*
X1309000Y687142D01*
X1309083Y686808D01*
X1309333Y686517D01*
X1309708Y686350D01*
X1310125Y686308D01*
X1310667Y686392D01*
X1310958Y686517D01*
X1311250Y686725D01*
X1311458Y687017D01*
X1311500Y687308D01*
X1311417Y687600D01*
X1311208Y687808D01*
G01X1309000Y690700D02*
X1311500D01*
X1309708Y689158D01*
Y691242D01*
G01X1303528Y678595D02*
X1303653Y678345D01*
X1303736Y678053D01*
Y677720D01*
X1303611Y677345D01*
X1303403Y677053D01*
X1303153Y676845D01*
X1302736Y676678D01*
X1302361Y676636D01*
X1301986Y676720D01*
X1301736Y676845D01*
X1301486Y677095D01*
X1301319Y677386D01*
X1301236Y677678D01*
Y677970D01*
X1301319Y678261D01*
X1301444Y678511D01*
X1301611Y678720D01*
G01X1301236Y680778D02*
X1301278Y681070D01*
X1301403Y681403D01*
X1301611Y681611D01*
X1301903Y681695D01*
X1302194Y681611D01*
X1302444Y681361D01*
X1302569Y680986D01*
Y680570D01*
X1302653Y680320D01*
X1302861Y680111D01*
X1303153Y680028D01*
X1303444Y680153D01*
X1303653Y680445D01*
X1303736Y680778D01*
X1303653Y681111D01*
X1303444Y681403D01*
X1303153Y681528D01*
X1302861Y681445D01*
X1302653Y681236D01*
X1302569Y680986D01*
Y680570D01*
X1302444Y680195D01*
X1302194Y679945D01*
X1301903Y679861D01*
X1301611Y679945D01*
X1301403Y680153D01*
X1301278Y680486D01*
X1301236Y680778D01*
G01X1303736Y683878D02*
X1303653Y683545D01*
X1303444Y683295D01*
X1303194Y683128D01*
X1302861Y683003D01*
X1302486Y682961D01*
X1302111Y683003D01*
X1301778Y683128D01*
X1301528Y683295D01*
X1301319Y683545D01*
X1301236Y683878D01*
X1301319Y684211D01*
X1301528Y684461D01*
X1301778Y684628D01*
X1302111Y684753D01*
X1302486Y684795D01*
X1302861Y684753D01*
X1303194Y684628D01*
X1303444Y684461D01*
X1303653Y684211D01*
X1303736Y683878D01*
G01X1301236Y686978D02*
X1301278Y687270D01*
X1301403Y687603D01*
X1301611Y687811D01*
X1301903Y687895D01*
X1302194Y687811D01*
X1302444Y687561D01*
X1302569Y687186D01*
Y686770D01*
X1302653Y686520D01*
X1302861Y686311D01*
X1303153Y686228D01*
X1303444Y686353D01*
X1303653Y686645D01*
X1303736Y686978D01*
X1303653Y687311D01*
X1303444Y687603D01*
X1303153Y687728D01*
X1302861Y687645D01*
X1302653Y687436D01*
X1302569Y687186D01*
Y686770D01*
X1302444Y686395D01*
X1302194Y686145D01*
X1301903Y686061D01*
X1301611Y686145D01*
X1301403Y686353D01*
X1301278Y686686D01*
X1301236Y686978D01*
G01Y690578D02*
X1303736D01*
X1301944Y689036D01*
Y691120D01*
G01X1301000Y693467D02*
X1303500D01*
Y694508D01*
X1303375Y694842D01*
X1303208Y695050D01*
X1302875Y695133D01*
X1302542Y695050D01*
X1302333Y694800D01*
X1302208Y694508D01*
Y693467D01*
G01Y694508D02*
X1301000Y695133D01*
G01X1301375Y696483D02*
X1301167Y696733D01*
X1301042Y697025D01*
X1301000Y697400D01*
X1301083Y697775D01*
X1301250Y698067D01*
X1301542Y698275D01*
X1301875Y698317D01*
X1302208Y698233D01*
X1302417Y698025D01*
X1302583Y697733D01*
X1302625Y697442D01*
X1302583Y697150D01*
X1302417Y696775D01*
X1303500Y696900D01*
Y698025D01*
G01X1301000Y700417D02*
X1301542Y700500D01*
X1302000Y700625D01*
X1302417Y700792D01*
X1302875Y701000D01*
X1303500Y701333D01*
Y699667D01*
G01X1301000Y703517D02*
X1301542Y703600D01*
X1302000Y703725D01*
X1302417Y703892D01*
X1302875Y704100D01*
X1303500Y704433D01*
Y702767D01*
G01X1301000Y706700D02*
X1303500D01*
X1303000Y706200D01*
G01X1301000D02*
Y707200D01*
G01X1309000Y695017D02*
X1311500D01*
Y696058D01*
X1311375Y696392D01*
X1311208Y696600D01*
X1310875Y696683D01*
X1310542Y696600D01*
X1310333Y696350D01*
X1310208Y696058D01*
Y695017D01*
G01Y696058D02*
X1309000Y696683D01*
G01Y699450D02*
X1311500D01*
X1309708Y697908D01*
Y699992D01*
G01X1309500Y701133D02*
X1309208Y701383D01*
X1309042Y701717D01*
X1309000Y702092D01*
X1309042Y702425D01*
X1309250Y702758D01*
X1309500Y702967D01*
X1309750Y703008D01*
X1310042Y702925D01*
X1310250Y702633D01*
X1310333Y702342D01*
Y701967D01*
G01Y702342D02*
X1310458Y702592D01*
X1310667Y702800D01*
X1310917Y702883D01*
X1311167Y702800D01*
X1311375Y702592D01*
X1311500Y702217D01*
X1311458Y701842D01*
X1311292Y701467D01*
G01X1309000Y705650D02*
X1311500D01*
X1309708Y704108D01*
Y706192D01*
G01X1307292Y695217D02*
X1307417Y694967D01*
X1307500Y694675D01*
Y694342D01*
X1307375Y693967D01*
X1307167Y693675D01*
X1306917Y693467D01*
X1306500Y693300D01*
X1306125Y693258D01*
X1305750Y693342D01*
X1305500Y693467D01*
X1305250Y693717D01*
X1305083Y694008D01*
X1305000Y694300D01*
Y694592D01*
X1305083Y694883D01*
X1305208Y695133D01*
X1305375Y695342D01*
G01X1305000Y697400D02*
X1305042Y697692D01*
X1305167Y698025D01*
X1305375Y698233D01*
X1305667Y698317D01*
X1305958Y698233D01*
X1306208Y697983D01*
X1306333Y697608D01*
Y697192D01*
X1306417Y696942D01*
X1306625Y696733D01*
X1306917Y696650D01*
X1307208Y696775D01*
X1307417Y697067D01*
X1307500Y697400D01*
X1307417Y697733D01*
X1307208Y698025D01*
X1306917Y698150D01*
X1306625Y698067D01*
X1306417Y697858D01*
X1306333Y697608D01*
Y697192D01*
X1306208Y696817D01*
X1305958Y696567D01*
X1305667Y696483D01*
X1305375Y696567D01*
X1305167Y696775D01*
X1305042Y697108D01*
X1305000Y697400D01*
G01X1307500Y700500D02*
X1307417Y700167D01*
X1307208Y699917D01*
X1306958Y699750D01*
X1306625Y699625D01*
X1306250Y699583D01*
X1305875Y699625D01*
X1305542Y699750D01*
X1305292Y699917D01*
X1305083Y700167D01*
X1305000Y700500D01*
X1305083Y700833D01*
X1305292Y701083D01*
X1305542Y701250D01*
X1305875Y701375D01*
X1306250Y701417D01*
X1306625Y701375D01*
X1306958Y701250D01*
X1307208Y701083D01*
X1307417Y700833D01*
X1307500Y700500D01*
G01X1305000Y703600D02*
X1305042Y703892D01*
X1305167Y704225D01*
X1305375Y704433D01*
X1305667Y704517D01*
X1305958Y704433D01*
X1306208Y704183D01*
X1306333Y703808D01*
Y703392D01*
X1306417Y703142D01*
X1306625Y702933D01*
X1306917Y702850D01*
X1307208Y702975D01*
X1307417Y703267D01*
X1307500Y703600D01*
X1307417Y703933D01*
X1307208Y704225D01*
X1306917Y704350D01*
X1306625Y704267D01*
X1306417Y704058D01*
X1306333Y703808D01*
Y703392D01*
X1306208Y703017D01*
X1305958Y702767D01*
X1305667Y702683D01*
X1305375Y702767D01*
X1305167Y702975D01*
X1305042Y703308D01*
X1305000Y703600D01*
G01Y706700D02*
X1305042Y706992D01*
X1305167Y707325D01*
X1305375Y707533D01*
X1305667Y707617D01*
X1305958Y707533D01*
X1306208Y707283D01*
X1306333Y706908D01*
Y706492D01*
X1306417Y706242D01*
X1306625Y706033D01*
X1306917Y705950D01*
X1307208Y706075D01*
X1307417Y706367D01*
X1307500Y706700D01*
X1307417Y707033D01*
X1307208Y707325D01*
X1306917Y707450D01*
X1306625Y707367D01*
X1306417Y707158D01*
X1306333Y706908D01*
Y706492D01*
X1306208Y706117D01*
X1305958Y705867D01*
X1305667Y705783D01*
X1305375Y705867D01*
X1305167Y706075D01*
X1305042Y706408D01*
X1305000Y706700D01*
G01X1309000Y709467D02*
X1311500D01*
Y710508D01*
X1311375Y710842D01*
X1311208Y711050D01*
X1310875Y711133D01*
X1310542Y711050D01*
X1310333Y710800D01*
X1310208Y710508D01*
Y709467D01*
G01Y710508D02*
X1309000Y711133D01*
G01X1309375Y712483D02*
X1309167Y712733D01*
X1309042Y713025D01*
X1309000Y713400D01*
X1309083Y713775D01*
X1309250Y714067D01*
X1309542Y714275D01*
X1309875Y714317D01*
X1310208Y714233D01*
X1310417Y714025D01*
X1310583Y713733D01*
X1310625Y713442D01*
X1310583Y713150D01*
X1310417Y712775D01*
X1311500Y712900D01*
Y714025D01*
G01X1309000Y716417D02*
X1309542Y716500D01*
X1310000Y716625D01*
X1310417Y716792D01*
X1310875Y717000D01*
X1311500Y717333D01*
Y715667D01*
G01X1310042Y718808D02*
X1310333Y719100D01*
X1310500Y719350D01*
X1310583Y719683D01*
X1310500Y719975D01*
X1310333Y720183D01*
X1310083Y720350D01*
X1309792Y720392D01*
X1309542Y720350D01*
X1309292Y720183D01*
X1309083Y719933D01*
X1309000Y719642D01*
X1309083Y719308D01*
X1309333Y719017D01*
X1309708Y718850D01*
X1310125Y718808D01*
X1310667Y718892D01*
X1310958Y719017D01*
X1311250Y719225D01*
X1311458Y719517D01*
X1311500Y719808D01*
X1311417Y720100D01*
X1311208Y720308D01*
G01X1309000Y722700D02*
X1309042Y722992D01*
X1309167Y723325D01*
X1309375Y723533D01*
X1309667Y723617D01*
X1309958Y723533D01*
X1310208Y723283D01*
X1310333Y722908D01*
Y722492D01*
X1310417Y722242D01*
X1310625Y722033D01*
X1310917Y721950D01*
X1311208Y722075D01*
X1311417Y722367D01*
X1311500Y722700D01*
X1311417Y723033D01*
X1311208Y723325D01*
X1310917Y723450D01*
X1310625Y723367D01*
X1310417Y723158D01*
X1310333Y722908D01*
Y722492D01*
X1310208Y722117D01*
X1309958Y721867D01*
X1309667Y721783D01*
X1309375Y721867D01*
X1309167Y722075D01*
X1309042Y722408D01*
X1309000Y722700D01*
G01X1301000Y709467D02*
X1303500D01*
Y710508D01*
X1303375Y710842D01*
X1303208Y711050D01*
X1302875Y711133D01*
X1302542Y711050D01*
X1302333Y710800D01*
X1302208Y710508D01*
Y709467D01*
G01Y710508D02*
X1301000Y711133D01*
G01X1301375Y712483D02*
X1301167Y712733D01*
X1301042Y713025D01*
X1301000Y713400D01*
X1301083Y713775D01*
X1301250Y714067D01*
X1301542Y714275D01*
X1301875Y714317D01*
X1302208Y714233D01*
X1302417Y714025D01*
X1302583Y713733D01*
X1302625Y713442D01*
X1302583Y713150D01*
X1302417Y712775D01*
X1303500Y712900D01*
Y714025D01*
G01X1301000Y716417D02*
X1301542Y716500D01*
X1302000Y716625D01*
X1302417Y716792D01*
X1302875Y717000D01*
X1303500Y717333D01*
Y715667D01*
G01X1301000Y719517D02*
X1301542Y719600D01*
X1302000Y719725D01*
X1302417Y719892D01*
X1302875Y720100D01*
X1303500Y720433D01*
Y718767D01*
G01Y722700D02*
X1303417Y722367D01*
X1303208Y722117D01*
X1302958Y721950D01*
X1302625Y721825D01*
X1302250Y721783D01*
X1301875Y721825D01*
X1301542Y721950D01*
X1301292Y722117D01*
X1301083Y722367D01*
X1301000Y722700D01*
X1301083Y723033D01*
X1301292Y723283D01*
X1301542Y723450D01*
X1301875Y723575D01*
X1302250Y723617D01*
X1302625Y723575D01*
X1302958Y723450D01*
X1303208Y723283D01*
X1303417Y723033D01*
X1303500Y722700D01*
G01X1307292Y711217D02*
X1307417Y710967D01*
X1307500Y710675D01*
Y710342D01*
X1307375Y709967D01*
X1307167Y709675D01*
X1306917Y709467D01*
X1306500Y709300D01*
X1306125Y709258D01*
X1305750Y709342D01*
X1305500Y709467D01*
X1305250Y709717D01*
X1305083Y710008D01*
X1305000Y710300D01*
Y710592D01*
X1305083Y710883D01*
X1305208Y711133D01*
X1305375Y711342D01*
G01X1305000Y713400D02*
X1305042Y713692D01*
X1305167Y714025D01*
X1305375Y714233D01*
X1305667Y714317D01*
X1305958Y714233D01*
X1306208Y713983D01*
X1306333Y713608D01*
Y713192D01*
X1306417Y712942D01*
X1306625Y712733D01*
X1306917Y712650D01*
X1307208Y712775D01*
X1307417Y713067D01*
X1307500Y713400D01*
X1307417Y713733D01*
X1307208Y714025D01*
X1306917Y714150D01*
X1306625Y714067D01*
X1306417Y713858D01*
X1306333Y713608D01*
Y713192D01*
X1306208Y712817D01*
X1305958Y712567D01*
X1305667Y712483D01*
X1305375Y712567D01*
X1305167Y712775D01*
X1305042Y713108D01*
X1305000Y713400D01*
G01X1307500Y716500D02*
X1307417Y716167D01*
X1307208Y715917D01*
X1306958Y715750D01*
X1306625Y715625D01*
X1306250Y715583D01*
X1305875Y715625D01*
X1305542Y715750D01*
X1305292Y715917D01*
X1305083Y716167D01*
X1305000Y716500D01*
X1305083Y716833D01*
X1305292Y717083D01*
X1305542Y717250D01*
X1305875Y717375D01*
X1306250Y717417D01*
X1306625Y717375D01*
X1306958Y717250D01*
X1307208Y717083D01*
X1307417Y716833D01*
X1307500Y716500D01*
G01X1305000Y719600D02*
X1305042Y719892D01*
X1305167Y720225D01*
X1305375Y720433D01*
X1305667Y720517D01*
X1305958Y720433D01*
X1306208Y720183D01*
X1306333Y719808D01*
Y719392D01*
X1306417Y719142D01*
X1306625Y718933D01*
X1306917Y718850D01*
X1307208Y718975D01*
X1307417Y719267D01*
X1307500Y719600D01*
X1307417Y719933D01*
X1307208Y720225D01*
X1306917Y720350D01*
X1306625Y720267D01*
X1306417Y720058D01*
X1306333Y719808D01*
Y719392D01*
X1306208Y719017D01*
X1305958Y718767D01*
X1305667Y718683D01*
X1305375Y718767D01*
X1305167Y718975D01*
X1305042Y719308D01*
X1305000Y719600D01*
G01Y722617D02*
X1305542Y722700D01*
X1306000Y722825D01*
X1306417Y722992D01*
X1306875Y723200D01*
X1307500Y723533D01*
Y721867D01*
G01X1313500Y726467D02*
X1316000D01*
Y727508D01*
X1315875Y727842D01*
X1315708Y728050D01*
X1315375Y728133D01*
X1315042Y728050D01*
X1314833Y727800D01*
X1314708Y727508D01*
Y726467D01*
G01Y727508D02*
X1313500Y728133D01*
G01X1314000Y729483D02*
X1313708Y729733D01*
X1313542Y730067D01*
X1313500Y730442D01*
X1313542Y730775D01*
X1313750Y731108D01*
X1314000Y731317D01*
X1314250Y731358D01*
X1314542Y731275D01*
X1314750Y730983D01*
X1314833Y730692D01*
Y730317D01*
G01Y730692D02*
X1314958Y730942D01*
X1315167Y731150D01*
X1315417Y731233D01*
X1315667Y731150D01*
X1315875Y730942D01*
X1316000Y730567D01*
X1315958Y730192D01*
X1315792Y729817D01*
G01X1316000Y733500D02*
X1315917Y733167D01*
X1315708Y732917D01*
X1315458Y732750D01*
X1315125Y732625D01*
X1314750Y732583D01*
X1314375Y732625D01*
X1314042Y732750D01*
X1313792Y732917D01*
X1313583Y733167D01*
X1313500Y733500D01*
X1313583Y733833D01*
X1313792Y734083D01*
X1314042Y734250D01*
X1314375Y734375D01*
X1314750Y734417D01*
X1315125Y734375D01*
X1315458Y734250D01*
X1315708Y734083D01*
X1315917Y733833D01*
X1316000Y733500D01*
G01X1315583Y735808D02*
X1315833Y736058D01*
X1315958Y736350D01*
X1316000Y736683D01*
X1315917Y737100D01*
X1315708Y737392D01*
X1315458Y737475D01*
X1315208Y737433D01*
X1315000Y737267D01*
X1314583Y736433D01*
X1314292Y736058D01*
X1313875Y735808D01*
X1313500Y735725D01*
Y737475D01*
G01X1313792Y738992D02*
X1313583Y739283D01*
X1313500Y739617D01*
X1313583Y739950D01*
X1313833Y740242D01*
X1314208Y740450D01*
X1314583Y740533D01*
X1315042D01*
X1315417Y740450D01*
X1315750Y740242D01*
X1315917Y739992D01*
X1316000Y739700D01*
X1315917Y739367D01*
X1315750Y739117D01*
X1315500Y738950D01*
X1315167Y738867D01*
X1314875Y738950D01*
X1314583Y739158D01*
X1314417Y739408D01*
X1314375Y739700D01*
X1314458Y740033D01*
X1314667Y740283D01*
X1315042Y740533D01*
G01X1309500Y726467D02*
X1312000D01*
Y727508D01*
X1311875Y727842D01*
X1311708Y728050D01*
X1311375Y728133D01*
X1311042Y728050D01*
X1310833Y727800D01*
X1310708Y727508D01*
Y726467D01*
G01Y727508D02*
X1309500Y728133D01*
G01X1309875Y729483D02*
X1309667Y729733D01*
X1309542Y730025D01*
X1309500Y730400D01*
X1309583Y730775D01*
X1309750Y731067D01*
X1310042Y731275D01*
X1310375Y731317D01*
X1310708Y731233D01*
X1310917Y731025D01*
X1311083Y730733D01*
X1311125Y730442D01*
X1311083Y730150D01*
X1310917Y729775D01*
X1312000Y729900D01*
Y731025D01*
G01X1309500Y733417D02*
X1310042Y733500D01*
X1310500Y733625D01*
X1310917Y733792D01*
X1311375Y734000D01*
X1312000Y734333D01*
Y732667D01*
G01X1310542Y735808D02*
X1310833Y736100D01*
X1311000Y736350D01*
X1311083Y736683D01*
X1311000Y736975D01*
X1310833Y737183D01*
X1310583Y737350D01*
X1310292Y737392D01*
X1310042Y737350D01*
X1309792Y737183D01*
X1309583Y736933D01*
X1309500Y736642D01*
X1309583Y736308D01*
X1309833Y736017D01*
X1310208Y735850D01*
X1310625Y735808D01*
X1311167Y735892D01*
X1311458Y736017D01*
X1311750Y736225D01*
X1311958Y736517D01*
X1312000Y736808D01*
X1311917Y737100D01*
X1311708Y737308D01*
G01X1311583Y738908D02*
X1311833Y739158D01*
X1311958Y739450D01*
X1312000Y739783D01*
X1311917Y740200D01*
X1311708Y740492D01*
X1311458Y740575D01*
X1311208Y740533D01*
X1311000Y740367D01*
X1310583Y739533D01*
X1310292Y739158D01*
X1309875Y738908D01*
X1309500Y738825D01*
Y740575D01*
G01X1307792Y728217D02*
X1307917Y727967D01*
X1308000Y727675D01*
Y727342D01*
X1307875Y726967D01*
X1307667Y726675D01*
X1307417Y726467D01*
X1307000Y726300D01*
X1306625Y726258D01*
X1306250Y726342D01*
X1306000Y726467D01*
X1305750Y726717D01*
X1305583Y727008D01*
X1305500Y727300D01*
Y727592D01*
X1305583Y727883D01*
X1305708Y728133D01*
X1305875Y728342D01*
G01X1305500Y730400D02*
X1305542Y730692D01*
X1305667Y731025D01*
X1305875Y731233D01*
X1306167Y731317D01*
X1306458Y731233D01*
X1306708Y730983D01*
X1306833Y730608D01*
Y730192D01*
X1306917Y729942D01*
X1307125Y729733D01*
X1307417Y729650D01*
X1307708Y729775D01*
X1307917Y730067D01*
X1308000Y730400D01*
X1307917Y730733D01*
X1307708Y731025D01*
X1307417Y731150D01*
X1307125Y731067D01*
X1306917Y730858D01*
X1306833Y730608D01*
Y730192D01*
X1306708Y729817D01*
X1306458Y729567D01*
X1306167Y729483D01*
X1305875Y729567D01*
X1305667Y729775D01*
X1305542Y730108D01*
X1305500Y730400D01*
G01X1308000Y733500D02*
X1307917Y733167D01*
X1307708Y732917D01*
X1307458Y732750D01*
X1307125Y732625D01*
X1306750Y732583D01*
X1306375Y732625D01*
X1306042Y732750D01*
X1305792Y732917D01*
X1305583Y733167D01*
X1305500Y733500D01*
X1305583Y733833D01*
X1305792Y734083D01*
X1306042Y734250D01*
X1306375Y734375D01*
X1306750Y734417D01*
X1307125Y734375D01*
X1307458Y734250D01*
X1307708Y734083D01*
X1307917Y733833D01*
X1308000Y733500D01*
G01X1305500Y736600D02*
X1305542Y736892D01*
X1305667Y737225D01*
X1305875Y737433D01*
X1306167Y737517D01*
X1306458Y737433D01*
X1306708Y737183D01*
X1306833Y736808D01*
Y736392D01*
X1306917Y736142D01*
X1307125Y735933D01*
X1307417Y735850D01*
X1307708Y735975D01*
X1307917Y736267D01*
X1308000Y736600D01*
X1307917Y736933D01*
X1307708Y737225D01*
X1307417Y737350D01*
X1307125Y737267D01*
X1306917Y737058D01*
X1306833Y736808D01*
Y736392D01*
X1306708Y736017D01*
X1306458Y735767D01*
X1306167Y735683D01*
X1305875Y735767D01*
X1305667Y735975D01*
X1305542Y736308D01*
X1305500Y736600D01*
G01X1306000Y738783D02*
X1305708Y739033D01*
X1305542Y739367D01*
X1305500Y739742D01*
X1305542Y740075D01*
X1305750Y740408D01*
X1306000Y740617D01*
X1306250Y740658D01*
X1306542Y740575D01*
X1306750Y740283D01*
X1306833Y739992D01*
Y739617D01*
G01Y739992D02*
X1306958Y740242D01*
X1307167Y740450D01*
X1307417Y740533D01*
X1307667Y740450D01*
X1307875Y740242D01*
X1308000Y739867D01*
X1307958Y739492D01*
X1307792Y739117D01*
G01X1309500Y742967D02*
X1312000D01*
Y744008D01*
X1311875Y744342D01*
X1311708Y744550D01*
X1311375Y744633D01*
X1311042Y744550D01*
X1310833Y744300D01*
X1310708Y744008D01*
Y742967D01*
G01Y744008D02*
X1309500Y744633D01*
G01X1310000Y745983D02*
X1309708Y746233D01*
X1309542Y746567D01*
X1309500Y746942D01*
X1309542Y747275D01*
X1309750Y747608D01*
X1310000Y747817D01*
X1310250Y747858D01*
X1310542Y747775D01*
X1310750Y747483D01*
X1310833Y747192D01*
Y746817D01*
G01Y747192D02*
X1310958Y747442D01*
X1311167Y747650D01*
X1311417Y747733D01*
X1311667Y747650D01*
X1311875Y747442D01*
X1312000Y747067D01*
X1311958Y746692D01*
X1311792Y746317D01*
G01X1309500Y750000D02*
X1312000D01*
X1311500Y749500D01*
G01X1309500D02*
Y750500D01*
G01X1312000Y753100D02*
X1311917Y752767D01*
X1311708Y752517D01*
X1311458Y752350D01*
X1311125Y752225D01*
X1310750Y752183D01*
X1310375Y752225D01*
X1310042Y752350D01*
X1309792Y752517D01*
X1309583Y752767D01*
X1309500Y753100D01*
X1309583Y753433D01*
X1309792Y753683D01*
X1310042Y753850D01*
X1310375Y753975D01*
X1310750Y754017D01*
X1311125Y753975D01*
X1311458Y753850D01*
X1311708Y753683D01*
X1311917Y753433D01*
X1312000Y753100D01*
G01Y756200D02*
X1311917Y755867D01*
X1311708Y755617D01*
X1311458Y755450D01*
X1311125Y755325D01*
X1310750Y755283D01*
X1310375Y755325D01*
X1310042Y755450D01*
X1309792Y755617D01*
X1309583Y755867D01*
X1309500Y756200D01*
X1309583Y756533D01*
X1309792Y756783D01*
X1310042Y756950D01*
X1310375Y757075D01*
X1310750Y757117D01*
X1311125Y757075D01*
X1311458Y756950D01*
X1311708Y756783D01*
X1311917Y756533D01*
X1312000Y756200D01*
G01X1313500Y742967D02*
X1316000D01*
Y744008D01*
X1315875Y744342D01*
X1315708Y744550D01*
X1315375Y744633D01*
X1315042Y744550D01*
X1314833Y744300D01*
X1314708Y744008D01*
Y742967D01*
G01Y744008D02*
X1313500Y744633D01*
G01X1313875Y745983D02*
X1313667Y746233D01*
X1313542Y746525D01*
X1313500Y746900D01*
X1313583Y747275D01*
X1313750Y747567D01*
X1314042Y747775D01*
X1314375Y747817D01*
X1314708Y747733D01*
X1314917Y747525D01*
X1315083Y747233D01*
X1315125Y746942D01*
X1315083Y746650D01*
X1314917Y746275D01*
X1316000Y746400D01*
Y747525D01*
G01X1313500Y749917D02*
X1314042Y750000D01*
X1314500Y750125D01*
X1314917Y750292D01*
X1315375Y750500D01*
X1316000Y750833D01*
Y749167D01*
G01X1314542Y752308D02*
X1314833Y752600D01*
X1315000Y752850D01*
X1315083Y753183D01*
X1315000Y753475D01*
X1314833Y753683D01*
X1314583Y753850D01*
X1314292Y753892D01*
X1314042Y753850D01*
X1313792Y753683D01*
X1313583Y753433D01*
X1313500Y753142D01*
X1313583Y752808D01*
X1313833Y752517D01*
X1314208Y752350D01*
X1314625Y752308D01*
X1315167Y752392D01*
X1315458Y752517D01*
X1315750Y752725D01*
X1315958Y753017D01*
X1316000Y753308D01*
X1315917Y753600D01*
X1315708Y753808D01*
G01X1314000Y755283D02*
X1313708Y755533D01*
X1313542Y755867D01*
X1313500Y756242D01*
X1313542Y756575D01*
X1313750Y756908D01*
X1314000Y757117D01*
X1314250Y757158D01*
X1314542Y757075D01*
X1314750Y756783D01*
X1314833Y756492D01*
Y756117D01*
G01Y756492D02*
X1314958Y756742D01*
X1315167Y756950D01*
X1315417Y757033D01*
X1315667Y756950D01*
X1315875Y756742D01*
X1316000Y756367D01*
X1315958Y755992D01*
X1315792Y755617D01*
G01X1307792Y744717D02*
X1307917Y744467D01*
X1308000Y744175D01*
Y743842D01*
X1307875Y743467D01*
X1307667Y743175D01*
X1307417Y742967D01*
X1307000Y742800D01*
X1306625Y742758D01*
X1306250Y742842D01*
X1306000Y742967D01*
X1305750Y743217D01*
X1305583Y743508D01*
X1305500Y743800D01*
Y744092D01*
X1305583Y744383D01*
X1305708Y744633D01*
X1305875Y744842D01*
G01X1305500Y746900D02*
X1305542Y747192D01*
X1305667Y747525D01*
X1305875Y747733D01*
X1306167Y747817D01*
X1306458Y747733D01*
X1306708Y747483D01*
X1306833Y747108D01*
Y746692D01*
X1306917Y746442D01*
X1307125Y746233D01*
X1307417Y746150D01*
X1307708Y746275D01*
X1307917Y746567D01*
X1308000Y746900D01*
X1307917Y747233D01*
X1307708Y747525D01*
X1307417Y747650D01*
X1307125Y747567D01*
X1306917Y747358D01*
X1306833Y747108D01*
Y746692D01*
X1306708Y746317D01*
X1306458Y746067D01*
X1306167Y745983D01*
X1305875Y746067D01*
X1305667Y746275D01*
X1305542Y746608D01*
X1305500Y746900D01*
G01X1308000Y750000D02*
X1307917Y749667D01*
X1307708Y749417D01*
X1307458Y749250D01*
X1307125Y749125D01*
X1306750Y749083D01*
X1306375Y749125D01*
X1306042Y749250D01*
X1305792Y749417D01*
X1305583Y749667D01*
X1305500Y750000D01*
X1305583Y750333D01*
X1305792Y750583D01*
X1306042Y750750D01*
X1306375Y750875D01*
X1306750Y750917D01*
X1307125Y750875D01*
X1307458Y750750D01*
X1307708Y750583D01*
X1307917Y750333D01*
X1308000Y750000D01*
G01X1305500Y753100D02*
X1305542Y753392D01*
X1305667Y753725D01*
X1305875Y753933D01*
X1306167Y754017D01*
X1306458Y753933D01*
X1306708Y753683D01*
X1306833Y753308D01*
Y752892D01*
X1306917Y752642D01*
X1307125Y752433D01*
X1307417Y752350D01*
X1307708Y752475D01*
X1307917Y752767D01*
X1308000Y753100D01*
X1307917Y753433D01*
X1307708Y753725D01*
X1307417Y753850D01*
X1307125Y753767D01*
X1306917Y753558D01*
X1306833Y753308D01*
Y752892D01*
X1306708Y752517D01*
X1306458Y752267D01*
X1306167Y752183D01*
X1305875Y752267D01*
X1305667Y752475D01*
X1305542Y752808D01*
X1305500Y753100D01*
G01Y756200D02*
X1308000D01*
X1307500Y755700D01*
G01X1305500D02*
Y756700D01*
G01X1329300Y513312D02*
Y515812D01*
X1328259D01*
X1327925Y515687D01*
X1327717Y515520D01*
X1327634Y515187D01*
X1327717Y514854D01*
X1327967Y514645D01*
X1328259Y514520D01*
X1329300D01*
G01X1328259D02*
X1327634Y513312D01*
G01X1326284Y513687D02*
X1326034Y513479D01*
X1325742Y513354D01*
X1325367Y513312D01*
X1324992Y513395D01*
X1324700Y513562D01*
X1324492Y513854D01*
X1324450Y514187D01*
X1324534Y514520D01*
X1324742Y514729D01*
X1325034Y514895D01*
X1325325Y514937D01*
X1325617Y514895D01*
X1325992Y514729D01*
X1325867Y515812D01*
X1324742D01*
G01X1323184Y513687D02*
X1322934Y513479D01*
X1322642Y513354D01*
X1322267Y513312D01*
X1321892Y513395D01*
X1321600Y513562D01*
X1321392Y513854D01*
X1321350Y514187D01*
X1321434Y514520D01*
X1321642Y514729D01*
X1321934Y514895D01*
X1322225Y514937D01*
X1322517Y514895D01*
X1322892Y514729D01*
X1322767Y515812D01*
X1321642D01*
G01X1319250Y513312D02*
X1319167Y513854D01*
X1319042Y514312D01*
X1318875Y514729D01*
X1318667Y515187D01*
X1318334Y515812D01*
X1320000D01*
G01X1329300Y505312D02*
Y507812D01*
X1328259D01*
X1327925Y507687D01*
X1327717Y507520D01*
X1327634Y507187D01*
X1327717Y506854D01*
X1327967Y506645D01*
X1328259Y506520D01*
X1329300D01*
G01X1328259D02*
X1327634Y505312D01*
G01X1326284Y505687D02*
X1326034Y505479D01*
X1325742Y505354D01*
X1325367Y505312D01*
X1324992Y505395D01*
X1324700Y505562D01*
X1324492Y505854D01*
X1324450Y506187D01*
X1324534Y506520D01*
X1324742Y506729D01*
X1325034Y506895D01*
X1325325Y506937D01*
X1325617Y506895D01*
X1325992Y506729D01*
X1325867Y507812D01*
X1324742D01*
G01X1323184Y505687D02*
X1322934Y505479D01*
X1322642Y505354D01*
X1322267Y505312D01*
X1321892Y505395D01*
X1321600Y505562D01*
X1321392Y505854D01*
X1321350Y506187D01*
X1321434Y506520D01*
X1321642Y506729D01*
X1321934Y506895D01*
X1322225Y506937D01*
X1322517Y506895D01*
X1322892Y506729D01*
X1322767Y507812D01*
X1321642D01*
G01X1319167Y505312D02*
Y507812D01*
X1319667Y507312D01*
G01Y505312D02*
X1318667D01*
G01X1318792Y608867D02*
X1318917Y608617D01*
X1319000Y608325D01*
Y607992D01*
X1318875Y607617D01*
X1318667Y607325D01*
X1318417Y607117D01*
X1318000Y606950D01*
X1317625Y606908D01*
X1317250Y606992D01*
X1317000Y607117D01*
X1316750Y607367D01*
X1316583Y607658D01*
X1316500Y607950D01*
Y608242D01*
X1316583Y608533D01*
X1316708Y608783D01*
X1316875Y608992D01*
G01X1317000Y610133D02*
X1316708Y610383D01*
X1316542Y610717D01*
X1316500Y611092D01*
X1316542Y611425D01*
X1316750Y611758D01*
X1317000Y611967D01*
X1317250Y612008D01*
X1317542Y611925D01*
X1317750Y611633D01*
X1317833Y611342D01*
Y610967D01*
G01Y611342D02*
X1317958Y611592D01*
X1318167Y611800D01*
X1318417Y611883D01*
X1318667Y611800D01*
X1318875Y611592D01*
X1319000Y611217D01*
X1318958Y610842D01*
X1318792Y610467D01*
G01X1346200Y401500D02*
Y397500D01*
X1338800D01*
G01X1347983Y387000D02*
Y389500D01*
X1346983D01*
X1346650Y389375D01*
X1346400Y389083D01*
X1346317Y388750D01*
X1346400Y388417D01*
X1346608Y388167D01*
X1346983Y388042D01*
X1347983D01*
G01X1343133Y389292D02*
X1343383Y389417D01*
X1343675Y389500D01*
X1344008D01*
X1344383Y389375D01*
X1344675Y389167D01*
X1344883Y388917D01*
X1345050Y388500D01*
X1345092Y388125D01*
X1345008Y387750D01*
X1344883Y387500D01*
X1344633Y387250D01*
X1344342Y387083D01*
X1344050Y387000D01*
X1343758D01*
X1343467Y387083D01*
X1343217Y387208D01*
X1343008Y387375D01*
G01X1340950Y387000D02*
Y389500D01*
X1341450Y389000D01*
G01Y387000D02*
X1340450D01*
G01X1337350D02*
Y389500D01*
X1338892Y387708D01*
X1336808D01*
G01X1347983Y405000D02*
Y407500D01*
X1346983D01*
X1346650Y407375D01*
X1346400Y407083D01*
X1346317Y406750D01*
X1346400Y406417D01*
X1346608Y406167D01*
X1346983Y406042D01*
X1347983D01*
G01X1344883Y405000D02*
Y407500D01*
X1343842D01*
X1343508Y407375D01*
X1343300Y407208D01*
X1343217Y406875D01*
X1343300Y406542D01*
X1343550Y406333D01*
X1343842Y406208D01*
X1344883D01*
G01X1343842D02*
X1343217Y405000D01*
G01X1340950D02*
Y407500D01*
X1341450Y407000D01*
G01Y405000D02*
X1340450D01*
G01X1337350D02*
Y407500D01*
X1338892Y405708D01*
X1336808D01*
G01X1342800Y513312D02*
Y515812D01*
X1341759D01*
X1341425Y515687D01*
X1341217Y515520D01*
X1341134Y515187D01*
X1341217Y514854D01*
X1341467Y514645D01*
X1341759Y514520D01*
X1342800D01*
G01X1341759D02*
X1341134Y513312D01*
G01X1339784Y513687D02*
X1339534Y513479D01*
X1339242Y513354D01*
X1338867Y513312D01*
X1338492Y513395D01*
X1338200Y513562D01*
X1337992Y513854D01*
X1337950Y514187D01*
X1338034Y514520D01*
X1338242Y514729D01*
X1338534Y514895D01*
X1338825Y514937D01*
X1339117Y514895D01*
X1339492Y514729D01*
X1339367Y515812D01*
X1338242D01*
G01X1336684Y513687D02*
X1336434Y513479D01*
X1336142Y513354D01*
X1335767Y513312D01*
X1335392Y513395D01*
X1335100Y513562D01*
X1334892Y513854D01*
X1334850Y514187D01*
X1334934Y514520D01*
X1335142Y514729D01*
X1335434Y514895D01*
X1335725Y514937D01*
X1336017Y514895D01*
X1336392Y514729D01*
X1336267Y515812D01*
X1335142D01*
G01X1333375Y513604D02*
X1333084Y513395D01*
X1332750Y513312D01*
X1332417Y513395D01*
X1332125Y513645D01*
X1331917Y514020D01*
X1331834Y514395D01*
Y514854D01*
X1331917Y515229D01*
X1332125Y515562D01*
X1332375Y515729D01*
X1332667Y515812D01*
X1333000Y515729D01*
X1333250Y515562D01*
X1333417Y515312D01*
X1333500Y514979D01*
X1333417Y514687D01*
X1333209Y514395D01*
X1332959Y514229D01*
X1332667Y514187D01*
X1332334Y514270D01*
X1332084Y514479D01*
X1331834Y514854D01*
G01X1356800Y513312D02*
Y515812D01*
X1355759D01*
X1355425Y515687D01*
X1355217Y515520D01*
X1355134Y515187D01*
X1355217Y514854D01*
X1355467Y514645D01*
X1355759Y514520D01*
X1356800D01*
G01X1355759D02*
X1355134Y513312D01*
G01X1353784Y513687D02*
X1353534Y513479D01*
X1353242Y513354D01*
X1352867Y513312D01*
X1352492Y513395D01*
X1352200Y513562D01*
X1351992Y513854D01*
X1351950Y514187D01*
X1352034Y514520D01*
X1352242Y514729D01*
X1352534Y514895D01*
X1352825Y514937D01*
X1353117Y514895D01*
X1353492Y514729D01*
X1353367Y515812D01*
X1352242D01*
G01X1350684Y513687D02*
X1350434Y513479D01*
X1350142Y513354D01*
X1349767Y513312D01*
X1349392Y513395D01*
X1349100Y513562D01*
X1348892Y513854D01*
X1348850Y514187D01*
X1348934Y514520D01*
X1349142Y514729D01*
X1349434Y514895D01*
X1349725Y514937D01*
X1350017Y514895D01*
X1350392Y514729D01*
X1350267Y515812D01*
X1349142D01*
G01X1347459Y514354D02*
X1347167Y514645D01*
X1346917Y514812D01*
X1346584Y514895D01*
X1346292Y514812D01*
X1346084Y514645D01*
X1345917Y514395D01*
X1345875Y514104D01*
X1345917Y513854D01*
X1346084Y513604D01*
X1346334Y513395D01*
X1346625Y513312D01*
X1346959Y513395D01*
X1347250Y513645D01*
X1347417Y514020D01*
X1347459Y514437D01*
X1347375Y514979D01*
X1347250Y515270D01*
X1347042Y515562D01*
X1346750Y515770D01*
X1346459Y515812D01*
X1346167Y515729D01*
X1345959Y515520D01*
G01X1342800Y505312D02*
Y507812D01*
X1341759D01*
X1341425Y507687D01*
X1341217Y507520D01*
X1341134Y507187D01*
X1341217Y506854D01*
X1341467Y506645D01*
X1341759Y506520D01*
X1342800D01*
G01X1341759D02*
X1341134Y505312D01*
G01X1339784Y505687D02*
X1339534Y505479D01*
X1339242Y505354D01*
X1338867Y505312D01*
X1338492Y505395D01*
X1338200Y505562D01*
X1337992Y505854D01*
X1337950Y506187D01*
X1338034Y506520D01*
X1338242Y506729D01*
X1338534Y506895D01*
X1338825Y506937D01*
X1339117Y506895D01*
X1339492Y506729D01*
X1339367Y507812D01*
X1338242D01*
G01X1336684Y505687D02*
X1336434Y505479D01*
X1336142Y505354D01*
X1335767Y505312D01*
X1335392Y505395D01*
X1335100Y505562D01*
X1334892Y505854D01*
X1334850Y506187D01*
X1334934Y506520D01*
X1335142Y506729D01*
X1335434Y506895D01*
X1335725Y506937D01*
X1336017Y506895D01*
X1336392Y506729D01*
X1336267Y507812D01*
X1335142D01*
G01X1333584Y505687D02*
X1333334Y505479D01*
X1333042Y505354D01*
X1332667Y505312D01*
X1332292Y505395D01*
X1332000Y505562D01*
X1331792Y505854D01*
X1331750Y506187D01*
X1331834Y506520D01*
X1332042Y506729D01*
X1332334Y506895D01*
X1332625Y506937D01*
X1332917Y506895D01*
X1333292Y506729D01*
X1333167Y507812D01*
X1332042D01*
G01X1356800Y505312D02*
Y507812D01*
X1355759D01*
X1355425Y507687D01*
X1355217Y507520D01*
X1355134Y507187D01*
X1355217Y506854D01*
X1355467Y506645D01*
X1355759Y506520D01*
X1356800D01*
G01X1355759D02*
X1355134Y505312D01*
G01X1353784Y505687D02*
X1353534Y505479D01*
X1353242Y505354D01*
X1352867Y505312D01*
X1352492Y505395D01*
X1352200Y505562D01*
X1351992Y505854D01*
X1351950Y506187D01*
X1352034Y506520D01*
X1352242Y506729D01*
X1352534Y506895D01*
X1352825Y506937D01*
X1353117Y506895D01*
X1353492Y506729D01*
X1353367Y507812D01*
X1352242D01*
G01X1350684Y505687D02*
X1350434Y505479D01*
X1350142Y505354D01*
X1349767Y505312D01*
X1349392Y505395D01*
X1349100Y505562D01*
X1348892Y505854D01*
X1348850Y506187D01*
X1348934Y506520D01*
X1349142Y506729D01*
X1349434Y506895D01*
X1349725Y506937D01*
X1350017Y506895D01*
X1350392Y506729D01*
X1350267Y507812D01*
X1349142D01*
G01X1346167Y505312D02*
Y507812D01*
X1347709Y506020D01*
X1345625D01*
G01X1348084Y286368D02*
X1352084D01*
Y278968D01*
G01X1360584D02*
X1356584D01*
Y286368D01*
G01X1349084Y288685D02*
X1351584D01*
Y289726D01*
X1351459Y290060D01*
X1351292Y290268D01*
X1350959Y290351D01*
X1350626Y290268D01*
X1350417Y290018D01*
X1350292Y289726D01*
Y288685D01*
G01Y289726D02*
X1349084Y290351D01*
G01X1351167Y291826D02*
X1351417Y292076D01*
X1351542Y292368D01*
X1351584Y292701D01*
X1351501Y293118D01*
X1351292Y293410D01*
X1351042Y293493D01*
X1350792Y293451D01*
X1350584Y293285D01*
X1350167Y292451D01*
X1349876Y292076D01*
X1349459Y291826D01*
X1349084Y291743D01*
Y293493D01*
G01X1350126Y294926D02*
X1350417Y295218D01*
X1350584Y295468D01*
X1350667Y295801D01*
X1350584Y296093D01*
X1350417Y296301D01*
X1350167Y296468D01*
X1349876Y296510D01*
X1349626Y296468D01*
X1349376Y296301D01*
X1349167Y296051D01*
X1349084Y295760D01*
X1349167Y295426D01*
X1349417Y295135D01*
X1349792Y294968D01*
X1350209Y294926D01*
X1350751Y295010D01*
X1351042Y295135D01*
X1351334Y295343D01*
X1351542Y295635D01*
X1351584Y295926D01*
X1351501Y296218D01*
X1351292Y296426D01*
G01X1349459Y297901D02*
X1349251Y298151D01*
X1349126Y298443D01*
X1349084Y298818D01*
X1349167Y299193D01*
X1349334Y299485D01*
X1349626Y299693D01*
X1349959Y299735D01*
X1350292Y299651D01*
X1350501Y299443D01*
X1350667Y299151D01*
X1350709Y298860D01*
X1350667Y298568D01*
X1350501Y298193D01*
X1351584Y298318D01*
Y299443D01*
G01X1357584Y288685D02*
X1360084D01*
Y289726D01*
X1359959Y290060D01*
X1359792Y290268D01*
X1359459Y290351D01*
X1359126Y290268D01*
X1358917Y290018D01*
X1358792Y289726D01*
Y288685D01*
G01Y289726D02*
X1357584Y290351D01*
G01X1359667Y291826D02*
X1359917Y292076D01*
X1360042Y292368D01*
X1360084Y292701D01*
X1360001Y293118D01*
X1359792Y293410D01*
X1359542Y293493D01*
X1359292Y293451D01*
X1359084Y293285D01*
X1358667Y292451D01*
X1358376Y292076D01*
X1357959Y291826D01*
X1357584Y291743D01*
Y293493D01*
G01X1358626Y294926D02*
X1358917Y295218D01*
X1359084Y295468D01*
X1359167Y295801D01*
X1359084Y296093D01*
X1358917Y296301D01*
X1358667Y296468D01*
X1358376Y296510D01*
X1358126Y296468D01*
X1357876Y296301D01*
X1357667Y296051D01*
X1357584Y295760D01*
X1357667Y295426D01*
X1357917Y295135D01*
X1358292Y294968D01*
X1358709Y294926D01*
X1359251Y295010D01*
X1359542Y295135D01*
X1359834Y295343D01*
X1360042Y295635D01*
X1360084Y295926D01*
X1360001Y296218D01*
X1359792Y296426D01*
G01X1357584Y298735D02*
X1358126Y298818D01*
X1358584Y298943D01*
X1359001Y299110D01*
X1359459Y299318D01*
X1360084Y299651D01*
Y297985D01*
G01X1356000Y460517D02*
X1358500D01*
Y461517D01*
X1358375Y461850D01*
X1358083Y462100D01*
X1357750Y462183D01*
X1357417Y462100D01*
X1357167Y461892D01*
X1357042Y461517D01*
Y460517D01*
G01X1358292Y465367D02*
X1358417Y465117D01*
X1358500Y464825D01*
Y464492D01*
X1358375Y464117D01*
X1358167Y463825D01*
X1357917Y463617D01*
X1357500Y463450D01*
X1357125Y463408D01*
X1356750Y463492D01*
X1356500Y463617D01*
X1356250Y463867D01*
X1356083Y464158D01*
X1356000Y464450D01*
Y464742D01*
X1356083Y465033D01*
X1356208Y465283D01*
X1356375Y465492D01*
G01X1356000Y467550D02*
X1358500D01*
X1358000Y467050D01*
G01X1356000D02*
Y468050D01*
G01X1356292Y469942D02*
X1356083Y470233D01*
X1356000Y470567D01*
X1356083Y470900D01*
X1356333Y471192D01*
X1356708Y471400D01*
X1357083Y471483D01*
X1357542D01*
X1357917Y471400D01*
X1358250Y471192D01*
X1358417Y470942D01*
X1358500Y470650D01*
X1358417Y470317D01*
X1358250Y470067D01*
X1358000Y469900D01*
X1357667Y469817D01*
X1357375Y469900D01*
X1357083Y470108D01*
X1356917Y470358D01*
X1356875Y470650D01*
X1356958Y470983D01*
X1357167Y471233D01*
X1357542Y471483D01*
G01X1378300Y279000D02*
X1374300D01*
Y286400D01*
G01X1382300Y279000D02*
X1378300D01*
Y286400D01*
G01X1370300D02*
X1374300D01*
Y279000D01*
G01X1374800Y292217D02*
X1377300D01*
Y293258D01*
X1377175Y293592D01*
X1377008Y293800D01*
X1376675Y293883D01*
X1376342Y293800D01*
X1376133Y293550D01*
X1376008Y293258D01*
Y292217D01*
G01Y293258D02*
X1374800Y293883D01*
G01X1376883Y295358D02*
X1377133Y295608D01*
X1377258Y295900D01*
X1377300Y296233D01*
X1377217Y296650D01*
X1377008Y296942D01*
X1376758Y297025D01*
X1376508Y296983D01*
X1376300Y296817D01*
X1375883Y295983D01*
X1375592Y295608D01*
X1375175Y295358D01*
X1374800Y295275D01*
Y297025D01*
G01X1375092Y298542D02*
X1374883Y298833D01*
X1374800Y299167D01*
X1374883Y299500D01*
X1375133Y299792D01*
X1375508Y300000D01*
X1375883Y300083D01*
X1376342D01*
X1376717Y300000D01*
X1377050Y299792D01*
X1377217Y299542D01*
X1377300Y299250D01*
X1377217Y298917D01*
X1377050Y298667D01*
X1376800Y298500D01*
X1376467Y298417D01*
X1376175Y298500D01*
X1375883Y298708D01*
X1375717Y298958D01*
X1375675Y299250D01*
X1375758Y299583D01*
X1375967Y299833D01*
X1376342Y300083D01*
G01X1375300Y301433D02*
X1375008Y301683D01*
X1374842Y302017D01*
X1374800Y302392D01*
X1374842Y302725D01*
X1375050Y303058D01*
X1375300Y303267D01*
X1375550Y303308D01*
X1375842Y303225D01*
X1376050Y302933D01*
X1376133Y302642D01*
Y302267D01*
G01Y302642D02*
X1376258Y302892D01*
X1376467Y303100D01*
X1376717Y303183D01*
X1376967Y303100D01*
X1377175Y302892D01*
X1377300Y302517D01*
X1377258Y302142D01*
X1377092Y301767D01*
G01X1378800Y292217D02*
X1381300D01*
Y293258D01*
X1381175Y293592D01*
X1381008Y293800D01*
X1380675Y293883D01*
X1380342Y293800D01*
X1380133Y293550D01*
X1380008Y293258D01*
Y292217D01*
G01Y293258D02*
X1378800Y293883D01*
G01X1380883Y295358D02*
X1381133Y295608D01*
X1381258Y295900D01*
X1381300Y296233D01*
X1381217Y296650D01*
X1381008Y296942D01*
X1380758Y297025D01*
X1380508Y296983D01*
X1380300Y296817D01*
X1379883Y295983D01*
X1379592Y295608D01*
X1379175Y295358D01*
X1378800Y295275D01*
Y297025D01*
G01X1379092Y298542D02*
X1378883Y298833D01*
X1378800Y299167D01*
X1378883Y299500D01*
X1379133Y299792D01*
X1379508Y300000D01*
X1379883Y300083D01*
X1380342D01*
X1380717Y300000D01*
X1381050Y299792D01*
X1381217Y299542D01*
X1381300Y299250D01*
X1381217Y298917D01*
X1381050Y298667D01*
X1380800Y298500D01*
X1380467Y298417D01*
X1380175Y298500D01*
X1379883Y298708D01*
X1379717Y298958D01*
X1379675Y299250D01*
X1379758Y299583D01*
X1379967Y299833D01*
X1380342Y300083D01*
G01X1379175Y301433D02*
X1378967Y301683D01*
X1378842Y301975D01*
X1378800Y302350D01*
X1378883Y302725D01*
X1379050Y303017D01*
X1379342Y303225D01*
X1379675Y303267D01*
X1380008Y303183D01*
X1380217Y302975D01*
X1380383Y302683D01*
X1380425Y302392D01*
X1380383Y302100D01*
X1380217Y301725D01*
X1381300Y301850D01*
Y302975D01*
G01X1370800Y292217D02*
X1373300D01*
Y293258D01*
X1373175Y293592D01*
X1373008Y293800D01*
X1372675Y293883D01*
X1372342Y293800D01*
X1372133Y293550D01*
X1372008Y293258D01*
Y292217D01*
G01Y293258D02*
X1370800Y293883D01*
G01X1371300Y295233D02*
X1371008Y295483D01*
X1370842Y295817D01*
X1370800Y296192D01*
X1370842Y296525D01*
X1371050Y296858D01*
X1371300Y297067D01*
X1371550Y297108D01*
X1371842Y297025D01*
X1372050Y296733D01*
X1372133Y296442D01*
Y296067D01*
G01Y296442D02*
X1372258Y296692D01*
X1372467Y296900D01*
X1372717Y296983D01*
X1372967Y296900D01*
X1373175Y296692D01*
X1373300Y296317D01*
X1373258Y295942D01*
X1373092Y295567D01*
G01X1370800Y299750D02*
X1373300D01*
X1371508Y298208D01*
Y300292D01*
G01X1371842Y301558D02*
X1372133Y301850D01*
X1372300Y302100D01*
X1372383Y302433D01*
X1372300Y302725D01*
X1372133Y302933D01*
X1371883Y303100D01*
X1371592Y303142D01*
X1371342Y303100D01*
X1371092Y302933D01*
X1370883Y302683D01*
X1370800Y302392D01*
X1370883Y302058D01*
X1371133Y301767D01*
X1371508Y301600D01*
X1371925Y301558D01*
X1372467Y301642D01*
X1372758Y301767D01*
X1373050Y301975D01*
X1373258Y302267D01*
X1373300Y302558D01*
X1373217Y302850D01*
X1373008Y303058D01*
G01X1375792Y316267D02*
X1375917Y316017D01*
X1376000Y315725D01*
Y315392D01*
X1375875Y315017D01*
X1375667Y314725D01*
X1375417Y314517D01*
X1375000Y314350D01*
X1374625Y314308D01*
X1374250Y314392D01*
X1374000Y314517D01*
X1373750Y314767D01*
X1373583Y315058D01*
X1373500Y315350D01*
Y315642D01*
X1373583Y315933D01*
X1373708Y316183D01*
X1373875Y316392D01*
G01X1373500Y318450D02*
X1376000D01*
X1375500Y317950D01*
G01X1373500D02*
Y318950D01*
G01Y321550D02*
X1373542Y321842D01*
X1373667Y322175D01*
X1373875Y322383D01*
X1374167Y322467D01*
X1374458Y322383D01*
X1374708Y322133D01*
X1374833Y321758D01*
Y321342D01*
X1374917Y321092D01*
X1375125Y320883D01*
X1375417Y320800D01*
X1375708Y320925D01*
X1375917Y321217D01*
X1376000Y321550D01*
X1375917Y321883D01*
X1375708Y322175D01*
X1375417Y322300D01*
X1375125Y322217D01*
X1374917Y322008D01*
X1374833Y321758D01*
Y321342D01*
X1374708Y320967D01*
X1374458Y320717D01*
X1374167Y320633D01*
X1373875Y320717D01*
X1373667Y320925D01*
X1373542Y321258D01*
X1373500Y321550D01*
G01X1374542Y323858D02*
X1374833Y324150D01*
X1375000Y324400D01*
X1375083Y324733D01*
X1375000Y325025D01*
X1374833Y325233D01*
X1374583Y325400D01*
X1374292Y325442D01*
X1374042Y325400D01*
X1373792Y325233D01*
X1373583Y324983D01*
X1373500Y324692D01*
X1373583Y324358D01*
X1373833Y324067D01*
X1374208Y323900D01*
X1374625Y323858D01*
X1375167Y323942D01*
X1375458Y324067D01*
X1375750Y324275D01*
X1375958Y324567D01*
X1376000Y324858D01*
X1375917Y325150D01*
X1375708Y325358D01*
G01X1366000Y461067D02*
X1368500D01*
Y462067D01*
X1368375Y462400D01*
X1368083Y462650D01*
X1367750Y462733D01*
X1367417Y462650D01*
X1367167Y462442D01*
X1367042Y462067D01*
Y461067D01*
G01X1367250Y465250D02*
Y466083D01*
X1366500D01*
X1366250Y465833D01*
X1366083Y465542D01*
X1366000Y465125D01*
X1366083Y464708D01*
X1366250Y464417D01*
X1366500Y464167D01*
X1366792Y464000D01*
X1367125Y463917D01*
X1367417D01*
X1367667Y464000D01*
X1367958Y464167D01*
X1368208Y464417D01*
X1368375Y464667D01*
X1368500Y465000D01*
Y465292D01*
X1368417Y465625D01*
X1368250Y465875D01*
G01X1368083Y467308D02*
X1368333Y467558D01*
X1368458Y467850D01*
X1368500Y468183D01*
X1368417Y468600D01*
X1368208Y468892D01*
X1367958Y468975D01*
X1367708Y468933D01*
X1367500Y468767D01*
X1367083Y467933D01*
X1366792Y467558D01*
X1366375Y467308D01*
X1366000Y467225D01*
Y468975D01*
G01X1382300Y286400D02*
X1386300D01*
Y279000D01*
G01X1382800Y292217D02*
X1385300D01*
Y293258D01*
X1385175Y293592D01*
X1385008Y293800D01*
X1384675Y293883D01*
X1384342Y293800D01*
X1384133Y293550D01*
X1384008Y293258D01*
Y292217D01*
G01Y293258D02*
X1382800Y293883D01*
G01X1383300Y295233D02*
X1383008Y295483D01*
X1382842Y295817D01*
X1382800Y296192D01*
X1382842Y296525D01*
X1383050Y296858D01*
X1383300Y297067D01*
X1383550Y297108D01*
X1383842Y297025D01*
X1384050Y296733D01*
X1384133Y296442D01*
Y296067D01*
G01Y296442D02*
X1384258Y296692D01*
X1384467Y296900D01*
X1384717Y296983D01*
X1384967Y296900D01*
X1385175Y296692D01*
X1385300Y296317D01*
X1385258Y295942D01*
X1385092Y295567D01*
G01X1382800Y299750D02*
X1385300D01*
X1383508Y298208D01*
Y300292D01*
G01X1384883Y301558D02*
X1385133Y301808D01*
X1385258Y302100D01*
X1385300Y302433D01*
X1385217Y302850D01*
X1385008Y303142D01*
X1384758Y303225D01*
X1384508Y303183D01*
X1384300Y303017D01*
X1383883Y302183D01*
X1383592Y301808D01*
X1383175Y301558D01*
X1382800Y301475D01*
Y303225D01*
G01X1389000Y315017D02*
X1391500D01*
Y316058D01*
X1391375Y316392D01*
X1391208Y316600D01*
X1390875Y316683D01*
X1390542Y316600D01*
X1390333Y316350D01*
X1390208Y316058D01*
Y315017D01*
G01Y316058D02*
X1389000Y316683D01*
G01X1391083Y318158D02*
X1391333Y318408D01*
X1391458Y318700D01*
X1391500Y319033D01*
X1391417Y319450D01*
X1391208Y319742D01*
X1390958Y319825D01*
X1390708Y319783D01*
X1390500Y319617D01*
X1390083Y318783D01*
X1389792Y318408D01*
X1389375Y318158D01*
X1389000Y318075D01*
Y319825D01*
G01X1390042Y321258D02*
X1390333Y321550D01*
X1390500Y321800D01*
X1390583Y322133D01*
X1390500Y322425D01*
X1390333Y322633D01*
X1390083Y322800D01*
X1389792Y322842D01*
X1389542Y322800D01*
X1389292Y322633D01*
X1389083Y322383D01*
X1389000Y322092D01*
X1389083Y321758D01*
X1389333Y321467D01*
X1389708Y321300D01*
X1390125Y321258D01*
X1390667Y321342D01*
X1390958Y321467D01*
X1391250Y321675D01*
X1391458Y321967D01*
X1391500Y322258D01*
X1391417Y322550D01*
X1391208Y322758D01*
G01X1390042Y324358D02*
X1390333Y324650D01*
X1390500Y324900D01*
X1390583Y325233D01*
X1390500Y325525D01*
X1390333Y325733D01*
X1390083Y325900D01*
X1389792Y325942D01*
X1389542Y325900D01*
X1389292Y325733D01*
X1389083Y325483D01*
X1389000Y325192D01*
X1389083Y324858D01*
X1389333Y324567D01*
X1389708Y324400D01*
X1390125Y324358D01*
X1390667Y324442D01*
X1390958Y324567D01*
X1391250Y324775D01*
X1391458Y325067D01*
X1391500Y325358D01*
X1391417Y325650D01*
X1391208Y325858D01*
G01X1386500Y317300D02*
X1382500D01*
Y324700D01*
G54D15*
G01X316500Y74000D02*
X312500D01*
G01X309500Y291500D02*
X305500D01*
G01X321500Y74000D02*
X317500D01*
G01X334500Y71500D02*
X330500D01*
G01X374000Y13500D02*
X378000D01*
G01X379000D02*
X383000D01*
G01X623500Y351000D02*
X627500D01*
G01X638500D02*
X642500D01*
G01X633500D02*
X637500D01*
G01X628500D02*
X632500D01*
G01X668000Y444000D02*
Y448000D01*
G01X676000Y466800D02*
Y467900D01*
G01Y464100D02*
Y465200D01*
G01X709748Y115000D02*
Y119000D01*
G01X785000Y403500D02*
X789000D01*
G01X1033500Y66500D02*
X1029500D01*
G01X1038500D02*
X1034500D01*
G01X1043500D02*
X1039500D01*
G01X1048500D02*
X1044500D01*
G01X1053500D02*
X1049500D01*
G01X1070500Y138500D02*
Y142500D01*
G01X1126800Y807000D02*
X1122800D01*
G01X1133300D02*
X1129300D01*
G01X1141968Y693784D02*
Y697784D01*
G01X1142000Y698500D02*
Y702500D01*
G01X1149000Y705000D02*
X1153000D01*
G01X1144000Y802500D02*
X1140000D01*
G01X1196450Y696520D02*
Y700520D01*
G01X1214500Y200500D02*
X1210500D01*
G01X1206390Y706200D02*
X1202390D01*
G01X1287500Y431000D02*
Y435000D01*
G01X1342500Y392500D02*
Y396500D01*
G01X1333517Y532212D02*
Y531112D01*
G01Y524212D02*
Y523112D01*
G01Y526912D02*
Y525812D01*
G01X1339017Y532212D02*
Y531112D01*
G01X1344517D02*
Y532212D01*
G01X1339017Y524212D02*
Y523112D01*
G01Y526912D02*
Y525812D01*
G01X1344517D02*
Y526912D01*
G01Y523112D02*
Y524212D01*
G01X1333517Y534912D02*
Y533812D01*
G01X1339017Y534912D02*
Y533812D01*
G01X1344517D02*
Y534912D01*
M02*
